G04 ================== begin FILE IDENTIFICATION RECORD ==================*
G04 Layout Name:  13948-1b.brd*
G04 Film Name:    13948-1b_X_Y*
G04 File Format:  Gerber RS274X*
G04 File Origin:  Cadence Allegro 16.5-S045*
G04 Origin Date:  Thu Nov 13 15:45:42 2014*
G04 *
G04 Layer:  BOARD GEOMETRY/PANEL_DRAWING*
G04 *
G04 Offset:    (0.00 0.00)*
G04 Mirror:    No*
G04 Mode:      Positive*
G04 Rotation:  0*
G04 FullContactRelief:  No*
G04 UndefLineWidth:     6.00*
G04 ================== end FILE IDENTIFICATION RECORD ====================*
%FSLAX35Y35*MOIN*%
%IR0*IPPOS*OFA0.00000B0.00000*MIA0B0*SFA1.00000B1.00000*%
%ADD10C,.006*%
G75*
%LPD*%
G75*
G36*
G01X2095934Y1021023D02*
X2093966Y1010787D01*
X2097903D01*
X2095934Y1021023D01*
G37*
G36*
G01Y1026535D02*
X2097903Y1036771D01*
X2093966D01*
X2095934Y1026535D01*
G37*
G36*
G01X2139304Y1038278D02*
X2129068Y1040246D01*
Y1036309D01*
X2139304Y1038278D01*
G37*
G36*
G01X2122069Y1056576D02*
X2130342Y1062919D01*
X2120307Y1060097D01*
X2122069Y1056576D01*
G37*
G36*
G01X2145603Y1038278D02*
X2155840Y1036309D01*
Y1040246D01*
X2145603Y1038278D01*
G37*
G36*
G01X2155998Y1066395D02*
X2145603Y1065612D01*
X2155547Y1062484D01*
X2155998Y1066395D01*
G37*
G36*
G01X2527115Y1070807D02*
X2535011Y1064002D01*
X2536971Y1067416D01*
X2527115Y1070807D01*
G37*
G36*
G01X2593625Y-952770D02*
X2603857Y-950781D01*
X2602390Y-947128D01*
X2593625Y-952770D01*
G37*
G36*
G01X2591762Y-947504D02*
X2599063Y-940065D01*
X2595783Y-937887D01*
X2591762Y-947504D01*
G37*
G36*
G01X2589848Y-952275D02*
X2598561Y-946552D01*
X2595816Y-943729D01*
X2589848Y-952275D01*
G37*
G36*
G01X2586738Y-918324D02*
X2595875Y-913306D01*
X2593362Y-910276D01*
X2586738Y-918324D01*
G37*
G36*
G01X2627687Y495902D02*
X2635003Y503326D01*
X2631727Y505510D01*
X2627687Y495902D01*
G37*
G36*
G01X2762144Y-1205714D02*
X2768207Y-1214192D01*
X2770920Y-1211339D01*
X2762144Y-1205714D01*
G37*
G36*
G01X2772038Y-1207611D02*
X2780659Y-1213472D01*
X2782218Y-1209857D01*
X2772038Y-1207611D01*
G37*
G36*
G01X2762875Y-1134972D02*
X2772548Y-1131088D01*
X2770417Y-1127777D01*
X2762875Y-1134972D01*
G37*
G36*
G01X2765747Y-1124918D02*
X2772740Y-1117188D01*
X2769374Y-1115146D01*
X2765747Y-1124918D01*
G37*
G36*
G01X2768397Y214434D02*
X2762193Y222810D01*
X2759529Y219912D01*
X2768397Y214434D01*
G37*
G36*
G01X2825383Y-880918D02*
X2835059Y-877042D01*
X2832931Y-873729D01*
X2825383Y-880918D01*
G37*
G36*
G01X2828831Y-874423D02*
X2837158Y-868153D01*
X2834238Y-865512D01*
X2828831Y-874423D01*
G37*
G36*
G01X2847831Y-1191935D02*
X2856160Y-1185666D01*
X2853241Y-1183025D01*
X2847831Y-1191935D01*
G37*
G36*
G01X2849374Y-1184720D02*
X2855714Y-1176446D01*
X2852194Y-1174685D01*
X2849374Y-1184720D01*
G37*
G36*
G01X2943644Y-1048056D02*
X2946286Y-1058139D01*
X2949837Y-1056440D01*
X2943644Y-1048056D01*
G37*
G36*
G01X2942181Y-1040856D02*
X2947349Y-1049909D01*
X2950338Y-1047346D01*
X2942181Y-1040856D01*
G37*
G36*
G01X2946407Y131545D02*
X2953157Y139487D01*
X2949730Y141424D01*
X2946407Y131545D01*
G37*
G36*
G01X2983942Y-1210504D02*
X2993837Y-1207226D01*
X2991916Y-1203790D01*
X2983942Y-1210504D01*
G37*
G36*
G01X2983792Y-1035052D02*
X2993522Y-1031312D01*
X2991440Y-1027970D01*
X2983792Y-1035052D01*
G37*
G36*
G01X2985783Y-1024448D02*
X2992295Y-1016309D01*
X2988811Y-1014474D01*
X2985783Y-1024448D01*
G37*
G36*
G01X2989303Y-1202173D02*
X2997787Y-1196117D01*
X2994936Y-1193402D01*
X2989303Y-1202173D01*
G37*
G36*
G01X3038279Y187905D02*
X3045837Y195083D01*
X3042635Y197374D01*
X3038279Y187905D01*
G37*
G36*
G01Y345021D02*
X3046511Y338626D01*
X3048296Y342135D01*
X3038279Y345021D01*
G37*
G36*
G01X3069186Y-965543D02*
X3074766Y-974348D01*
X3077634Y-971650D01*
X3069186Y-965543D01*
G37*
G36*
G01X3065468Y-959342D02*
X3072878Y-966673D01*
X3075068Y-963402D01*
X3065468Y-959342D01*
G37*
G36*
G01X3236751Y-936637D02*
X3246487Y-932915D01*
X3244413Y-929569D01*
X3236751Y-936637D01*
G37*
G36*
G01X3239957Y-926738D02*
X3247174Y-919216D01*
X3243869Y-917076D01*
X3239957Y-926738D01*
G37*
G36*
G01X3237017Y-880024D02*
X3247038Y-877155D01*
X3245259Y-873643D01*
X3237017Y-880024D01*
G37*
G36*
G01X3238420Y-868774D02*
X3244746Y-860490D01*
X3241222Y-858734D01*
X3238420Y-868774D01*
G37*
G36*
G01X3294972Y471438D02*
X3298450Y481265D01*
X3294557Y481854D01*
X3294972Y471438D01*
G37*
G36*
G01X3425448Y-888381D02*
X3423480Y-898618D01*
X3427417D01*
X3425448Y-888381D01*
G37*
G36*
G01Y-875783D02*
X3427417Y-865547D01*
X3423480D01*
X3425448Y-875783D01*
G37*
G36*
G01X3437197Y1077634D02*
X3430057Y1070039D01*
X3433383Y1067933D01*
X3437197Y1077634D01*
G37*
G36*
G01X3486318Y-854806D02*
X3476082Y-852838D01*
Y-856775D01*
X3486318Y-854806D01*
G37*
G36*
G01X3495848Y-888381D02*
X3490676Y-897431D01*
X3494401Y-898705D01*
X3495848Y-888381D01*
G37*
G36*
G01X3506013Y-1035549D02*
X3513730Y-1028542D01*
X3510581Y-1026179D01*
X3506013Y-1035549D01*
G37*
G36*
G01X3505216Y-854806D02*
X3515452Y-856775D01*
Y-852838D01*
X3505216Y-854806D01*
G37*
G36*
G01X3519883Y1075713D02*
X3525214Y1066756D01*
X3528156Y1069372D01*
X3519883Y1075713D01*
G37*
G36*
G01X3546645Y514080D02*
X3556089Y518492D01*
X3553779Y521680D01*
X3546645Y514080D01*
G37*
G36*
G01X3782733Y-1193692D02*
X3777840Y-1184487D01*
X3774776Y-1186959D01*
X3782733Y-1193692D01*
G37*
G36*
G01X3782488Y-1018697D02*
X3777411Y-1009593D01*
X3774396Y-1012126D01*
X3782488Y-1018697D01*
G37*
G36*
G01X3789139Y-1200700D02*
X3785128Y-1191078D01*
X3781846Y-1193252D01*
X3789139Y-1200700D01*
G37*
G36*
G01X3790255Y-1024915D02*
X3788240Y-1014688D01*
X3784590Y-1016165D01*
X3790255Y-1024915D01*
G37*
G36*
G01X3850866Y-1069027D02*
X3843018Y-1062168D01*
X3841033Y-1065568D01*
X3850866Y-1069027D01*
G37*
G36*
G01X3859104Y-1142953D02*
X3851419Y-1135911D01*
X3849355Y-1139263D01*
X3859104Y-1142953D01*
G37*
G36*
G01X3853841Y-1134634D02*
X3848386Y-1125752D01*
X3845480Y-1128408D01*
X3853841Y-1134634D01*
G37*
G36*
G01X3858748Y-1079602D02*
X3848628Y-1082101D01*
X3850276Y-1085676D01*
X3858748Y-1079602D01*
G37*
G36*
G01X3854421Y183721D02*
X3864726Y185291D01*
X3863408Y189002D01*
X3854421Y183721D01*
G37*
G36*
G01Y357181D02*
X3864766Y358463D01*
X3863552Y362208D01*
X3854421Y357181D01*
G37*
G36*
G01X3924500Y318202D02*
X3934852Y319422D01*
X3933661Y323174D01*
X3924500Y318202D01*
G37*
G36*
G01X3921849Y1070869D02*
X3912005Y1067443D01*
X3913978Y1064036D01*
X3921849Y1070869D01*
G37*
G54D10*
G01X-426669Y-1856796D02*
X4254433D01*
G01X-426669D02*
Y1454227D01*
G01Y-1605749D02*
X-407657D01*
G01X-426669Y-1389010D02*
X-407657D01*
G01X-426669Y-1172271D02*
X-407657D01*
G01X-426669Y-955533D02*
X-407657D01*
G01X-426669Y-738794D02*
X-407657D01*
G01X-426669Y-522056D02*
X-407657D01*
G01X-426669Y-305317D02*
X-407657D01*
G01X-426669Y-88578D02*
X-407657D01*
G01X-426669Y128160D02*
X-407657D01*
G01X-426669Y344899D02*
X-407657D01*
G01X-426669Y561638D02*
X-407657D01*
G01X-426669Y778376D02*
X-407657D01*
G01X-426669Y995115D02*
X-407657D01*
G01X-426669Y1211853D02*
X-407657D01*
G01X-426669Y1454227D02*
X4254433D01*
G01X-426669Y1453929D02*
X4254433D01*
G01X-416687Y-1719822D02*
X-417828Y-1719632D01*
X-418826Y-1718872D01*
X-419682Y-1717731D01*
X-420252Y-1716400D01*
X-420537Y-1714879D01*
Y-1713358D01*
X-420252Y-1711837D01*
X-419682Y-1710506D01*
X-418826Y-1709366D01*
X-417828Y-1708605D01*
X-416687Y-1708415D01*
X-415546Y-1708605D01*
X-414548Y-1709366D01*
X-413692Y-1710506D01*
X-413122Y-1711837D01*
X-412837Y-1713358D01*
Y-1714879D01*
X-413122Y-1716400D01*
X-413692Y-1717731D01*
X-414548Y-1718872D01*
X-415546Y-1719632D01*
X-416687Y-1719822D01*
G01X-419967Y-1503083D02*
Y-1491676D01*
X-413407Y-1503083D01*
Y-1491676D01*
G01X-420395Y-1286345D02*
Y-1274938D01*
X-416687Y-1284444D01*
X-412979Y-1274938D01*
Y-1286345D01*
G01X-419539Y-1058389D02*
Y-1069796D01*
X-413835D01*
G01X-419824Y-853057D02*
Y-841650D01*
G01X-414405D02*
X-419824Y-848685D01*
G01X-413550Y-853057D02*
X-417400Y-845453D01*
G01X-419539Y-633847D02*
X-418826Y-634988D01*
X-417971Y-635748D01*
X-416972Y-636128D01*
X-415831Y-635748D01*
X-414976Y-634988D01*
X-414120Y-633847D01*
X-413835Y-632326D01*
Y-624721D01*
G01X-418398Y-407983D02*
X-414976D01*
G01X-416687D02*
Y-419390D01*
G01X-418398D02*
X-414976D01*
G01X-419682Y-202841D02*
Y-191434D01*
G01X-413692D02*
Y-202841D01*
G01Y-197138D02*
X-419682D01*
G01X-415831Y19600D02*
X-412979D01*
Y16178D01*
X-413835Y15037D01*
X-414833Y14277D01*
X-416259Y13897D01*
X-417685Y14277D01*
X-418683Y15037D01*
X-419539Y16178D01*
X-420110Y17509D01*
X-420395Y19030D01*
Y20361D01*
X-420110Y21501D01*
X-419539Y22833D01*
X-418683Y23973D01*
X-417828Y24733D01*
X-416687Y25304D01*
X-415689D01*
X-414548Y24924D01*
X-413692Y24163D01*
G01X-419777Y230826D02*
Y242233D01*
X-414359D01*
G01X-416355Y236720D02*
X-419777D01*
G01X-413835Y447755D02*
X-419539D01*
Y459162D01*
X-413835D01*
G01X-416117Y453649D02*
X-419539D01*
G01X-419824Y664303D02*
Y675710D01*
X-416972D01*
X-415831Y675139D01*
X-414976Y674379D01*
X-414263Y673239D01*
X-413692Y671907D01*
X-413550Y670006D01*
X-413692Y668105D01*
X-414263Y666774D01*
X-414976Y665634D01*
X-415831Y664873D01*
X-416972Y664303D01*
X-419824D01*
G01X-413550Y891688D02*
X-414405Y892259D01*
X-415403Y892639D01*
X-416544D01*
X-417828Y892068D01*
X-418826Y891118D01*
X-419539Y889977D01*
X-420110Y888076D01*
X-420252Y886365D01*
X-419967Y884654D01*
X-419539Y883513D01*
X-418683Y882372D01*
X-417685Y881612D01*
X-416687Y881232D01*
X-415689D01*
X-414691Y881612D01*
X-413835Y882182D01*
X-413122Y882943D01*
G01X-415546Y1103865D02*
X-414976Y1104435D01*
X-414548Y1105385D01*
X-414263Y1106717D01*
X-414548Y1107857D01*
X-415118Y1108617D01*
X-416117Y1109188D01*
X-419967D01*
Y1097781D01*
X-415261D01*
X-414263Y1098541D01*
X-413692Y1099682D01*
X-413407Y1101013D01*
X-413692Y1102344D01*
X-414548Y1103484D01*
X-415546Y1103865D01*
X-419967D01*
G01X-420252Y1314519D02*
X-416687Y1325926D01*
X-413122Y1314519D01*
G01X-414405Y1318511D02*
X-418969D01*
G01X4235421Y-1837784D02*
X-407657D01*
G01D02*
Y1434916D01*
G01D02*
X4235421D01*
G01X-288120Y-1852994D02*
Y-1841587D01*
X-289831Y-1843868D01*
G01Y-1852994D02*
X-286409D01*
G01X-288120Y1438719D02*
Y1450126D01*
X-289831Y1447845D01*
G01Y1438719D02*
X-286409D01*
G01X-77391Y1026339D02*
X-76792Y1027138D01*
X-76093Y1027537D01*
X-75295Y1027670D01*
X-74297Y1027404D01*
X-73598Y1026738D01*
X-73398Y1025940D01*
X-73498Y1025141D01*
X-73898Y1024476D01*
X-75894Y1023145D01*
X-76792Y1022214D01*
X-77391Y1020882D01*
X-77591Y1019685D01*
X-73398D01*
G01X-69406Y1023012D02*
X-68707Y1023944D01*
X-68108Y1024476D01*
X-67310Y1024742D01*
X-66611Y1024476D01*
X-66112Y1023944D01*
X-65713Y1023145D01*
X-65613Y1022214D01*
X-65713Y1021415D01*
X-66112Y1020616D01*
X-66711Y1019951D01*
X-67410Y1019685D01*
X-68208Y1019951D01*
X-68907Y1020749D01*
X-69306Y1021947D01*
X-69406Y1023278D01*
X-69206Y1025008D01*
X-68907Y1025940D01*
X-68408Y1026871D01*
X-67709Y1027537D01*
X-67010Y1027670D01*
X-66312Y1027404D01*
X-65813Y1026738D01*
G01X-61421Y1023012D02*
X-60722Y1023944D01*
X-60123Y1024476D01*
X-59325Y1024742D01*
X-58626Y1024476D01*
X-58127Y1023944D01*
X-57728Y1023145D01*
X-57628Y1022214D01*
X-57728Y1021415D01*
X-58127Y1020616D01*
X-58726Y1019951D01*
X-59425Y1019685D01*
X-60223Y1019951D01*
X-60922Y1020749D01*
X-61321Y1021947D01*
X-61421Y1023278D01*
X-61221Y1025008D01*
X-60922Y1025940D01*
X-60423Y1026871D01*
X-59724Y1027537D01*
X-59025Y1027670D01*
X-58327Y1027404D01*
X-57828Y1026738D01*
G01X-51540Y1019419D02*
X-51739Y1019552D01*
Y1019818D01*
X-51540Y1019951D01*
X-51340Y1019818D01*
Y1019552D01*
X-51540Y1019419D01*
G01X-45750Y1020882D02*
X-45152Y1020217D01*
X-44453Y1019818D01*
X-43555Y1019685D01*
X-42656Y1019951D01*
X-41958Y1020483D01*
X-41458Y1021415D01*
X-41359Y1022480D01*
X-41558Y1023544D01*
X-42057Y1024210D01*
X-42756Y1024742D01*
X-43455Y1024875D01*
X-44153Y1024742D01*
X-45052Y1024210D01*
X-44752Y1027670D01*
X-42057D01*
G01X-35570D02*
X-36368Y1027404D01*
X-36967Y1026738D01*
X-37366Y1025940D01*
X-37666Y1024875D01*
X-37765Y1023677D01*
X-37666Y1022480D01*
X-37366Y1021415D01*
X-36967Y1020616D01*
X-36368Y1019951D01*
X-35570Y1019685D01*
X-34771Y1019951D01*
X-34172Y1020616D01*
X-33773Y1021415D01*
X-33473Y1022480D01*
X-33374Y1023677D01*
X-33473Y1024875D01*
X-33773Y1025940D01*
X-34172Y1026738D01*
X-34771Y1027404D01*
X-35570Y1027670D01*
G01X-59945Y-21543D02*
X-60743Y-21809D01*
X-61342Y-22475D01*
X-61741Y-23273D01*
X-62041Y-24338D01*
X-62140Y-25536D01*
X-62041Y-26733D01*
X-61741Y-27798D01*
X-61342Y-28597D01*
X-60743Y-29262D01*
X-59945Y-29528D01*
X-59146Y-29262D01*
X-58547Y-28597D01*
X-58148Y-27798D01*
X-57848Y-26733D01*
X-57749Y-25536D01*
X-57848Y-24338D01*
X-58148Y-23273D01*
X-58547Y-22475D01*
X-59146Y-21809D01*
X-59945Y-21543D01*
G01X-51960Y-29794D02*
X-52159Y-29661D01*
Y-29395D01*
X-51960Y-29262D01*
X-51760Y-29395D01*
Y-29661D01*
X-51960Y-29794D01*
G01X-43975Y-21543D02*
X-44773Y-21809D01*
X-45372Y-22475D01*
X-45771Y-23273D01*
X-46071Y-24338D01*
X-46170Y-25536D01*
X-46071Y-26733D01*
X-45771Y-27798D01*
X-45372Y-28597D01*
X-44773Y-29262D01*
X-43975Y-29528D01*
X-43176Y-29262D01*
X-42577Y-28597D01*
X-42178Y-27798D01*
X-41878Y-26733D01*
X-41779Y-25536D01*
X-41878Y-24338D01*
X-42178Y-23273D01*
X-42577Y-22475D01*
X-43176Y-21809D01*
X-43975Y-21543D01*
G01X-35990D02*
X-36788Y-21809D01*
X-37387Y-22475D01*
X-37786Y-23273D01*
X-38086Y-24338D01*
X-38185Y-25536D01*
X-38086Y-26733D01*
X-37786Y-27798D01*
X-37387Y-28597D01*
X-36788Y-29262D01*
X-35990Y-29528D01*
X-35191Y-29262D01*
X-34592Y-28597D01*
X-34193Y-27798D01*
X-33893Y-26733D01*
X-33794Y-25536D01*
X-33893Y-24338D01*
X-34193Y-23273D01*
X-34592Y-22475D01*
X-35191Y-21809D01*
X-35990Y-21543D01*
G01X-50417Y295315D02*
X-49718Y295448D01*
X-48919Y295847D01*
X-48420Y296512D01*
X-48221Y297444D01*
X-48420Y298376D01*
X-49019Y299174D01*
X-49917Y299574D01*
X-50916D01*
X-51515Y299840D01*
X-52014Y300505D01*
X-52213Y301437D01*
X-51914Y302368D01*
X-51215Y303034D01*
X-50417Y303300D01*
X-49618Y303034D01*
X-48919Y302368D01*
X-48620Y301437D01*
X-48820Y300505D01*
X-49318Y299840D01*
X-49917Y299574D01*
X-50916D01*
X-51814Y299174D01*
X-52413Y298376D01*
X-52612Y297444D01*
X-52413Y296512D01*
X-51914Y295847D01*
X-51115Y295448D01*
X-50417Y295315D01*
G01X-44328Y301969D02*
X-43729Y302768D01*
X-43030Y303167D01*
X-42232Y303300D01*
X-41234Y303034D01*
X-40535Y302368D01*
X-40335Y301570D01*
X-40435Y300771D01*
X-40835Y300106D01*
X-42831Y298775D01*
X-43729Y297844D01*
X-44328Y296512D01*
X-44528Y295315D01*
X-40335D01*
G01X-34447Y295049D02*
X-34646Y295182D01*
Y295448D01*
X-34447Y295581D01*
X-34247Y295448D01*
Y295182D01*
X-34447Y295049D01*
G01X-28657Y296512D02*
X-28059Y295847D01*
X-27360Y295448D01*
X-26462Y295315D01*
X-25563Y295581D01*
X-24865Y296113D01*
X-24365Y297045D01*
X-24266Y298110D01*
X-24465Y299174D01*
X-24964Y299840D01*
X-25663Y300372D01*
X-26362Y300505D01*
X-27060Y300372D01*
X-27959Y299840D01*
X-27659Y303300D01*
X-24964D01*
G01X-18477Y295315D02*
Y303300D01*
X-19674Y301703D01*
G01Y295315D02*
X-17279D01*
G01X-51410Y309494D02*
X-50711Y309627D01*
X-49912Y310026D01*
X-49413Y310691D01*
X-49214Y311623D01*
X-49413Y312555D01*
X-50012Y313353D01*
X-50910Y313753D01*
X-51909D01*
X-52508Y314019D01*
X-53007Y314684D01*
X-53206Y315616D01*
X-52907Y316547D01*
X-52208Y317213D01*
X-51410Y317479D01*
X-50611Y317213D01*
X-49912Y316547D01*
X-49613Y315616D01*
X-49813Y314684D01*
X-50311Y314019D01*
X-50910Y313753D01*
X-51909D01*
X-52807Y313353D01*
X-53406Y312555D01*
X-53605Y311623D01*
X-53406Y310691D01*
X-52907Y310026D01*
X-52108Y309627D01*
X-51410Y309494D01*
G01X-42227D02*
Y317479D01*
X-45920Y311756D01*
X-40929D01*
G01X-35440Y309228D02*
X-35639Y309361D01*
Y309627D01*
X-35440Y309760D01*
X-35240Y309627D01*
Y309361D01*
X-35440Y309228D01*
G01X-29650Y310691D02*
X-29052Y310026D01*
X-28353Y309627D01*
X-27455Y309494D01*
X-26556Y309760D01*
X-25858Y310292D01*
X-25358Y311224D01*
X-25259Y312289D01*
X-25458Y313353D01*
X-25957Y314019D01*
X-26656Y314551D01*
X-27355Y314684D01*
X-28053Y314551D01*
X-28952Y314019D01*
X-28652Y317479D01*
X-25957D01*
G01X-19470Y309494D02*
Y317479D01*
X-20667Y315882D01*
G01Y309494D02*
X-18272D01*
G01X-14084Y-25591D02*
X-42899D01*
G01X14755Y1023622D02*
X-40076D01*
G01X-245Y299252D02*
X-24185D01*
G01X-23761Y313431D02*
X-25178D01*
G01X-22343Y307126D02*
X-23761Y313431D01*
G01X11565Y307126D02*
X-22343D01*
G01X1Y-17717D02*
Y-29817D01*
G01Y-17717D02*
G03X7875Y-25591I7874J0D01*
G01X1Y299252D02*
Y-10394D01*
G01Y-17717D02*
G03X7875Y-25591I7874J0D01*
G01X1Y299252D02*
Y-10394D01*
G01Y-17717D02*
Y-10394D01*
G01X7875Y-25591D02*
X-13838D01*
G01X1Y-10394D02*
Y-17723D01*
G01X0Y11811D02*
Y0D01*
G01X92520Y299252D02*
X1D01*
G01X92520D02*
X1D01*
G01X0Y318937D02*
G03X11811Y307126I11811J0D01*
G01X0Y968503D02*
Y318937D01*
G01D02*
G03X11811Y307126I11811J0D01*
G01X0Y968503D02*
Y318937D01*
G01Y429133D02*
X884646D01*
G01X19685Y988189D02*
G03X0Y968503I0J-19685D01*
G01X19685Y988189D02*
G03X0Y968503I0J-19685D01*
G01X43950Y996063D02*
X1D01*
G01X43950D02*
X1D01*
G01Y1008622D02*
Y996063D01*
G01Y1008622D02*
Y996063D01*
G01X15001Y1023622D02*
G03X1Y1008622I0J-15000D01*
G01X15001Y1023622D02*
G03X1Y1008622I0J-15000D01*
G01X7875Y-25591D02*
X45337D01*
G01X7875D02*
X45337D01*
G01X104233Y302007D02*
X13878D01*
G01X17422Y305944D02*
Y302007D01*
G01X13878Y427086D02*
Y302007D01*
G01X11811Y307126D02*
X100394D01*
G01X22048Y309055D02*
X17107D01*
G01X100394Y307126D02*
X11811D01*
G01X13878Y305944D02*
X22049D01*
G01X17107Y423149D02*
Y309055D01*
G01X23229Y337795D02*
G03I-3937J0D01*
G01X24213D02*
G03I-4921J0D01*
G01X27166D02*
G03I-7874J0D01*
G01X18248Y329921D02*
X13878D01*
G01X18248Y345669D02*
X13878D01*
G01X23229Y396850D02*
G03I-3937J0D01*
G01X24213D02*
G03I-4921J0D01*
G01X27166D02*
G03I-7874J0D01*
G01X18248Y388976D02*
X13878D01*
G01X18248Y404724D02*
X13878D01*
G01Y427086D02*
X104233D01*
G01X25177Y423149D02*
X17107D01*
G01X15748Y987791D02*
Y429133D01*
G01X8815Y663490D02*
X9485D01*
G01X6805D02*
X7475D01*
G01X9485Y660866D02*
X8815D01*
G01X7475D02*
X6805D01*
G01X4292Y659553D02*
X12166D01*
G01X7475Y658569D02*
X4292D01*
G01X12166D02*
X8480D01*
G01Y653976D02*
X12166D01*
G01X4292D02*
X7475D01*
G01X12166Y652992D02*
X4292D01*
G01X12166Y653976D02*
Y652992D01*
G01Y659553D02*
Y658569D01*
G01X9485Y663490D02*
Y660866D01*
G01X8815D02*
Y663490D01*
G01X8480Y658569D02*
Y653976D01*
G01X7475D02*
Y658569D01*
G01Y663490D02*
Y660866D01*
G01X6805D02*
Y663490D01*
G01X4292Y658569D02*
Y659553D01*
G01Y652992D02*
Y653976D01*
G01X7642Y669888D02*
X6637Y669724D01*
G01X8815Y665623D02*
X9820Y665787D01*
G01X7475Y670708D02*
X6637Y670544D01*
G01X8983Y664803D02*
X9820Y664967D01*
G01X6805Y680223D02*
X7307D01*
G01X7977D02*
X12166D01*
G01Y679402D02*
X6805D01*
G01X8145Y678090D02*
X12166D01*
G01Y677270D02*
X8145D01*
G01Y675465D02*
X12166D01*
G01Y674645D02*
X8145D01*
G01X6805Y672841D02*
X7307D01*
G01X7977D02*
X12166D01*
G01Y672020D02*
X6805D01*
G01X8983Y670708D02*
X7475D01*
G01X8815Y669888D02*
X7642D01*
G01Y665623D02*
X8815D01*
G01X7475Y664803D02*
X8983D01*
G01X9820Y670544D02*
X8983Y670708D01*
G01X6637Y664967D02*
X7475Y664803D01*
G01X9820Y669724D02*
X8815Y669888D01*
G01X6637Y665787D02*
X7642Y665623D01*
G01X10323Y670380D02*
X9820Y670544D01*
G01X6135Y665131D02*
X6637Y664967D01*
G01X7810Y675629D02*
X8145Y675465D01*
G01X10993Y670052D02*
X10323Y670380D01*
G01X5464Y665459D02*
X6135Y665131D01*
G01X10825Y669068D02*
X9820Y669724D01*
G01X5632Y666443D02*
X6637Y665787D01*
G01X7642Y680551D02*
X7977Y680223D01*
G01X7307D02*
X6972Y680551D01*
G01X7642Y675794D02*
X7810Y675629D01*
G01X7475Y675302D02*
X6972Y675794D01*
G01X11496Y669560D02*
X10993Y670052D01*
G01X7642Y673169D02*
X7977Y672841D01*
G01X7307D02*
X6972Y673169D01*
G01X4962Y665951D02*
X5464Y665459D01*
G01X11998Y668740D02*
X11496Y669560D01*
G01X4459Y666771D02*
X4962Y665951D01*
G01X11161Y668576D02*
X10825Y669068D01*
G01X5297Y666935D02*
X5632Y666443D01*
G01X9820Y664967D02*
X10323Y665131D01*
G01X6637Y670544D02*
X6135Y670380D01*
G01X7475Y676122D02*
X7642Y675794D01*
G01X7307Y677762D02*
X8145Y678090D01*
G01X10323Y665131D02*
X10993Y665459D01*
G01X6135Y670380D02*
X5464Y670052D01*
G01X8145Y674645D02*
X7810Y674481D01*
G01X8145Y677270D02*
X7810Y677106D01*
G01X6972Y675794D02*
X6805Y676286D01*
G01X7475Y673661D02*
X7642Y673169D01*
G01X6972D02*
X6805Y673661D01*
G01X9820Y665787D02*
X10825Y666443D01*
G01X6637Y669724D02*
X5632Y669068D01*
G01X12166Y667755D02*
X11998Y668740D01*
G01X4292Y667755D02*
X4459Y666771D01*
G01X11328Y667755D02*
X11161Y668576D01*
G01X5129Y667755D02*
X5297Y666935D01*
G01X10993Y665459D02*
X11496Y665951D01*
G01X5464Y670052D02*
X4962Y669560D01*
G01X7810Y674481D02*
X7642Y674317D01*
G01X6972Y674809D02*
X7475Y675302D01*
G01X7810Y677106D02*
X7642Y676942D01*
G01X6972Y677434D02*
X7307Y677762D01*
G01X10825Y666443D02*
X11161Y666935D01*
G01X5632Y669068D02*
X5297Y668576D01*
G01X11496Y665951D02*
X11998Y666771D01*
G01X4962Y669560D02*
X4459Y668740D01*
G01X7642Y674317D02*
X7475Y673989D01*
G01X7642Y676942D02*
X7475Y676614D01*
G01X11161Y666935D02*
X11328Y667755D01*
G01X5297Y668576D02*
X5129Y667755D01*
G01X11998Y666771D02*
X12166Y667755D01*
G01X4459Y668740D02*
X4292Y667755D01*
G01X12166Y672841D02*
Y672020D01*
G01Y678090D02*
Y677270D01*
G01Y675465D02*
Y674645D01*
G01Y680223D02*
Y679402D01*
G01X7475Y673989D02*
Y673661D01*
G01Y676614D02*
Y676122D01*
G01X6805Y679402D02*
Y680223D01*
G01Y673661D02*
Y674317D01*
G01Y676286D02*
Y676942D01*
G01Y672020D02*
Y672841D01*
G01Y674317D02*
X6972Y674809D01*
G01X6805Y676942D02*
X6972Y677434D01*
G01X8145Y685472D02*
X12166D01*
G01Y684652D02*
X8145D01*
G01Y682847D02*
X12166D01*
G01Y682027D02*
X8145D01*
G01X7810Y683011D02*
X8145Y682847D01*
G01X7642Y683176D02*
X7810Y683011D01*
G01X7475Y682683D02*
X6972Y683176D01*
G01X7475Y683503D02*
X7642Y683176D01*
G01X7307Y685144D02*
X8145Y685472D01*
G01Y682027D02*
X7810Y681863D01*
G01X8145Y684652D02*
X7810Y684488D01*
G01X6972Y683176D02*
X6805Y683668D01*
G01X7475Y681043D02*
X7642Y680551D01*
G01X6972D02*
X6805Y681043D01*
G01X7810Y681863D02*
X7642Y681699D01*
G01X6972Y682191D02*
X7475Y682683D01*
G01X7810Y684488D02*
X7642Y684324D01*
G01X6972Y684816D02*
X7307Y685144D01*
G01X12166Y682847D02*
Y682027D01*
G01Y685472D02*
Y684652D01*
G01X7475Y681371D02*
Y681043D01*
G01Y683996D02*
Y683503D01*
G01X6805Y683668D02*
Y684324D01*
G01Y681043D02*
Y681699D01*
G01X7642D02*
X7475Y681371D01*
G01X7642Y684324D02*
X7475Y683996D01*
G01X6805Y681699D02*
X6972Y682191D01*
G01X6805Y684324D02*
X6972Y684816D01*
G01X19685Y988189D02*
G03X15748Y987791I1J-19685D01*
G01X10710Y1008622D02*
G03X19292I4291J0D01*
G01D02*
G03X10710I-4291J0D01*
G01X99804Y1023622D02*
X15001D01*
G01X99804D02*
X15001D01*
G01X25709Y278385D02*
G03X27284Y279960I0J1575D01*
G01D02*
X24134D01*
G01X25709Y278385D02*
X24134D01*
G01X96929Y275629D02*
X21181D01*
G01X95748Y274448D02*
X22363D01*
G01X21181Y275629D02*
X22363Y274448D01*
G01X27284Y312992D02*
Y279960D01*
G01X26103Y312992D02*
Y274448D01*
G01X24134Y312992D02*
Y274448D01*
G01X21181Y302007D02*
Y275629D01*
G01X22264Y302007D02*
Y305944D01*
G01X93977Y312992D02*
X24134D01*
G01X96063Y307913D02*
X22048D01*
G01X96063Y306929D02*
X22048D01*
G01X22264Y305944D02*
X95847D01*
G01X22049D02*
X22264D01*
G01X22048Y309055D02*
Y305944D01*
G01X21772Y427086D02*
Y305944D01*
G01X21083Y309055D02*
Y423149D01*
G01X20276Y305944D02*
Y427086D01*
G01X19488D02*
Y305944D01*
G01X19114Y423149D02*
Y309055D01*
G01X18307Y427086D02*
Y305944D01*
G01X18248D02*
Y329921D01*
G01X18091Y423149D02*
Y309055D01*
G01X93977Y323622D02*
X24134D01*
G01Y418779D02*
Y323622D01*
G01X18248Y345669D02*
Y388976D01*
G01X32677Y366955D02*
X37939D01*
G01Y365577D02*
X32677D01*
G01X85433Y361797D02*
X32677D01*
G01X35827Y365297D02*
X33227Y361797D01*
G01X32677Y407091D02*
Y361797D01*
G01X23111Y373228D02*
G03I-1890J0D01*
G01X37296Y374333D02*
G03Y372123I-1862J-1105D01*
G01X32784Y372470D02*
G03X37296Y371196I2650J758D01*
G01Y375259D02*
G03X32784Y373986I-1863J-2031D01*
G01X24095Y373228D02*
G03I-2874J0D01*
G01X24272D02*
G03I-3051J0D01*
G01X37939Y377092D02*
X32677D01*
G01X37939Y376913D02*
X32677D01*
G01X32784Y372470D02*
Y373986D01*
G01X32677Y400799D02*
X35630D01*
G01Y400405D02*
X32677D01*
G01Y400012D02*
X35630D01*
G01X32677Y399224D02*
X85433D01*
G01Y393182D02*
X32677D01*
G01X85433Y390872D02*
X32677D01*
G01X93977Y414842D02*
X24134D01*
G01X35630Y407091D02*
X32677D01*
G01X18248Y427086D02*
Y404724D01*
G01X25177Y432440D02*
X92933D01*
G01Y432006D02*
X25177D01*
G01Y431456D02*
X92933D01*
G01X25177Y431114D02*
X92933D01*
G01X25177Y429179D02*
X92933D01*
G01X25177Y428806D02*
X92933D01*
G01Y428589D02*
X25177D01*
G01Y428464D02*
X92933D01*
G01Y428229D02*
X25177D01*
G01X92933Y427914D02*
X25177D01*
G01X92933Y427805D02*
X25177D01*
G01Y427638D02*
X92933D01*
G01X25177Y427480D02*
X92933D01*
G01X24134Y418779D02*
X41142D01*
G01X25177Y432440D02*
Y423149D01*
G01X103740Y988189D02*
X19685D01*
G01X884646D02*
X19685D01*
G01X103740D02*
X19685D01*
G01X49274Y-25591D02*
Y-25985D01*
G01X53211Y-25591D02*
G03X45337I-3937J0D01*
G01X53211D02*
G03X45337I-3937J0D01*
G01X48782D02*
X49766D01*
G01X49274D02*
Y-25197D01*
G01X53211Y-25591D02*
G03X45337I-3937J0D01*
G01X53211D02*
G03X45337I-3937J0D01*
G01X44882Y286259D02*
X38977D01*
G01Y278385D02*
X44882D01*
G01Y286259D02*
Y278385D01*
G01X38977Y286259D02*
Y278385D01*
G01X82663Y364787D02*
X35448D01*
G01X37939Y377092D02*
Y361797D01*
G01X35827Y385919D02*
Y365297D01*
G01X48425Y376809D02*
X49213D01*
G01X45276D02*
X46063D01*
G01X42126D02*
X42914D01*
G01X38977D02*
X39764D01*
G01X41339D02*
X40551D01*
G01X47638D02*
X46851D01*
G01X44488D02*
X43701D01*
G01X50788D02*
X50000D01*
G01X48425Y375842D02*
X49213D01*
G01X45276D02*
X46063D01*
G01X42126D02*
X42914D01*
G01X38977D02*
X39764D01*
G01X41339D02*
X40551D01*
G01X47638D02*
X46851D01*
G01X44488D02*
X43701D01*
G01X50788D02*
X50000D01*
G01Y374937D02*
X50788D01*
G01X46851D02*
X47638D01*
G01X43701D02*
X44488D01*
G01X40551D02*
X41339D01*
G01X42914D02*
X42126D01*
G01X39764D02*
X38977D01*
G01X46063D02*
X45276D01*
G01X49213D02*
X48425D01*
G01X39370Y373497D02*
X78740D01*
G01X50000Y372296D02*
X50788D01*
G01X46851D02*
X47638D01*
G01X43701D02*
X44488D01*
G01X40551D02*
X41339D01*
G01X42914D02*
X42126D01*
G01X39764D02*
X38977D01*
G01X46063D02*
X45276D01*
G01X49213D02*
X48425D01*
G01X50000Y368532D02*
X50788D01*
G01X46851D02*
X47638D01*
G01X43701D02*
X44488D01*
G01X40551D02*
X41339D01*
G01X42914D02*
X42126D01*
G01X39764D02*
X38977D01*
G01X46063D02*
X45276D01*
G01X49213D02*
X48425D01*
G01X50000Y376809D02*
Y368532D01*
G01X49213Y376809D02*
Y368532D01*
G01X48425Y376809D02*
Y368532D01*
G01X47638Y376809D02*
Y368532D01*
G01X46851Y376809D02*
Y368532D01*
G01X46063Y376809D02*
Y368532D01*
G01X45276Y376809D02*
Y368532D01*
G01X44488Y376809D02*
Y368532D01*
G01X43701Y376809D02*
Y368532D01*
G01X42914Y376809D02*
Y368532D01*
G01X42126Y376809D02*
Y368532D01*
G01X41339Y376809D02*
Y368532D01*
G01X40551Y376809D02*
Y368532D01*
G01X39764Y376809D02*
Y368532D01*
G01X39370Y393182D02*
Y373497D01*
G01X38977Y376809D02*
Y368532D01*
G01X37296Y375259D02*
Y371196D01*
G01X50000Y396201D02*
X50788D01*
G01X43701D02*
X44488D01*
G01X46851D02*
X47638D01*
G01X40551D02*
X41339D01*
G01X43701Y396190D02*
X44488D01*
G01X46851D02*
X47638D01*
G01X40551D02*
X41339D01*
G01X50000D02*
X50788D01*
G01X38977Y396169D02*
X77559D01*
G01X41339Y395968D02*
X40551D01*
G01X44488D02*
X43701D01*
G01X47638D02*
X46851D01*
G01X50788D02*
X50000D01*
G01Y395690D02*
X50788D01*
G01X43701D02*
X44488D01*
G01X46851D02*
X47638D01*
G01X40551D02*
X41339D01*
G01Y395618D02*
X40551D01*
G01X44488D02*
X43701D01*
G01X47638D02*
X46851D01*
G01X50788D02*
X50000D01*
G01X50931Y395574D02*
X35630D01*
G01X41339Y395330D02*
X40551D01*
G01X44488D02*
X43701D01*
G01X47638D02*
X46851D01*
G01X50788D02*
X50000D01*
G01Y395052D02*
X50788D01*
G01X43701D02*
X44488D01*
G01X46851D02*
X47638D01*
G01X40551D02*
X41339D01*
G01Y395035D02*
X40551D01*
G01X44488D02*
X43701D01*
G01X47638D02*
X46851D01*
G01X50788D02*
X50000D01*
G01X51719Y394787D02*
X35630D01*
G01X82481Y394000D02*
X35630D01*
G01X41339Y393576D02*
X40551D01*
G01X44488D02*
X43701D01*
G01X47638D02*
X46851D01*
G01X50788D02*
X50000D01*
G01Y392541D02*
X50788D01*
G01X43701D02*
X44488D01*
G01X46851D02*
X47638D01*
G01X40551D02*
X41339D01*
G01Y391941D02*
X40551D01*
G01X44488D02*
X43701D01*
G01X47638D02*
X46851D01*
G01X50788D02*
X50000D01*
G01X40666Y390138D02*
X41207D01*
G01X82284Y385919D02*
X35827D01*
G01X41207Y385807D02*
X40666D01*
G01X82284Y385132D02*
X35827D01*
G01X41749Y386453D02*
X41207Y385807D01*
G01Y386545D02*
X41749Y387190D01*
G01X50000Y396201D02*
Y391941D01*
G01X47638Y396201D02*
Y391941D01*
G01X46851Y396201D02*
Y391941D01*
G01X44488Y396201D02*
Y391941D01*
G01X43701Y396201D02*
Y391941D01*
G01X41749Y387190D02*
Y386453D01*
G01X41339Y396201D02*
Y391941D01*
G01X41207Y390138D02*
Y386545D01*
G01X40666Y385807D02*
Y390138D01*
G01X40551Y396201D02*
Y391941D01*
G01X38977Y405571D02*
Y393182D01*
G01X35630Y407091D02*
Y394000D01*
G01X50591Y415629D02*
X56496D01*
G01X41142D02*
X47048D01*
G01X42914Y405571D02*
X42126D01*
G01X39764D02*
X38977D01*
G01X46063D02*
X45276D01*
G01X49213D02*
X48425D01*
G01X42914Y404971D02*
X42126D01*
G01X39764D02*
X38977D01*
G01X46063D02*
X45276D01*
G01X49213D02*
X48425D01*
G01X42914Y403565D02*
X42126D01*
G01X39764D02*
X38977D01*
G01X46063D02*
X45276D01*
G01X49213D02*
X48425D01*
G01X35630Y403368D02*
X82481D01*
G01X48425Y403001D02*
X49213D01*
G01X45276D02*
X46063D01*
G01X42126D02*
X42914D01*
G01X38977D02*
X39764D01*
G01X48425Y401990D02*
X49213D01*
G01X45276D02*
X46063D01*
G01X42126D02*
X42914D01*
G01X38977D02*
X39764D01*
G01X42914Y401390D02*
X42126D01*
G01X39764D02*
X38977D01*
G01X46063D02*
X45276D01*
G01X49213D02*
X48425D01*
G01X50591Y427086D02*
Y415629D01*
G01X49213Y405571D02*
Y401390D01*
G01X48425Y405571D02*
Y401390D01*
G01X47048Y427086D02*
Y415629D01*
G01X46063Y405571D02*
Y401390D01*
G01X45276Y405571D02*
Y401390D01*
G01X42914Y405571D02*
Y401390D01*
G01X42126Y405571D02*
Y401390D01*
G01X41142Y427086D02*
Y415629D01*
G01X39764Y405571D02*
Y401390D01*
G01X47048Y418779D02*
X50591D01*
G01X43950Y988189D02*
G03Y996063I0J3937D01*
G01Y988189D02*
G03Y996063I0J3937D01*
G01X53211Y-25591D02*
X1392127D01*
G01X53211D02*
X1392127D01*
G01X57087Y275629D02*
G03X58268Y274448I1181J0D01*
G01X59843D02*
G03X61024Y275629I0J1181D01*
G01Y312992D02*
Y275629D01*
G01X57087Y312992D02*
Y275629D01*
G01X64174Y376809D02*
X64961D01*
G01X57874D02*
X58662D01*
G01X61024D02*
X61811D01*
G01X54725D02*
X55512D01*
G01X51575D02*
X52363D01*
G01X57087D02*
X56300D01*
G01X53937D02*
X53150D01*
G01X60237D02*
X59449D01*
G01X63386D02*
X62599D01*
G01X66536D02*
X65748D01*
G01X64174Y375842D02*
X64961D01*
G01X57874D02*
X58662D01*
G01X61024D02*
X61811D01*
G01X54725D02*
X55512D01*
G01X51575D02*
X52363D01*
G01X57087D02*
X56300D01*
G01X53937D02*
X53150D01*
G01X60237D02*
X59449D01*
G01X63386D02*
X62599D01*
G01X66536D02*
X65748D01*
G01X62599Y374937D02*
X63386D01*
G01X65748D02*
X66536D01*
G01X59449D02*
X60237D01*
G01X56300D02*
X57087D01*
G01X53150D02*
X53937D01*
G01X52363D02*
X51575D01*
G01X55512D02*
X54725D01*
G01X58662D02*
X57874D01*
G01X61811D02*
X61024D01*
G01X64961D02*
X64174D01*
G01X62599Y372296D02*
X63386D01*
G01X65748D02*
X66536D01*
G01X59449D02*
X60237D01*
G01X56300D02*
X57087D01*
G01X53150D02*
X53937D01*
G01X52363D02*
X51575D01*
G01X55512D02*
X54725D01*
G01X58662D02*
X57874D01*
G01X61811D02*
X61024D01*
G01X64961D02*
X64174D01*
G01X62599Y368532D02*
X63386D01*
G01X65748D02*
X66536D01*
G01X59449D02*
X60237D01*
G01X56300D02*
X57087D01*
G01X53150D02*
X53937D01*
G01X52363D02*
X51575D01*
G01X55512D02*
X54725D01*
G01X58662D02*
X57874D01*
G01X61811D02*
X61024D01*
G01X64961D02*
X64174D01*
G01X66536Y376809D02*
Y368532D01*
G01X65748Y376809D02*
Y368532D01*
G01X64961Y376809D02*
Y368532D01*
G01X64174Y376809D02*
Y368532D01*
G01X63386Y376809D02*
Y368532D01*
G01X62599Y376809D02*
Y368532D01*
G01X61811Y376809D02*
Y368532D01*
G01X61024Y376809D02*
Y368532D01*
G01X60237Y376809D02*
Y368532D01*
G01X59449Y376809D02*
Y368532D01*
G01X58662Y376809D02*
Y368532D01*
G01X57874Y376809D02*
Y368532D01*
G01X57087Y376809D02*
Y368532D01*
G01X56300Y376809D02*
Y368532D01*
G01X55512Y376809D02*
Y368532D01*
G01X54725Y376809D02*
Y368532D01*
G01X53937Y376809D02*
Y368532D01*
G01X53150Y376809D02*
Y368532D01*
G01X52363Y376809D02*
Y368532D01*
G01X51575Y376809D02*
Y368532D01*
G01X50788Y376809D02*
Y368532D01*
G01X62599Y396201D02*
X63386D01*
G01X65748D02*
X66536D01*
G01X59449D02*
X60237D01*
G01X53150D02*
X53937D01*
G01X56300D02*
X57087D01*
G01X62599Y396190D02*
X63386D01*
G01X65748D02*
X66536D01*
G01X59449D02*
X60237D01*
G01X53150D02*
X53937D01*
G01X56300D02*
X57087D01*
G01X53937Y395968D02*
X53150D01*
G01X57087D02*
X56300D01*
G01X60237D02*
X59449D01*
G01X63386D02*
X62599D01*
G01X66536D02*
X65748D01*
G01X62599Y395690D02*
X63386D01*
G01X65748D02*
X66536D01*
G01X59449D02*
X60237D01*
G01X53150D02*
X53937D01*
G01X56300D02*
X57087D01*
G01X53937Y395618D02*
X53150D01*
G01X57087D02*
X56300D01*
G01X60237D02*
X59449D01*
G01X63386D02*
X62599D01*
G01X66536D02*
X65748D01*
G01X63530Y395574D02*
X53006D01*
G01X82481D02*
X65605D01*
G01X53937Y395330D02*
X53150D01*
G01X57087D02*
X56300D01*
G01X60237D02*
X59449D01*
G01X63386D02*
X62599D01*
G01X66536D02*
X65748D01*
G01X62599Y395052D02*
X63386D01*
G01X65748D02*
X66536D01*
G01X59449D02*
X60237D01*
G01X53150D02*
X53937D01*
G01X56300D02*
X57087D01*
G01X53937Y395035D02*
X53150D01*
G01X57087D02*
X56300D01*
G01X60237D02*
X59449D01*
G01X63386D02*
X62599D01*
G01X66536D02*
X65748D01*
G01X64317Y394787D02*
X52219D01*
G01X82481D02*
X64817D01*
G01X53937Y393576D02*
X53150D01*
G01X57087D02*
X56300D01*
G01X60237D02*
X59449D01*
G01X63386D02*
X62599D01*
G01X66536D02*
X65748D01*
G01X62599Y392541D02*
X63386D01*
G01X65748D02*
X66536D01*
G01X59449D02*
X60237D01*
G01X53150D02*
X53937D01*
G01X56300D02*
X57087D01*
G01X53937Y391941D02*
X53150D01*
G01X57087D02*
X56300D01*
G01X60237D02*
X59449D01*
G01X63386D02*
X62599D01*
G01X66536D02*
X65748D01*
G01X63530Y395574D02*
X64317Y394787D01*
G01X50931Y395574D02*
X51719Y394787D01*
G01X65605Y395574D02*
X64817Y394787D01*
G01X52219D02*
X53006Y395574D01*
G01X66536Y396201D02*
Y391941D01*
G01X65748Y396201D02*
Y391941D01*
G01X65605Y399224D02*
Y395574D01*
G01X64817Y394787D02*
Y399224D01*
G01X64317D02*
Y394787D01*
G01X63530Y399224D02*
Y395574D01*
G01X63386Y396201D02*
Y391941D01*
G01X62599Y396201D02*
Y391941D01*
G01X60237Y396201D02*
Y391941D01*
G01X59449Y396201D02*
Y391941D01*
G01X57087Y396201D02*
Y391941D01*
G01X56300Y396201D02*
Y391941D01*
G01X53937Y396201D02*
Y391941D01*
G01X53150Y396201D02*
Y391941D01*
G01X53006Y399224D02*
Y395574D01*
G01X52219Y394787D02*
Y399224D01*
G01X51719D02*
Y394787D01*
G01X50931Y399224D02*
Y395574D01*
G01X50788Y396201D02*
Y391941D01*
G01X60040Y415629D02*
X65945D01*
G01X52363Y405571D02*
X51575D01*
G01X55512D02*
X54725D01*
G01X61811D02*
X61024D01*
G01X58662D02*
X57874D01*
G01X64961D02*
X64174D01*
G01X52363Y404971D02*
X51575D01*
G01X55512D02*
X54725D01*
G01X61811D02*
X61024D01*
G01X58662D02*
X57874D01*
G01X64961D02*
X64174D01*
G01X52363Y403565D02*
X51575D01*
G01X55512D02*
X54725D01*
G01X61811D02*
X61024D01*
G01X58662D02*
X57874D01*
G01X64961D02*
X64174D01*
G01Y403001D02*
X64961D01*
G01X61024D02*
X61811D01*
G01X57874D02*
X58662D01*
G01X54725D02*
X55512D01*
G01X51575D02*
X52363D01*
G01X64174Y401990D02*
X64961D01*
G01X61024D02*
X61811D01*
G01X57874D02*
X58662D01*
G01X54725D02*
X55512D01*
G01X51575D02*
X52363D01*
G01Y401390D02*
X51575D01*
G01X55512D02*
X54725D01*
G01X61811D02*
X61024D01*
G01X58662D02*
X57874D01*
G01X64961D02*
X64174D01*
G01X65945Y427086D02*
Y415629D01*
G01X64961Y405571D02*
Y401390D01*
G01X64174Y405571D02*
Y401390D01*
G01X61811Y405571D02*
Y401390D01*
G01X61024Y405571D02*
Y401390D01*
G01X60040Y427086D02*
Y415629D01*
G01X58662Y405571D02*
Y401390D01*
G01X57874Y405571D02*
Y401390D01*
G01X56496Y427086D02*
Y415629D01*
G01X55512Y405571D02*
Y401390D01*
G01X54725Y405571D02*
Y401390D01*
G01X52363Y405571D02*
Y401390D01*
G01X51575Y405571D02*
Y401390D01*
G01X65945Y418779D02*
X69488D01*
G01X56496D02*
X60040D01*
G01X69147Y996063D02*
G03Y988189I0J-3937D01*
G01Y996063D02*
G03Y988189I0J-3937D01*
G01X80769Y-24191D02*
Y-26991D01*
G01X79134Y286259D02*
X73229D01*
G01Y278385D02*
X79134D01*
G01Y286259D02*
Y278385D01*
G01X73229Y286259D02*
Y278385D01*
G01X80172Y366955D02*
X85433D01*
G01X83887Y366577D02*
X80836D01*
G01X83887Y366085D02*
X79950D01*
G01X84281Y365691D02*
X79557D01*
G01X85433Y365577D02*
X80172D01*
G01X83887Y367758D02*
X80836Y366577D01*
G01X83100Y368004D02*
X79950Y366774D01*
G01Y369234D02*
X83100Y368004D01*
G01X82284Y365297D02*
X84884Y361797D01*
G01X82284Y385919D02*
Y365297D01*
G01X80172Y377092D02*
Y361797D01*
G01X79950Y366774D02*
Y366085D01*
G01X79557Y377650D02*
Y365691D01*
G01X80815Y372123D02*
G03Y374333I1862J1105D01*
G01X85327Y373986D02*
G03X80815Y375259I-2649J-758D01*
G01Y371196D02*
G03X85327Y372470I1862J2032D01*
G01X84281Y377650D02*
X79557D01*
G01X83887Y377256D02*
X79950D01*
G01X85433Y377092D02*
X80172D01*
G01X85433Y376913D02*
X80172D01*
G01X76772Y376809D02*
X77559D01*
G01X73622D02*
X74410D01*
G01X67323D02*
X68111D01*
G01X70473D02*
X71260D01*
G01X69685D02*
X68898D01*
G01X72835D02*
X72048D01*
G01X75985D02*
X75197D01*
G01X79134D02*
X78347D01*
G01X83887Y376764D02*
X81033D01*
G01X76772Y375842D02*
X77559D01*
G01X73622D02*
X74410D01*
G01X67323D02*
X68111D01*
G01X70473D02*
X71260D01*
G01X69685D02*
X68898D01*
G01X72835D02*
X72048D01*
G01X75985D02*
X75197D01*
G01X79134D02*
X78347D01*
G01X81033Y375829D02*
X80639D01*
G01X78347Y374937D02*
X79134D01*
G01X72048D02*
X72835D01*
G01X75197D02*
X75985D01*
G01X68898D02*
X69685D01*
G01X68111D02*
X67323D01*
G01X71260D02*
X70473D01*
G01X74410D02*
X73622D01*
G01X77559D02*
X76772D01*
G01X78347Y372296D02*
X79134D01*
G01X72048D02*
X72835D01*
G01X75197D02*
X75985D01*
G01X68898D02*
X69685D01*
G01X68111D02*
X67323D01*
G01X71260D02*
X70473D01*
G01X74410D02*
X73622D01*
G01X77559D02*
X76772D01*
G01X83887Y369923D02*
X79950D01*
G01X83887Y369431D02*
X80836D01*
G01X78347Y368532D02*
X79134D01*
G01X72048D02*
X72835D01*
G01X75197D02*
X75985D01*
G01X68898D02*
X69685D01*
G01X68111D02*
X67323D01*
G01X71260D02*
X70473D01*
G01X74410D02*
X73622D01*
G01X77559D02*
X76772D01*
G01X80836Y369431D02*
X83887Y368250D01*
G01X79950Y376862D02*
X80098Y376813D01*
G01X81427Y372384D02*
X79950Y371400D01*
G01X83887Y373417D02*
X82362Y372384D01*
G01X83887Y374057D02*
X81870Y372679D01*
G01Y372089D02*
X79950Y370760D01*
G01X80098Y376813D02*
X80295Y376665D01*
G01X79950Y374008D02*
X81870Y372679D01*
G01Y372089D02*
X83887Y370711D01*
G01X82362Y372384D02*
X83887Y371350D01*
G01X79950Y373368D02*
X81427Y372384D01*
G01X80295Y376665D02*
X80442Y376518D01*
G01X80541Y376321D02*
X80590Y376173D01*
G01X80442Y376518D02*
X80541Y376321D01*
G01X80590Y376173D02*
X80639Y375927D01*
G01X81033Y376764D02*
Y375829D01*
G01X80815Y371196D02*
Y375259D01*
G01X80639Y375927D02*
Y375829D01*
G01X79950Y371400D02*
Y370760D01*
G01Y374008D02*
Y373368D01*
G01Y369923D02*
Y369234D01*
G01Y377256D02*
Y376862D01*
G01X79134Y376809D02*
Y368532D01*
G01X78740Y393182D02*
Y373497D01*
G01X78347Y376809D02*
Y368532D01*
G01X77559Y376809D02*
Y368532D01*
G01X76772Y376809D02*
Y368532D01*
G01X75985Y376809D02*
Y368532D01*
G01X75197Y376809D02*
Y368532D01*
G01X74410Y376809D02*
Y368532D01*
G01X73622Y376809D02*
Y368532D01*
G01X72835Y376809D02*
Y368532D01*
G01X72048Y376809D02*
Y368532D01*
G01X71260Y376809D02*
Y368532D01*
G01X70473Y376809D02*
Y368532D01*
G01X69685Y376809D02*
Y368532D01*
G01X68898Y376809D02*
Y368532D01*
G01X68111Y376809D02*
Y368532D01*
G01X67323Y376809D02*
Y368532D01*
G01X82481Y400799D02*
X85433D01*
G01Y400405D02*
X82481D01*
G01Y400012D02*
X85433D01*
G01X78347Y396201D02*
X79134D01*
G01X72048D02*
X72835D01*
G01X75197D02*
X75985D01*
G01X68898D02*
X69685D01*
G01X78347Y396190D02*
X79134D01*
G01X72048D02*
X72835D01*
G01X75197D02*
X75985D01*
G01X68898D02*
X69685D01*
G01Y395968D02*
X68898D01*
G01X72835D02*
X72048D01*
G01X75985D02*
X75197D01*
G01X79134D02*
X78347D01*
G01Y395690D02*
X79134D01*
G01X72048D02*
X72835D01*
G01X75197D02*
X75985D01*
G01X68898D02*
X69685D01*
G01Y395618D02*
X68898D01*
G01X72835D02*
X72048D01*
G01X75985D02*
X75197D01*
G01X79134D02*
X78347D01*
G01X69685Y395330D02*
X68898D01*
G01X72835D02*
X72048D01*
G01X75985D02*
X75197D01*
G01X79134D02*
X78347D01*
G01Y395052D02*
X79134D01*
G01X72048D02*
X72835D01*
G01X75197D02*
X75985D01*
G01X68898D02*
X69685D01*
G01Y395035D02*
X68898D01*
G01X72835D02*
X72048D01*
G01X75985D02*
X75197D01*
G01X79134D02*
X78347D01*
G01X69685Y393576D02*
X68898D01*
G01X72835D02*
X72048D01*
G01X75985D02*
X75197D01*
G01X79134D02*
X78347D01*
G01Y392541D02*
X79134D01*
G01X72048D02*
X72835D01*
G01X75197D02*
X75985D01*
G01X68898D02*
X69685D01*
G01Y391941D02*
X68898D01*
G01X72835D02*
X72048D01*
G01X75985D02*
X75197D01*
G01X79134D02*
X78347D01*
G01X82481Y407091D02*
Y394000D01*
G01X79134Y396201D02*
Y391941D01*
G01X78347Y396201D02*
Y391941D01*
G01X77559Y405571D02*
Y393182D01*
G01X75985Y396201D02*
Y391941D01*
G01X75197Y396201D02*
Y391941D01*
G01X72835Y396201D02*
Y391941D01*
G01X72048Y396201D02*
Y391941D01*
G01X69685Y396201D02*
Y391941D01*
G01X68898Y396201D02*
Y391941D01*
G01X69488Y415629D02*
X75394D01*
G01X82481Y407091D02*
X85433D01*
G01X71260Y405571D02*
X70473D01*
G01X68111D02*
X67323D01*
G01X74410D02*
X73622D01*
G01X77559D02*
X76772D01*
G01X71260Y404971D02*
X70473D01*
G01X68111D02*
X67323D01*
G01X74410D02*
X73622D01*
G01X77559D02*
X76772D01*
G01X71260Y403565D02*
X70473D01*
G01X68111D02*
X67323D01*
G01X74410D02*
X73622D01*
G01X77559D02*
X76772D01*
G01Y403001D02*
X77559D01*
G01X73622D02*
X74410D01*
G01X70473D02*
X71260D01*
G01X67323D02*
X68111D01*
G01X76772Y401990D02*
X77559D01*
G01X73622D02*
X74410D01*
G01X70473D02*
X71260D01*
G01X67323D02*
X68111D01*
G01X71260Y401390D02*
X70473D01*
G01X68111D02*
X67323D01*
G01X74410D02*
X73622D01*
G01X77559D02*
X76772D01*
G01Y405571D02*
Y401390D01*
G01X75394Y427086D02*
Y415629D01*
G01X74410Y405571D02*
Y401390D01*
G01X73622Y405571D02*
Y401390D01*
G01X71260Y405571D02*
Y401390D01*
G01X70473Y405571D02*
Y401390D01*
G01X69488Y427086D02*
Y415629D01*
G01X68111Y405571D02*
Y401390D01*
G01X67323Y405571D02*
Y401390D01*
G01X75394Y418779D02*
X93977D01*
G01X99804Y996063D02*
X69147D01*
G01X99804D02*
X69147D01*
G01X94412Y72220D02*
G03X85830Y72219I-4291J-1D01*
G01D02*
G03X94412Y72220I4291J0D01*
G01X90827Y279960D02*
G03X92402Y278385I1575J0D01*
G01X93977Y279960D02*
X90827D01*
G01X93977Y278385D02*
X92402D01*
G01X96929Y275629D02*
X95748Y274448D01*
G01X96929Y302007D02*
Y275629D01*
G01X93977Y312992D02*
Y274448D01*
G01X92008Y312992D02*
Y274448D01*
G01X90827Y312992D02*
Y279960D01*
G01X100394Y291377D02*
G03X92520Y299252I-7874J1D01*
G01X100394Y291377D02*
G03X92520Y299252I-7874J1D01*
G01X95847Y305944D02*
Y302007D01*
G01X101004Y309055D02*
X96063D01*
G01X104233Y305944D02*
X96063D01*
G01D02*
X95847D01*
G01X99863Y329921D02*
Y305944D01*
G01X99803Y427086D02*
Y305944D01*
G01X98996Y423149D02*
Y309055D01*
G01X98622Y305944D02*
Y427086D01*
G01X97835D02*
Y305944D01*
G01X97028Y423149D02*
Y309055D01*
G01X96339Y305944D02*
Y427086D01*
G01X96063Y309055D02*
Y305944D01*
G01X102756Y337795D02*
G03I-3937J0D01*
G01X103740D02*
G03I-4921J0D01*
G01X106693D02*
G03I-7874J0D01*
G01X104233Y329921D02*
X99863D01*
G01X93977Y418779D02*
Y323622D01*
G01X104233Y345669D02*
X99863D01*
G01Y388976D02*
Y345669D01*
G01X85433Y407091D02*
Y361797D01*
G01X84281Y377650D02*
Y365691D01*
G01X83887Y366577D02*
Y366085D01*
G01Y368250D02*
Y367758D01*
G01X98780Y373228D02*
G03I-1890J0D01*
G01X99764D02*
G03I-2874J0D01*
G01X99941D02*
G03I-3051J0D01*
G01X85327Y373986D02*
Y372470D01*
G01X83887Y371350D02*
Y370711D01*
G01Y374057D02*
Y373417D01*
G01Y369923D02*
Y369431D01*
G01Y377256D02*
Y376764D01*
G01X102756Y396850D02*
G03I-3937J0D01*
G01X103740D02*
G03I-4921J0D01*
G01X106693D02*
G03I-7874J0D01*
G01X104233Y388976D02*
X99863D01*
G01X104233Y404724D02*
X99863D01*
G01D02*
Y427086D01*
G01X101004Y423149D02*
X92933D01*
G01D02*
Y432440D01*
G01X99804Y1023622D02*
Y996063D01*
G01Y1023622D02*
Y996063D01*
G01Y1023868D02*
Y1041084D01*
G01X97087Y1042536D02*
X96288Y1043135D01*
X95889Y1043834D01*
X95756Y1044632D01*
X96022Y1045630D01*
X96688Y1046329D01*
X97486Y1046529D01*
X98285Y1046429D01*
X98950Y1046029D01*
X100281Y1044033D01*
X101212Y1043135D01*
X102544Y1042536D01*
X103741Y1042336D01*
Y1046529D01*
G01X102544Y1050222D02*
X103209Y1050820D01*
X103608Y1051519D01*
X103741Y1052417D01*
X103475Y1053316D01*
X102943Y1054014D01*
X102011Y1054514D01*
X100946Y1054613D01*
X99882Y1054414D01*
X99216Y1053915D01*
X98684Y1053216D01*
X98551Y1052517D01*
X98684Y1051819D01*
X99216Y1050920D01*
X95756Y1051220D01*
Y1053915D01*
G01X104007Y1060402D02*
X103874Y1060203D01*
X103608D01*
X103475Y1060402D01*
X103608Y1060602D01*
X103874D01*
X104007Y1060402D01*
G01X102144Y1066192D02*
X103076Y1066790D01*
X103608Y1067589D01*
X103741Y1068487D01*
X103608Y1069286D01*
X102943Y1070084D01*
X102144Y1070583D01*
X101346Y1070683D01*
X100414Y1070484D01*
X99749Y1069785D01*
X99482Y1069086D01*
Y1068188D01*
G01Y1069086D02*
X99083Y1069685D01*
X98418Y1070184D01*
X97619Y1070384D01*
X96821Y1070184D01*
X96155Y1069685D01*
X95756Y1068787D01*
X95889Y1067888D01*
X96422Y1066990D01*
G01X102544Y1074177D02*
X103209Y1074775D01*
X103608Y1075474D01*
X103741Y1076372D01*
X103475Y1077271D01*
X102943Y1077969D01*
X102011Y1078469D01*
X100946Y1078568D01*
X99882Y1078369D01*
X99216Y1077870D01*
X98684Y1077171D01*
X98551Y1076472D01*
X98684Y1075774D01*
X99216Y1074875D01*
X95756Y1075175D01*
Y1077870D01*
G01X112264Y-24191D02*
Y-26991D01*
G01X106247Y-5451D02*
X108018D01*
G01X107132D02*
Y-11357D01*
G01X106247D02*
X108018D01*
G01X111414D02*
Y-5451D01*
X112890D01*
X113480Y-5746D01*
X113923Y-6140D01*
X114292Y-6731D01*
X114588Y-7420D01*
X114661Y-8404D01*
X114588Y-9388D01*
X114292Y-10077D01*
X113923Y-10668D01*
X113480Y-11062D01*
X112890Y-11357D01*
X111414D01*
G01X117983Y-9388D02*
X119902D01*
G01X123371Y-5451D02*
Y-11357D01*
X126324D01*
G01X128907D02*
X130752Y-5451D01*
X132598Y-11357D01*
G01X131934Y-9290D02*
X129571D01*
G01X137248Y-8207D02*
X137543Y-7912D01*
X137765Y-7420D01*
X137912Y-6731D01*
X137765Y-6140D01*
X137470Y-5746D01*
X136953Y-5451D01*
X134960D01*
Y-11357D01*
X137396D01*
X137912Y-10963D01*
X138208Y-10373D01*
X138355Y-9684D01*
X138208Y-8995D01*
X137765Y-8404D01*
X137248Y-8207D01*
X134960D01*
G01X144039Y-11357D02*
X141086D01*
Y-5451D01*
X144039D01*
G01X142858Y-8305D02*
X141086D01*
G01X146991Y-5451D02*
Y-11357D01*
X149944D01*
G01X153413Y-9388D02*
X155332D01*
G01X160277Y-11357D02*
Y-5451D01*
X159392Y-6632D01*
G01Y-11357D02*
X161163D01*
G01X164780Y-8896D02*
X165297Y-8207D01*
X165740Y-7813D01*
X166330Y-7617D01*
X166847Y-7813D01*
X167216Y-8207D01*
X167511Y-8798D01*
X167585Y-9487D01*
X167511Y-10077D01*
X167216Y-10668D01*
X166773Y-11160D01*
X166256Y-11357D01*
X165666Y-11160D01*
X165149Y-10570D01*
X164854Y-9684D01*
X164780Y-8699D01*
X164928Y-7420D01*
X165149Y-6731D01*
X165518Y-6042D01*
X166035Y-5549D01*
X166552Y-5451D01*
X167068Y-5648D01*
X167437Y-6140D01*
G01X171128Y-9388D02*
X173047D01*
G01X176369Y-11357D02*
Y-5451D01*
X177845D01*
X178435Y-5746D01*
X178878Y-6140D01*
X179247Y-6731D01*
X179543Y-7420D01*
X179616Y-8404D01*
X179543Y-9388D01*
X179247Y-10077D01*
X178878Y-10668D01*
X178435Y-11062D01*
X177845Y-11357D01*
X176369D01*
G01X100394Y236259D02*
G03X116142Y220511I15748J0D01*
G01D02*
X232088D01*
G01X100394Y236259D02*
G03X116142Y220511I15748J0D01*
G01D02*
X232088D01*
G01X116142Y228385D02*
X239961D01*
G01X108268Y236259D02*
G03X116142Y228385I7874J0D01*
G01X108268Y299252D02*
Y236259D01*
G01X100395Y240899D02*
X100394Y236259D01*
G01X100395Y240899D02*
X100394Y236259D01*
G01X108268D02*
G03X116142Y228385I7874J0D01*
G01D02*
X239961D01*
G01X108268Y299252D02*
Y236259D01*
G01X108269Y240899D02*
G03X100395I-3937J0D01*
G01X108269D02*
G03X100395I-3937J0D01*
G01Y266096D02*
G03X108269I3937J-1D01*
G01X100395D02*
G03X108269I3937J-1D01*
G01X100395D02*
X100394Y291377D01*
G01X100395Y266096D02*
X100394Y291377D01*
G01X108268Y299252D02*
G03X100394Y307126I-7874J0D01*
G01X108268Y299252D02*
G03X100394Y307126I-7874J0D01*
G01X104233Y302007D02*
Y427086D01*
G01X100689Y302007D02*
Y305944D01*
G01X101004Y423149D02*
Y309055D01*
G01X100020Y423149D02*
Y309055D01*
G01X103740Y988189D02*
G03X107677Y992126I0J3937D01*
G01Y1018109D02*
Y992126D01*
G01X103740Y988189D02*
G03X107677Y992126I0J3937D01*
G01Y1018110D02*
Y992126D01*
G01X115551Y1001574D02*
X112796D01*
G01X111614D02*
X108859D01*
G01X115551Y1014173D02*
Y1001574D01*
G01X112796D02*
Y1014173D01*
G01X111614Y1018110D02*
Y1001574D01*
G01X108859D02*
Y1018110D01*
G01X107677Y1021899D02*
Y1040083D01*
G01X107678Y1021653D02*
X107677Y1018109D01*
G01X134056Y1023622D02*
X109646D01*
G01D02*
X107678Y1021653D01*
G01X134055Y1023622D02*
X109646D01*
G01X108859Y1018110D02*
X111614D01*
G01X136024D02*
X107677D01*
G01X112796Y1014173D02*
X115551D01*
G01X107677Y1021653D02*
Y1018110D01*
G01X109646Y1023622D02*
X107677Y1021653D01*
G01Y1040083D02*
X112179Y1041501D01*
G01X109462Y1044370D02*
X108663Y1044969D01*
X108264Y1045668D01*
X108131Y1046466D01*
X108397Y1047464D01*
X109063Y1048163D01*
X109861Y1048363D01*
X110660Y1048263D01*
X111325Y1047863D01*
X112656Y1045867D01*
X113587Y1044969D01*
X114919Y1044370D01*
X116116Y1044170D01*
Y1048363D01*
G01Y1054052D02*
X114386Y1054251D01*
X112922Y1054551D01*
X111591Y1054950D01*
X110127Y1055449D01*
X108131Y1056248D01*
Y1052255D01*
G01X116382Y1062236D02*
X116249Y1062037D01*
X115983D01*
X115850Y1062236D01*
X115983Y1062436D01*
X116249D01*
X116382Y1062236D01*
G01X114519Y1068026D02*
X115451Y1068624D01*
X115983Y1069423D01*
X116116Y1070321D01*
X115983Y1071120D01*
X115318Y1071918D01*
X114519Y1072417D01*
X113721Y1072517D01*
X112789Y1072318D01*
X112124Y1071619D01*
X111857Y1070920D01*
Y1070022D01*
G01Y1070920D02*
X111458Y1071519D01*
X110793Y1072018D01*
X109994Y1072218D01*
X109196Y1072018D01*
X108530Y1071519D01*
X108131Y1070621D01*
X108264Y1069722D01*
X108797Y1068824D01*
G01X114919Y1076011D02*
X115584Y1076609D01*
X115983Y1077308D01*
X116116Y1078206D01*
X115850Y1079105D01*
X115318Y1079803D01*
X114386Y1080303D01*
X113321Y1080402D01*
X112257Y1080203D01*
X111591Y1079704D01*
X111059Y1079005D01*
X110926Y1078306D01*
X111059Y1077608D01*
X111591Y1076709D01*
X108131Y1077009D01*
Y1079704D01*
G01X112179Y1041501D02*
Y1042918D01*
G01X125788Y235275D02*
G03X137992I6102J0D01*
G01X125788D02*
X137992D01*
G01X131890Y265787D02*
Y235275D01*
G01X125788Y244724D02*
Y235275D01*
G01X129174Y249645D02*
G03X129370Y249448I197J0D01*
G01X130709D02*
G03X130906Y249645I0J197D01*
G01D02*
X132874D01*
G01X138058Y249448D02*
X123860D01*
G01X142323Y248070D02*
X121457D01*
G01X124410Y245511D02*
X137992D01*
G01X125000Y244724D02*
X137992D01*
G01X118701Y244133D02*
X145079D01*
G01X120906Y252362D02*
X127599Y249448D01*
G01X126811Y254729D02*
X129174Y251417D01*
G01X130906Y249645D02*
Y270905D01*
G01X129174Y251417D02*
Y249645D01*
G01X125000Y244724D02*
Y245511D01*
G01X124878Y265787D02*
Y249448D01*
G01X124410Y245511D02*
Y249448D01*
G01X123860D02*
Y244133D01*
G01X121457Y268543D02*
Y248070D01*
G01X120906Y270905D02*
Y252362D01*
G01X120709Y268543D02*
Y244133D01*
G01X118701Y270905D02*
Y244133D01*
G01X122874Y256107D02*
G03X123465Y255516I591J0D01*
G01X122874Y269763D02*
X120906D01*
G01X132874D02*
X130906D01*
G01X123859Y268543D02*
X120315D01*
G01X134174D02*
X129607D01*
G01X120315Y266968D02*
X143465D01*
G01X138058Y265787D02*
X124878D01*
G01X126811Y255516D02*
X123465D01*
G01X130315Y268937D02*
X126772Y266968D01*
G01X123465Y268937D02*
X125433Y266968D01*
G01X130315Y270905D02*
Y268937D01*
G01X126811Y255516D02*
Y254729D01*
G01X123465Y270905D02*
Y268937D01*
G01X122874Y256107D02*
Y270905D01*
G01X120315Y266968D02*
Y270905D01*
G01X118701D02*
X120906D01*
G01X130906D02*
X122874D01*
G01Y270511D02*
X120906D01*
G01X132874D02*
X130906D01*
G01X119488Y1001574D02*
X116733D01*
G01X123425D02*
X120670D01*
G01X127363D02*
X124607D01*
G01X131300D02*
X128544D01*
G01X135237D02*
X132481D01*
G01D02*
Y1018110D01*
G01X131300D02*
Y1001574D01*
G01X128544D02*
Y1018110D01*
G01X127363D02*
Y1001574D01*
G01X124607D02*
Y1018110D01*
G01X123425D02*
Y1001574D01*
G01X120670D02*
Y1018110D01*
G01X119488D02*
Y1001574D01*
G01X116733D02*
Y1018110D01*
G01X132481D02*
X135237D01*
G01X128544D02*
X131300D01*
G01X124607D02*
X127363D01*
G01X120670D02*
X123425D01*
G01X116733D02*
X119488D01*
G01X143759Y-24191D02*
Y-26991D01*
G01X137992Y249448D02*
Y235275D01*
G01X134410Y249448D02*
G03X134607Y249645I0J197D01*
G01X132874D02*
G03X133071Y249448I197J0D01*
G01X142874Y252283D02*
X136361Y249448D01*
G01X136813Y249645D02*
X134607D01*
G01X145079Y270905D02*
Y244133D01*
G01X143071Y268543D02*
Y244133D01*
G01X142874Y252283D02*
Y270905D01*
G01X142323Y268543D02*
Y248070D01*
G01X138058Y265787D02*
Y249448D01*
G01X138032D02*
Y244133D01*
G01X134607Y255157D02*
Y249645D01*
G01X132874D02*
Y270905D01*
G01X135197Y255748D02*
G03X134607Y255157I1J-591D01*
G01X140315Y255748D02*
G03X140906Y256338I1J590D01*
G01X142874Y269763D02*
X140906D01*
G01X143465Y268543D02*
X139843D01*
G01X140315Y255748D02*
X135197D01*
G01X137953Y266968D02*
X140315Y268937D01*
G01X137008Y266968D02*
X133465Y268937D01*
G01X143465Y270905D02*
Y266968D01*
G01X140906Y256338D02*
Y270905D01*
G01X140315D02*
Y268937D01*
G01X133465Y270905D02*
Y268937D01*
G01X141782Y275748D02*
X142303D01*
G01Y271574D02*
X141782D01*
G01X140906Y270905D02*
X132874D01*
G01X145079D02*
X142874D01*
G01Y270511D02*
X140906D01*
G01X141782Y275037D02*
X141260Y274416D01*
G01Y275126D02*
X141782Y275748D01*
G01X142303D02*
Y271574D01*
G01X141782D02*
Y275037D01*
G01X141260Y274416D02*
Y275126D01*
G01X142697Y382115D02*
X149587D01*
G01Y380607D02*
X142697D01*
G01Y375078D02*
X141221D01*
G01X142697Y380607D02*
Y375078D01*
G01Y386889D02*
Y382115D01*
G01X141221Y375078D02*
Y386889D01*
G01D02*
X142697D01*
G01X136024Y994290D02*
G03X143505I3740J0D01*
G01X136024Y994291D02*
G03X143504I3740J0D01*
G01X136024Y994290D02*
Y1018109D01*
G01X143504D02*
Y994290D01*
G01X147048Y1001574D02*
X144292D01*
G01X150985D02*
X148229D01*
G01D02*
Y1018110D01*
G01X147048D02*
Y1001574D01*
G01X144292D02*
Y1018110D01*
G01X143504Y1021653D02*
Y994291D01*
G01X136024D02*
Y1021653D01*
G01X135237Y1018110D02*
Y1001574D01*
G01X136024Y1021653D02*
Y1018109D01*
G01X143505Y1021653D02*
X143504Y1018109D01*
G01X185631Y1023622D02*
X145473D01*
G01X136024Y1021653D02*
X134056Y1023622D01*
G01X145473D02*
X143505Y1021653D01*
G01X185630Y1023622D02*
X145473D01*
G01X148229Y1018110D02*
X150985D01*
G01X144292D02*
X147048D01*
G01X187599D02*
X143504D01*
G01X136024Y1021653D02*
X134055Y1023622D01*
G01X145473D02*
X143504Y1021653D01*
G01X151575Y220511D02*
X226378D01*
G01X151575D02*
X226378D01*
G01X153445Y236929D02*
X154429D01*
G01Y236161D02*
X153445D01*
G01X154429Y234586D02*
X153445D01*
G01X154429Y233996D02*
X153445D01*
G01Y231122D02*
X224508D01*
G01X153445Y229153D02*
X154429D01*
G01X151575Y228385D02*
X226378D01*
G01X153445Y228366D02*
X154429D01*
G01X155906Y267736D02*
Y231122D01*
G01X154429Y267813D02*
Y228366D01*
G01X153445D02*
Y267736D01*
G01X151575Y318937D02*
Y228385D01*
G01X155899Y242830D02*
G03X155751Y244033I-844J507D01*
G01X154961Y246572D02*
G03X155248Y245928I983J52D01*
G01X155512Y246771D02*
G03I-1575J0D01*
G01Y238897D02*
G03I-1575J0D01*
G01X153978Y246521D02*
G03X154552Y245232I1966J103D01*
G01X156742Y242323D02*
G03X156447Y244729I-1687J1014D01*
G01X154429Y249330D02*
X153445D01*
G01X154429Y248149D02*
X153445D01*
G01Y248044D02*
X154429D01*
G01Y247748D02*
X153445D01*
G01Y246385D02*
X154429D01*
G01Y246089D02*
X153445D01*
G01X154429Y245984D02*
X153445D01*
G01Y244803D02*
X154429D01*
G01Y241456D02*
X153445D01*
G01X154429Y240275D02*
X153445D01*
G01Y240170D02*
X154429D01*
G01Y239874D02*
X153445D01*
G01X154429Y238523D02*
X153445D01*
G01Y238511D02*
X154429D01*
G01Y238215D02*
X153445D01*
G01X154429Y238110D02*
X153445D01*
G01X156742Y242323D02*
X155169Y239704D01*
G01X155899Y242830D02*
X154325Y240211D01*
G01X155339Y241898D02*
X156183Y241392D01*
G01X154325Y240211D02*
X155169Y239704D01*
G01X155248Y245928D02*
X156447Y244729D01*
G01X154552Y245232D02*
X155751Y244033D01*
G01X154429Y256712D02*
X154961Y246572D01*
G01X153445Y256687D02*
X153978Y246521D01*
G01X153545Y268274D02*
G03X153447Y267736I1869J-618D01*
G01X155512Y260551D02*
G03I-1575J0D01*
G01X168111Y267736D02*
X153445D01*
G01X154429Y263110D02*
X153445D01*
G01X154429Y261929D02*
X153445D01*
G01Y261823D02*
X154429D01*
G01Y261528D02*
X153445D01*
G01Y260164D02*
X154429D01*
G01Y259869D02*
X153445D01*
G01X154429Y259763D02*
X153445D01*
G01Y258582D02*
X154429D01*
G01Y257696D02*
X153445D01*
G01X154429Y256712D02*
X153445D01*
G01X155659Y271520D02*
X154429Y267813D01*
G01X154625Y271529D02*
X153545Y268274D01*
G01X155659Y271520D02*
G03X155709Y271830I-934J310D01*
G01X158268Y272342D02*
G03X159449Y273523I0J1181D01*
G01Y279822D02*
G03X158268Y281003I-1181J0D01*
G01X154625Y271529D02*
G03X154725Y272148I-1869J619D01*
G01X159193Y284041D02*
G03Y282100I-1712J-970D01*
G01X159981Y284230D02*
G03Y281911I-2500J-1160D01*
G01X160551Y283070D02*
G03I-3070J0D01*
G01X164766Y277464D02*
X164368D01*
G01X161617D02*
X161218D01*
G01X164016Y286023D02*
X163485D01*
G01X162500D02*
X161969D01*
G01X165650D02*
X165118D01*
G01X162704Y284004D02*
X163281D01*
G01X161697Y283763D02*
X161138D01*
G01X164846D02*
X164288D01*
G01X163386Y283660D02*
X162599D01*
G01X164318Y283564D02*
X164816D01*
G01X161169D02*
X161666D01*
G01X161661Y283539D02*
X161174D01*
G01X164811D02*
X164324D01*
G01X161024Y283505D02*
X161811D01*
G01X164174D02*
X164961D01*
G01X161811Y283323D02*
X161024D01*
G01X164961D02*
X164174D01*
G01X161024Y283182D02*
X161811D01*
G01X164174D02*
X164961D01*
G01X161811Y282965D02*
X161024D01*
G01X164961D02*
X164174D01*
G01X164335Y282665D02*
X164800D01*
G01X161185D02*
X161650D01*
G01X162599Y282635D02*
X163386D01*
G01X163272Y282210D02*
X162713D01*
G01X159981Y281102D02*
X154725D01*
G01Y281003D02*
X158268D01*
G01X165118Y280118D02*
X165650D01*
G01X163485D02*
X164016D01*
G01X161969D02*
X162500D01*
G01X162599Y279285D02*
X163386D01*
G01X161811Y278814D02*
X161024D01*
G01X164961D02*
X164174D01*
G01X159981Y278740D02*
X154725D01*
G01X163386Y278002D02*
X162599D01*
G01X161081Y277976D02*
X161754D01*
G01X164231D02*
X164903D01*
G01X154725Y277952D02*
X159981D01*
G01X162599Y277752D02*
X163386D01*
G01X164301Y277712D02*
X164833D01*
G01X161152D02*
X161683D01*
G01X161682Y277707D02*
X161153D01*
G01X164832D02*
X164303D01*
G01X163386Y277698D02*
X162599D01*
G01X163386Y277671D02*
X162599D01*
G01X164369Y277455D02*
X164764D01*
G01X161220D02*
X161614D01*
G01X162500Y276377D02*
X163485D01*
G01X165118Y275846D02*
X167166D01*
G01X161969D02*
X164016D01*
G01X163780Y274409D02*
X162205D01*
G01X166929D02*
X165355D01*
G01X157874Y274350D02*
X220079D01*
G01X154725Y272637D02*
X159981D01*
G01X158268Y272342D02*
X154725D01*
G01X223229Y271653D02*
X154725D01*
G01X163386Y277824D02*
X162599Y277823D01*
G01X165650Y276377D02*
X165118Y275846D01*
G01X162500Y276377D02*
X161969Y275846D01*
G01X155709Y271653D02*
X156693Y272637D01*
G01X157874Y274350D02*
X155177Y271653D01*
G01X163485Y276377D02*
X164016Y275846D01*
G01X164764Y277455D02*
X164961Y278189D01*
G01X161614Y277455D02*
X161811Y278189D01*
G01X164816Y283564D02*
X164811Y283539D01*
G01X161666Y283564D02*
X161661Y283539D01*
G01X163281Y284004D02*
X163386Y284521D01*
G01X162713Y282210D02*
X162599Y281616D01*
G01X164174Y281766D02*
X164335Y282665D01*
G01X161024Y281766D02*
X161185Y282665D01*
G01X164961Y284919D02*
X164846Y283763D01*
G01X161811Y284919D02*
X161697Y283763D01*
G01X165355Y274409D02*
Y271653D01*
G01X165197Y305255D02*
Y271653D01*
G01X165118Y304940D02*
Y275846D01*
G01X164961Y278189D02*
Y315472D01*
G01X164174Y278189D02*
Y315472D01*
G01X164016Y275846D02*
Y304940D01*
G01X163937Y305255D02*
Y271653D01*
G01X163780Y274409D02*
Y271653D01*
G01X163485Y286023D02*
Y304409D01*
G01Y276377D02*
Y280118D01*
G01X163386Y305826D02*
Y277671D01*
G01X162599D02*
Y305826D01*
G01X162500Y280118D02*
Y276377D01*
G01Y304409D02*
Y286023D01*
G01X162205Y274409D02*
Y271653D01*
G01X162048Y305255D02*
Y271653D01*
G01X161969Y304940D02*
Y275846D01*
G01X161811Y278189D02*
Y315472D01*
G01X161024Y278189D02*
Y315472D01*
G01X160788Y305255D02*
Y271653D01*
G01X159981D02*
Y287401D01*
G01X159449Y279822D02*
Y273523D01*
G01X159193Y282100D02*
Y284041D01*
G01X157874Y295748D02*
Y274350D01*
G01X156693Y272342D02*
Y272637D01*
G01D02*
Y281102D01*
G01X155709Y271653D02*
Y295629D01*
G01X154725Y271653D02*
Y316929D01*
G01X164288Y283763D02*
X164174Y284919D01*
G01X164800Y282665D02*
X164961Y281766D01*
G01X161650Y282665D02*
X161811Y281766D01*
G01X163386Y281616D02*
X163272Y282210D01*
G01X162704Y284004D02*
X162599Y284521D01*
G01X164324Y283539D02*
X164318Y283564D01*
G01X161174Y283539D02*
X161169Y283564D01*
G01X164370Y277455D02*
X164174Y278189D01*
G01X161221Y277455D02*
X161024Y278189D01*
G01X161138Y283763D02*
X161024Y284919D01*
G01X156654Y289153D02*
X155688Y288966D01*
G01X165118Y301574D02*
X165650Y301794D01*
G01X162500D02*
X161969Y301574D01*
G01X163386Y302401D02*
X162599D01*
G01X163386Y302165D02*
X162599D01*
G01X161024Y302126D02*
X161811D01*
G01X164174D02*
X164961D01*
G01X161024Y302086D02*
X161811D01*
G01X164174D02*
X164961D01*
G01X163386Y301988D02*
X162599D01*
G01X161811Y301847D02*
X161024D01*
G01X164961D02*
X164174D01*
G01X162599Y301811D02*
X163386D01*
G01X161969Y301574D02*
X154725D01*
G01X163386D02*
X162599D01*
G01X165118D02*
X164016D01*
G01X162500Y301555D02*
X163485D01*
G01X162599Y301496D02*
X163386D01*
G01X163485Y301240D02*
X162500D01*
G01X162599Y301202D02*
X163386D01*
G01Y301181D02*
X162599D01*
G01X163377Y301141D02*
X162608D01*
G01X163386Y301129D02*
X162599D01*
G01Y301094D02*
X163386D01*
G01X162711Y301039D02*
X163275D01*
G01X161024Y301026D02*
X161811D01*
G01X164174D02*
X164961D01*
G01X162599Y301014D02*
X163386D01*
G01X161811Y300908D02*
X161024D01*
G01X164961D02*
X164174D01*
G01X161969Y300787D02*
X154725D01*
G01X165118D02*
X164016D01*
G01X163189Y300783D02*
X162796D01*
G01X163485Y300000D02*
X165650D01*
G01X154725D02*
X162500D01*
G01X161024Y299753D02*
X161811D01*
G01X164174D02*
X164961D01*
G01X161024Y299731D02*
X161811D01*
G01X164174D02*
X164961D01*
G01X161811Y299477D02*
X161024D01*
G01X164961D02*
X164174D01*
G01X161811Y298818D02*
X161024D01*
G01X164961D02*
X164174D01*
G01X162796Y298626D02*
X163189D01*
G01X163275Y298370D02*
X162711D01*
G01X162608Y298267D02*
X163377D01*
G01X161811Y298228D02*
X161024D01*
G01X164961D02*
X164174D01*
G01X163485D02*
X162500D01*
G01X163386Y298015D02*
X162599D01*
G01X162500Y297913D02*
X163485D01*
G01X161811Y297637D02*
X161024D01*
G01X164961D02*
X164174D01*
G01X162500Y297598D02*
X163485D01*
G01X162599Y297582D02*
X163386D01*
G01X162599Y297358D02*
X163386D01*
G01X161024Y297047D02*
X161811D01*
G01X164174D02*
X164961D01*
G01X163386Y296925D02*
X162599D01*
G01X161811Y296456D02*
X161024D01*
G01X164961D02*
X164174D01*
G01X220079Y295748D02*
X157874D01*
G01X154725Y295728D02*
X155709D01*
G01Y295629D02*
X154725D01*
G01Y294547D02*
X155709D01*
G01Y294153D02*
X154725D01*
G01X155838Y293366D02*
X154725D01*
G01X155709Y288543D02*
X156693D01*
G01X155709Y288051D02*
X154725D01*
G01X159981Y287401D02*
X154725D01*
G01X159981Y286614D02*
X154725D01*
G01X162608Y298267D02*
X162711Y298370D01*
G01X165118Y300787D02*
X165650Y301318D01*
G01D02*
X165118Y300787D01*
G01X163275Y301039D02*
X163377Y301141D01*
G01X161969Y300787D02*
X162500Y301318D01*
G01D02*
X161969Y300787D01*
G01X163485Y301794D02*
X164016Y301574D01*
G01X163485Y301318D02*
X164016Y300787D01*
G01D02*
X163485Y301318D01*
G01X162711Y301039D02*
X162608Y301141D01*
G01X163275Y298370D02*
X163377Y298267D01*
G01X165059Y305118D02*
Y295748D01*
G01X164075Y305118D02*
Y295748D01*
G01X163189Y300783D02*
Y298626D01*
G01X162796D02*
Y300783D01*
G01X161910Y305118D02*
Y295748D01*
G01X160925Y305118D02*
Y295748D01*
G01X156693Y288543D02*
Y305511D01*
G01X155709Y295629D02*
Y295728D01*
G01X156654Y289153D02*
X155709Y294035D01*
G01X154725Y293940D02*
X155688Y288966D01*
G01X161461Y315808D02*
X161359Y315787D01*
G01X226378Y318937D02*
X151575D01*
G01X154725Y316929D02*
X157874D01*
G01X161912Y316771D02*
X162035D01*
G01X160866D02*
X161359D01*
G01X161379Y316646D02*
X160990D01*
G01Y316352D02*
X161379D01*
G01X160990Y316227D02*
X161379D01*
G01X154725Y316141D02*
X157874D01*
G01X161379Y315913D02*
X160990D01*
G01X162035Y315787D02*
X161912D01*
G01X161359D02*
X160866D01*
G01X161811Y315472D02*
X161024D01*
G01X164961D02*
X164174D01*
G01X161811Y314881D02*
X161024D01*
G01X164961D02*
X164174D01*
G01X161024Y313976D02*
X161811D01*
G01X164174D02*
X164961D01*
G01X162520Y313385D02*
X163465D01*
G01X154725D02*
X160315D01*
G01X161811D02*
X161024D01*
G01X164961D02*
X164174D01*
G01X161811Y312677D02*
X161024D01*
G01X164961D02*
X164174D01*
G01X154725Y312598D02*
X157874D01*
G01X154725Y312204D02*
X157874D01*
G01X161811Y311732D02*
X161024D01*
G01X164961D02*
X164174D01*
G01X157874Y311417D02*
X154725D01*
G01X164055Y311141D02*
X165079D01*
G01X160906D02*
X161929D01*
G01X154725Y310629D02*
X157874D01*
G01X161024Y310551D02*
X161811D01*
G01X164174D02*
X164961D01*
G01X161440Y315933D02*
X161379Y315913D01*
G01Y316352D02*
X161440Y316373D01*
G01X220079Y307086D02*
X157874D01*
G01X161811Y306102D02*
X161024D01*
G01X164961D02*
X164174D01*
G01X163386Y305826D02*
X162599D01*
G01X223229Y305511D02*
X154725D01*
G01X163386Y305236D02*
X162599D01*
G01X160925Y305118D02*
X161910D01*
G01X165059D02*
X164075D01*
G01X164016Y304940D02*
X161969D01*
G01X167166D02*
X165118D01*
G01X161811Y304921D02*
X161024D01*
G01X164961D02*
X164174D01*
G01X163485Y304409D02*
X162500D01*
G01X163386Y304330D02*
X162599D01*
G01X161024Y304133D02*
X161811D01*
G01X164174D02*
X164961D01*
G01X162599Y304094D02*
X163386D01*
G01X161811Y304015D02*
X161024D01*
G01X164961D02*
X164174D01*
G01X163386Y303917D02*
X162599D01*
G01X165355Y303543D02*
X163780D01*
G01X162205D02*
X160630D01*
G01X163386D02*
X162599D01*
G01X163386Y303503D02*
X162599D01*
G01X161543Y316311D02*
X161502Y316290D01*
G01X161359Y316771D02*
X161461Y316750D01*
G01X161440Y316625D02*
X161379Y316646D01*
G01Y316227D02*
X161440Y316206D01*
G01X161543Y315871D02*
X161461Y315808D01*
G01X165453Y305511D02*
X165059Y305118D01*
G01X163485Y304409D02*
X164016Y304940D01*
G01X162303Y305511D02*
X161910Y305118D01*
G01X165670Y313385D02*
X165079Y312795D01*
G01X161502Y316290D02*
X161543Y316268D01*
G01X162520Y313385D02*
X161929Y312795D01*
G01X161482Y315976D02*
X161440Y315933D01*
G01Y316373D02*
X161482Y316415D01*
G01X161912Y316603D02*
X161789Y316457D01*
G01Y316625D02*
X161912Y316771D01*
G01X161461Y316750D02*
X161543Y316687D01*
G01X161605Y315955D02*
X161543Y315871D01*
G01X161605Y316394D02*
X161543Y316311D01*
G01X161482Y316583D02*
X161440Y316625D01*
G01Y316206D02*
X161482Y316164D01*
G01X163465Y313385D02*
X164055Y312795D01*
G01X160315Y313385D02*
X160906Y312795D01*
G01X165118Y304940D02*
X165650Y304409D01*
G01X163681Y305511D02*
X164075Y305118D01*
G01X161969Y304940D02*
X162500Y304409D01*
G01X160532Y305511D02*
X160925Y305118D01*
G01X161625Y316017D02*
X161605Y315955D01*
G01X161502Y316038D02*
X161482Y315976D01*
G01X161625Y316457D02*
X161605Y316394D01*
G01X161482Y316415D02*
X161502Y316478D01*
G01X161605Y316603D02*
X161625Y316541D01*
G01X161502Y316520D02*
X161482Y316583D01*
G01X161605Y316185D02*
X161625Y316122D01*
G01X161482Y316164D02*
X161502Y316101D01*
G01X161543Y316687D02*
X161605Y316603D01*
G01X161543Y316268D02*
X161605Y316185D01*
G01X165355Y305511D02*
Y303543D01*
G01X165079Y311141D02*
Y312795D01*
G01X164055D02*
Y311141D01*
G01X163780Y305511D02*
Y303543D01*
G01X162205Y305511D02*
Y303543D01*
G01X162035Y316771D02*
Y315787D01*
G01X161929Y311141D02*
Y312795D01*
G01X161912Y315787D02*
Y316603D01*
G01X161789Y316457D02*
Y316625D01*
G01X161625Y316122D02*
Y316017D01*
G01Y316541D02*
Y316457D01*
G01X161502Y316478D02*
Y316520D01*
G01Y316101D02*
Y316038D01*
G01X160990Y315913D02*
Y316227D01*
G01Y316646D02*
Y316352D01*
G01X160906Y312795D02*
Y311141D01*
G01X160866Y315787D02*
Y316771D01*
G01X160630Y305511D02*
Y303543D01*
G01X157874Y307086D02*
Y312204D01*
G01Y316929D02*
Y312598D01*
G01X165335Y384125D02*
X164105D01*
G01X153032Y383120D02*
X156969D01*
G01Y382115D02*
X153032D01*
G01Y380104D02*
X156969D01*
G01Y379099D02*
X153032D01*
G01X151063Y375078D02*
X149587D01*
G01X172717D02*
X163859D01*
G01X161890D02*
X160414D01*
G01X163859Y376335D02*
X170748Y382617D01*
G01X160414Y384879D02*
X158937Y383120D01*
G01X165827Y384879D02*
X165335Y384125D01*
G01X164105D02*
X164351Y385130D01*
G01X163859Y375078D02*
Y376335D01*
G01X161890Y386889D02*
Y375078D01*
G01X160414D02*
Y384879D01*
G01X158937Y383120D02*
Y385130D01*
G01X156969Y380104D02*
Y379099D01*
G01Y383120D02*
Y382115D01*
G01X153032Y379099D02*
Y380104D01*
G01Y382115D02*
Y383120D01*
G01X151063Y386889D02*
Y375078D01*
G01X149587Y382115D02*
Y386889D01*
G01Y375078D02*
Y380607D01*
G01X160414Y386889D02*
X161890D01*
G01X149587D02*
X151063D01*
G01X165335Y386135D02*
X166319Y386638D01*
G01X164351Y385130D02*
X165335Y386135D01*
G01X158937Y385130D02*
X160414Y386889D01*
G01X165118Y721909D02*
X285118D01*
G01X217018Y721122D02*
X164331D01*
G01X217018Y716909D02*
X160118D01*
G01X165118Y746909D02*
Y721909D01*
G01X164331Y747696D02*
Y721122D01*
G01X160118Y751909D02*
Y716909D01*
G01X164331Y721122D02*
X165118Y721909D01*
G01X290118Y751909D02*
X160118D01*
G01X285906Y747696D02*
X164331D01*
G01X285118Y746909D02*
X165118D01*
G01X164331Y747696D02*
X165118Y746909D01*
G01X154922Y1001574D02*
X152166D01*
G01X158859D02*
X156103D01*
G01X162796D02*
X160040D01*
G01X166733D02*
X163977D01*
G01D02*
Y1018110D01*
G01X162796D02*
Y1001574D01*
G01X160040D02*
Y1018110D01*
G01X158859D02*
Y1001574D01*
G01X156103D02*
Y1018110D01*
G01X154922D02*
Y1001574D01*
G01X152166D02*
Y1018110D01*
G01X150985D02*
Y1001574D01*
G01X160040Y1018110D02*
X162796D01*
G01X163977D02*
X166733D01*
G01X156103D02*
X158859D01*
G01X152166D02*
X154922D01*
G01X175255Y-24191D02*
Y-26991D01*
G01X173996Y235059D02*
G03X174784Y234271I788J0D01*
G01Y237224D02*
G03X173996Y236437I0J-788D01*
G01X181595Y234271D02*
G03X182382Y235059I0J787D01*
G01X181595Y234271D02*
X174784D01*
G01X173996Y236437D02*
Y235059D01*
G01X182382Y236437D02*
G03X181595Y237224I-787J0D01*
G01X171260Y246082D02*
G03Y242145I0J-1968D01*
G01Y246935D02*
G03Y241293I0J-2821D01*
G01Y247787D02*
G03Y240440I0J-3673D01*
G01X206693Y247787D02*
X171260D01*
G01Y246935D02*
X206693D01*
G01Y246082D02*
X171260D01*
G01X206693Y242145D02*
X171260D01*
G01X206693Y241293D02*
X171260D01*
G01X206693Y240440D02*
X171260D01*
G01X181595Y237224D02*
X174784D01*
G01X171260Y242145D02*
Y240440D01*
G01Y247787D02*
Y246082D01*
G01X168111Y262815D02*
G03X170079I984J0D01*
G01Y271653D02*
Y262815D01*
G01X168111Y267736D02*
Y262815D01*
G01X177365Y277464D02*
X176966D01*
G01X174215D02*
X173817D01*
G01X180514D02*
X180116D01*
G01X171066D02*
X170667D01*
G01X167916D02*
X167518D01*
G01X168800Y286023D02*
X168268D01*
G01X167166D02*
X166634D01*
G01X173465D02*
X172933D01*
G01X171949D02*
X171418D01*
G01X170315D02*
X169784D01*
G01X178248D02*
X177717D01*
G01X176614D02*
X176083D01*
G01X175099D02*
X174567D01*
G01X181398D02*
X180866D01*
G01X179764D02*
X179233D01*
G01X207874Y285196D02*
X170079D01*
G01Y284802D02*
X207874D01*
G01X178452Y284004D02*
X179029D01*
G01X181602D02*
X182178D01*
G01X175303D02*
X175879D01*
G01X169003D02*
X169580D01*
G01X172153D02*
X172729D01*
G01X165854D02*
X166430D01*
G01X167996Y283763D02*
X167438D01*
G01X171146D02*
X170587D01*
G01X174295D02*
X173737D01*
G01X177445D02*
X176887D01*
G01X180594D02*
X180036D01*
G01X166536Y283660D02*
X165748D01*
G01X169685D02*
X168898D01*
G01X172835D02*
X172048D01*
G01X175985D02*
X175197D01*
G01X179134D02*
X178347D01*
G01X182284D02*
X181496D01*
G01X180066Y283564D02*
X180564D01*
G01X173767D02*
X174265D01*
G01X176917D02*
X177414D01*
G01X170618D02*
X171115D01*
G01X167468D02*
X167966D01*
G01X167961Y283539D02*
X167473D01*
G01X171110D02*
X170623D01*
G01X174260D02*
X173772D01*
G01X177409D02*
X176922D01*
G01X180559D02*
X180072D01*
G01X179922Y283505D02*
X180709D01*
G01X176772D02*
X177559D01*
G01X170473D02*
X171260D01*
G01X173622D02*
X174410D01*
G01X167323D02*
X168111D01*
G01Y283323D02*
X167323D01*
G01X171260D02*
X170473D01*
G01X174410D02*
X173622D01*
G01X177559D02*
X176772D01*
G01X180709D02*
X179922D01*
G01Y283182D02*
X180709D01*
G01X176772D02*
X177559D01*
G01X170473D02*
X171260D01*
G01X173622D02*
X174410D01*
G01X167323D02*
X168111D01*
G01Y282965D02*
X167323D01*
G01X171260D02*
X170473D01*
G01X174410D02*
X173622D01*
G01X177559D02*
X176772D01*
G01X180709D02*
X179922D01*
G01X180083Y282665D02*
X180548D01*
G01X173783D02*
X174249D01*
G01X176933D02*
X177398D01*
G01X170634D02*
X171099D01*
G01X167484D02*
X167950D01*
G01X178347Y282635D02*
X179134D01*
G01X181496D02*
X182284D01*
G01X175197D02*
X175985D01*
G01X172048D02*
X172835D01*
G01X165748D02*
X166536D01*
G01X168898D02*
X169685D01*
G01X207874Y282244D02*
X170079D01*
G01X166421Y282210D02*
X165863D01*
G01X169571D02*
X169013D01*
G01X172720D02*
X172162D01*
G01X175870D02*
X175312D01*
G01X179020D02*
X178461D01*
G01X182169D02*
X181611D01*
G01X170079Y281851D02*
X207874D01*
G01X180866Y280118D02*
X181398D01*
G01X179233D02*
X179764D01*
G01X177717D02*
X178248D01*
G01X176083D02*
X176614D01*
G01X174567D02*
X175099D01*
G01X172933D02*
X173465D01*
G01X171418D02*
X171949D01*
G01X169784D02*
X170315D01*
G01X168268D02*
X168800D01*
G01X166634D02*
X167166D01*
G01X170079Y279997D02*
X207874D01*
G01Y279551D02*
X170079D01*
G01X178347Y279285D02*
X179134D01*
G01X181496D02*
X182284D01*
G01X175197D02*
X175985D01*
G01X172048D02*
X172835D01*
G01X165748D02*
X166536D01*
G01X168898D02*
X169685D01*
G01X207874Y279112D02*
X170079D01*
G01Y279059D02*
X207874D01*
G01X168111Y278814D02*
X167323D01*
G01X171260D02*
X170473D01*
G01X174410D02*
X173622D01*
G01X177559D02*
X176772D01*
G01X180709D02*
X179922D01*
G01X207874Y278743D02*
X170079D01*
G01Y278470D02*
X207874D01*
G01X166536Y278002D02*
X165748D01*
G01X169685D02*
X168898D01*
G01X172835D02*
X172048D01*
G01X175985D02*
X175197D01*
G01X179134D02*
X178347D01*
G01X182284D02*
X181496D01*
G01X179979Y277976D02*
X180651D01*
G01X173680D02*
X174352D01*
G01X176829D02*
X177502D01*
G01X170530D02*
X171203D01*
G01X167381D02*
X168053D01*
G01X178347Y277752D02*
X179134D01*
G01X181496D02*
X182284D01*
G01X175197D02*
X175985D01*
G01X172048D02*
X172835D01*
G01X165748D02*
X166536D01*
G01X168898D02*
X169685D01*
G01X180050Y277712D02*
X180581D01*
G01X173750D02*
X174282D01*
G01X176900D02*
X177431D01*
G01X170601D02*
X171132D01*
G01X167451D02*
X167983D01*
G01X167981Y277707D02*
X167452D01*
G01X171131D02*
X170602D01*
G01X174281D02*
X173751D01*
G01X177430D02*
X176901D01*
G01X180580D02*
X180051D01*
G01X166536Y277698D02*
X165748D01*
G01X169685D02*
X168898D01*
G01X172835D02*
X172048D01*
G01X175985D02*
X175197D01*
G01X179134D02*
X178347D01*
G01X182284D02*
X181496D01*
G01X166536Y277671D02*
X165748D01*
G01X169685D02*
X168898D01*
G01X172835D02*
X172048D01*
G01X175985D02*
X175197D01*
G01X179134D02*
X178347D01*
G01X182284D02*
X181496D01*
G01X180118Y277455D02*
X180512D01*
G01X173818D02*
X174213D01*
G01X176968D02*
X177363D01*
G01X170670D02*
X171063D01*
G01X167520D02*
X167914D01*
G01X181398Y276377D02*
X182382D01*
G01X178248D02*
X179233D01*
G01X175099D02*
X176083D01*
G01X171949D02*
X172933D01*
G01X168800D02*
X169784D01*
G01X165650D02*
X166634D01*
G01X180866Y275846D02*
X182914D01*
G01X174567D02*
X176614D01*
G01X177717D02*
X179764D01*
G01X171418D02*
X173465D01*
G01X168268D02*
X170315D01*
G01X170079Y274409D02*
X168504D01*
G01X173229D02*
X171654D01*
G01X179528D02*
X177953D01*
G01X176378D02*
X174803D01*
G01X182677D02*
X181103D01*
G01X207874Y270137D02*
X170079D01*
G01Y269865D02*
X207874D01*
G01X166536Y277824D02*
X165748Y277823D01*
G01X169685Y277824D02*
X168898Y277823D01*
G01X172835Y277824D02*
X172048Y277823D01*
G01X175985Y277824D02*
X175197Y277823D01*
G01X179134Y277824D02*
X178347Y277823D01*
G01X182284Y277824D02*
X181496Y277823D01*
G01X181398Y276377D02*
X180866Y275846D01*
G01X178248Y276377D02*
X177717Y275846D01*
G01X175099Y276377D02*
X174567Y275846D01*
G01X171949Y276377D02*
X171418Y275846D01*
G01X168800Y276377D02*
X168268Y275846D01*
G01X179233Y276377D02*
X179764Y275846D01*
G01X176083Y276377D02*
X176614Y275846D01*
G01X172933Y276377D02*
X173465Y275846D01*
G01X169784Y276377D02*
X170315Y275846D01*
G01X166634Y276377D02*
X167166Y275846D01*
G01X180512Y277455D02*
X180709Y278189D01*
G01X177363Y277455D02*
X177559Y278189D01*
G01X174213Y277455D02*
X174410Y278189D01*
G01X171063Y277455D02*
X171260Y278189D01*
G01X167914Y277455D02*
X168111Y278189D01*
G01X180564Y283564D02*
X180559Y283539D01*
G01X177414Y283564D02*
X177409Y283539D01*
G01X179029Y284004D02*
X179134Y284521D01*
G01X175879Y284004D02*
X175985Y284521D01*
G01X181611Y282210D02*
X181496Y281616D01*
G01X178461Y282210D02*
X178347Y281616D01*
G01X180548Y282665D02*
X180709Y281766D01*
G01X177398Y282665D02*
X177559Y281766D01*
G01X174249Y282665D02*
X174410Y281766D01*
G01X171099Y282665D02*
X171260Y281766D01*
G01X179134Y281616D02*
X179020Y282210D01*
G01X175985Y281616D02*
X175870Y282210D01*
G01X172835Y281616D02*
X172720Y282210D01*
G01X181602Y284004D02*
X181496Y284521D01*
G01X178452Y284004D02*
X178347Y284521D01*
G01X175303Y284004D02*
X175197Y284521D01*
G01X172153Y284004D02*
X172048Y284521D01*
G01X180072Y283539D02*
X180066Y283564D01*
G01X176922Y283539D02*
X176917Y283564D01*
G01X173772Y283539D02*
X173767Y283564D01*
G01X170623Y283539D02*
X170618Y283564D01*
G01X180118Y277455D02*
X179922Y278189D01*
G01X176969Y277455D02*
X176772Y278189D01*
G01X173819Y277455D02*
X173622Y278189D01*
G01X174265Y283564D02*
X174260Y283539D01*
G01X171115Y283564D02*
X171110Y283539D01*
G01X167966Y283564D02*
X167961Y283539D01*
G01X172729Y284004D02*
X172835Y284521D01*
G01X169580Y284004D02*
X169685Y284521D01*
G01X166430Y284004D02*
X166536Y284521D01*
G01X175312Y282210D02*
X175197Y281616D01*
G01X172162Y282210D02*
X172048Y281616D01*
G01X169013Y282210D02*
X168898Y281616D01*
G01X165863Y282210D02*
X165748Y281616D01*
G01X179922Y281766D02*
X180083Y282665D01*
G01X176772Y281766D02*
X176933Y282665D01*
G01X173622Y281766D02*
X173783Y282665D01*
G01X170473Y281766D02*
X170634Y282665D01*
G01X167323Y281766D02*
X167484Y282665D01*
G01X180709Y284919D02*
X180594Y283763D01*
G01X177559Y284919D02*
X177445Y283763D01*
G01X174410Y284919D02*
X174295Y283763D01*
G01X171260Y284919D02*
X171146Y283763D01*
G01X168111Y284919D02*
X167996Y283763D01*
G01X181496Y277671D02*
Y305826D01*
G01X181398Y280118D02*
Y276377D01*
G01Y304409D02*
Y286023D01*
G01X181103Y274409D02*
Y271653D01*
G01X180945Y305255D02*
Y271653D01*
G01X180866Y304940D02*
Y275846D01*
G01X180709Y278189D02*
Y315472D01*
G01X179922Y278189D02*
Y315472D01*
G01X179764Y275846D02*
Y304940D01*
G01X179685Y305255D02*
Y271653D01*
G01X179528Y274409D02*
Y271653D01*
G01X179233Y286023D02*
Y304409D01*
G01Y276377D02*
Y280118D01*
G01X179134Y305826D02*
Y277671D01*
G01X178347D02*
Y305826D01*
G01X178248Y280118D02*
Y276377D01*
G01Y304409D02*
Y286023D01*
G01X177953Y274409D02*
Y271653D01*
G01X177796Y305255D02*
Y271653D01*
G01X177717Y304940D02*
Y275846D01*
G01X177559Y278189D02*
Y315472D01*
G01X176772Y278189D02*
Y315472D01*
G01X176614Y275846D02*
Y304940D01*
G01X176536Y305255D02*
Y271653D01*
G01X176378Y274409D02*
Y271653D01*
G01X176083Y286023D02*
Y304409D01*
G01Y276377D02*
Y280118D01*
G01X175985Y277671D02*
Y305826D01*
G01X175197Y277671D02*
Y305826D01*
G01X175099Y280118D02*
Y276377D01*
G01Y304409D02*
Y286023D01*
G01X174803Y274409D02*
Y271653D01*
G01X174646Y305255D02*
Y271653D01*
G01X174567Y304940D02*
Y275846D01*
G01X174410Y278189D02*
Y315472D01*
G01X173622Y278189D02*
Y315472D01*
G01X173465Y275846D02*
Y304940D01*
G01X173386Y305255D02*
Y271653D01*
G01X173229Y274409D02*
Y271653D01*
G01X172933Y286023D02*
Y304409D01*
G01Y276377D02*
Y280118D01*
G01X172835Y305826D02*
Y277671D01*
G01X172048D02*
Y305826D01*
G01X171949Y280118D02*
Y276377D01*
G01Y304409D02*
Y286023D01*
G01X171654Y274409D02*
Y271653D01*
G01X171496Y305255D02*
Y271653D01*
G01X171418Y304940D02*
Y275846D01*
G01X171260Y278189D02*
Y315472D01*
G01X170473Y278189D02*
Y315472D01*
G01X170315Y275846D02*
Y304940D01*
G01X170237Y305255D02*
Y271653D01*
G01X170079Y274409D02*
Y288846D01*
G01Y274409D02*
Y271653D01*
G01X169784Y286023D02*
Y304409D01*
G01Y276377D02*
Y280118D01*
G01X169685Y305826D02*
Y277671D01*
G01X168898D02*
Y305826D01*
G01X168800Y280118D02*
Y276377D01*
G01Y304409D02*
Y286023D01*
G01X168504Y274409D02*
Y271653D01*
G01X168347Y305255D02*
Y271653D01*
G01X168268Y304940D02*
Y275846D01*
G01X168111Y278189D02*
Y315472D01*
G01X167323Y278189D02*
Y315472D01*
G01X167166Y275846D02*
Y304940D01*
G01X167087Y305255D02*
Y271653D01*
G01X166929Y274409D02*
Y271653D01*
G01X166634Y286023D02*
Y304409D01*
G01Y276377D02*
Y280118D01*
G01X166536Y277671D02*
Y305826D01*
G01X165748Y277671D02*
Y305826D01*
G01X165650Y280118D02*
Y276377D01*
G01Y304409D02*
Y286023D01*
G01X180036Y283763D02*
X179922Y284919D01*
G01X176887Y283763D02*
X176772Y284919D01*
G01X173737Y283763D02*
X173622Y284919D01*
G01X170587Y283763D02*
X170473Y284919D01*
G01X167438Y283763D02*
X167323Y284919D01*
G01X167950Y282665D02*
X168111Y281766D01*
G01X169685Y281616D02*
X169571Y282210D01*
G01X166536Y281616D02*
X166421Y282210D01*
G01X169003Y284004D02*
X168898Y284521D01*
G01X165854Y284004D02*
X165748Y284521D01*
G01X167473Y283539D02*
X167468Y283564D01*
G01X170670Y277455D02*
X170473Y278189D01*
G01X167520Y277455D02*
X167323Y278189D01*
G01X180866Y301574D02*
X181398Y301794D01*
G01X177717Y301574D02*
X178248Y301794D01*
G01X174567Y301574D02*
X175099Y301794D01*
G01X171418Y301574D02*
X171949Y301794D01*
G01X168268Y301574D02*
X168800Y301794D01*
G01X166536Y302401D02*
X165748D01*
G01X169685D02*
X168898D01*
G01X172835D02*
X172048D01*
G01X175985D02*
X175197D01*
G01X179134D02*
X178347D01*
G01X182284D02*
X181496D01*
G01X166536Y302165D02*
X165748D01*
G01X169685D02*
X168898D01*
G01X172835D02*
X172048D01*
G01X175985D02*
X175197D01*
G01X179134D02*
X178347D01*
G01X182284D02*
X181496D01*
G01X179922Y302126D02*
X180709D01*
G01X176772D02*
X177559D01*
G01X170473D02*
X171260D01*
G01X173622D02*
X174410D01*
G01X167323D02*
X168111D01*
G01X179922Y302086D02*
X180709D01*
G01X176772D02*
X177559D01*
G01X170473D02*
X171260D01*
G01X173622D02*
X174410D01*
G01X167323D02*
X168111D01*
G01X166536Y301988D02*
X165748D01*
G01X169685D02*
X168898D01*
G01X172835D02*
X172048D01*
G01X175985D02*
X175197D01*
G01X179134D02*
X178347D01*
G01X182284D02*
X181496D01*
G01X168111Y301847D02*
X167323D01*
G01X171260D02*
X170473D01*
G01X174410D02*
X173622D01*
G01X177559D02*
X176772D01*
G01X180709D02*
X179922D01*
G01X178347Y301811D02*
X179134D01*
G01X181496D02*
X182284D01*
G01X175197D02*
X175985D01*
G01X172048D02*
X172835D01*
G01X165748D02*
X166536D01*
G01X168898D02*
X169685D01*
G01X166536Y301574D02*
X165748D01*
G01X169685D02*
X168898D01*
G01X168268D02*
X167166D01*
G01X172835D02*
X172048D01*
G01X171418D02*
X170315D01*
G01X174567D02*
X173465D01*
G01X175985D02*
X175197D01*
G01X177717D02*
X176614D01*
G01X179134D02*
X178347D01*
G01X182284D02*
X181496D01*
G01X180866D02*
X179764D01*
G01X178248Y301555D02*
X179233D01*
G01X181398D02*
X182382D01*
G01X175099D02*
X176083D01*
G01X171949D02*
X172933D01*
G01X165650D02*
X166634D01*
G01X168800D02*
X169784D01*
G01X178347Y301496D02*
X179134D01*
G01X181496D02*
X182284D01*
G01X175197D02*
X175985D01*
G01X172048D02*
X172835D01*
G01X165748D02*
X166536D01*
G01X168898D02*
X169685D01*
G01X166634Y301240D02*
X165650D01*
G01X169784D02*
X168800D01*
G01X172933D02*
X171949D01*
G01X176083D02*
X175099D01*
G01X179233D02*
X178248D01*
G01X182382D02*
X181398D01*
G01X178347Y301202D02*
X179134D01*
G01X181496D02*
X182284D01*
G01X175197D02*
X175985D01*
G01X172048D02*
X172835D01*
G01X165748D02*
X166536D01*
G01X168898D02*
X169685D01*
G01X166536Y301181D02*
X165748D01*
G01X169685D02*
X168898D01*
G01X172835D02*
X172048D01*
G01X175985D02*
X175197D01*
G01X179134D02*
X178347D01*
G01X182284D02*
X181496D01*
G01X166527Y301141D02*
X165757D01*
G01X169676D02*
X168907D01*
G01X172826D02*
X172057D01*
G01X175975D02*
X175206D01*
G01X179125D02*
X178356D01*
G01X182275D02*
X181505D01*
G01X166536Y301129D02*
X165748D01*
G01X169685D02*
X168898D01*
G01X172835D02*
X172048D01*
G01X175985D02*
X175197D01*
G01X179134D02*
X178347D01*
G01X182284D02*
X181496D01*
G01X178347Y301094D02*
X179134D01*
G01X181496D02*
X182284D01*
G01X175197D02*
X175985D01*
G01X172048D02*
X172835D01*
G01X165748D02*
X166536D01*
G01X168898D02*
X169685D01*
G01X178459Y301039D02*
X179023D01*
G01X181608D02*
X182172D01*
G01X175309D02*
X175873D01*
G01X169010D02*
X169574D01*
G01X172159D02*
X172724D01*
G01X165860D02*
X166424D01*
G01X179922Y301026D02*
X180709D01*
G01X176772D02*
X177559D01*
G01X170473D02*
X171260D01*
G01X173622D02*
X174410D01*
G01X167323D02*
X168111D01*
G01X178347Y301014D02*
X179134D01*
G01X181496D02*
X182284D01*
G01X175197D02*
X175985D01*
G01X172048D02*
X172835D01*
G01X165748D02*
X166536D01*
G01X168898D02*
X169685D01*
G01X168111Y300908D02*
X167323D01*
G01X171260D02*
X170473D01*
G01X174410D02*
X173622D01*
G01X177559D02*
X176772D01*
G01X180709D02*
X179922D01*
G01X168268Y300787D02*
X167166D01*
G01X171418D02*
X170315D01*
G01X174567D02*
X173465D01*
G01X177717D02*
X176614D01*
G01X180866D02*
X179764D01*
G01X166339Y300783D02*
X165945D01*
G01X169488D02*
X169095D01*
G01X172638D02*
X172244D01*
G01X175788D02*
X175394D01*
G01X178937D02*
X178544D01*
G01X182087D02*
X181693D01*
G01X179233Y300000D02*
X181398D01*
G01X176083D02*
X178248D01*
G01X172933D02*
X175099D01*
G01X169784D02*
X171949D01*
G01X166634D02*
X168800D01*
G01X179922Y299753D02*
X180709D01*
G01X176772D02*
X177559D01*
G01X170473D02*
X171260D01*
G01X173622D02*
X174410D01*
G01X167323D02*
X168111D01*
G01X179922Y299731D02*
X180709D01*
G01X176772D02*
X177559D01*
G01X170473D02*
X171260D01*
G01X173622D02*
X174410D01*
G01X167323D02*
X168111D01*
G01Y299477D02*
X167323D01*
G01X171260D02*
X170473D01*
G01X174410D02*
X173622D01*
G01X177559D02*
X176772D01*
G01X180709D02*
X179922D01*
G01X168111Y298818D02*
X167323D01*
G01X171260D02*
X170473D01*
G01X174410D02*
X173622D01*
G01X177559D02*
X176772D01*
G01X180709D02*
X179922D01*
G01X178544Y298626D02*
X178937D01*
G01X181693D02*
X182087D01*
G01X175394D02*
X175788D01*
G01X169095D02*
X169488D01*
G01X172244D02*
X172638D01*
G01X165945D02*
X166339D01*
G01X166424Y298370D02*
X165860D01*
G01X169574D02*
X169010D01*
G01X172724D02*
X172159D01*
G01X175873D02*
X175309D01*
G01X179023D02*
X178459D01*
G01X182172D02*
X181608D01*
G01X178356Y298267D02*
X179125D01*
G01X181505D02*
X182275D01*
G01X175206D02*
X175975D01*
G01X172057D02*
X172826D01*
G01X165757D02*
X166527D01*
G01X168907D02*
X169676D01*
G01X168111Y298228D02*
X167323D01*
G01X166634D02*
X165650D01*
G01X169784D02*
X168800D01*
G01X171260D02*
X170473D01*
G01X174410D02*
X173622D01*
G01X172933D02*
X171949D01*
G01X177559D02*
X176772D01*
G01X176083D02*
X175099D01*
G01X179233D02*
X178248D01*
G01X180709D02*
X179922D01*
G01X182382D02*
X181398D01*
G01X166536Y298015D02*
X165748D01*
G01X169685D02*
X168898D01*
G01X172835D02*
X172048D01*
G01X175985D02*
X175197D01*
G01X179134D02*
X178347D01*
G01X182284D02*
X181496D01*
G01X178248Y297913D02*
X179233D01*
G01X181398D02*
X182382D01*
G01X175099D02*
X176083D01*
G01X171949D02*
X172933D01*
G01X165650D02*
X166634D01*
G01X168800D02*
X169784D01*
G01X168111Y297637D02*
X167323D01*
G01X171260D02*
X170473D01*
G01X174410D02*
X173622D01*
G01X177559D02*
X176772D01*
G01X180709D02*
X179922D01*
G01X178248Y297598D02*
X179233D01*
G01X181398D02*
X182382D01*
G01X175099D02*
X176083D01*
G01X171949D02*
X172933D01*
G01X165650D02*
X166634D01*
G01X168800D02*
X169784D01*
G01X178347Y297582D02*
X179134D01*
G01X181496D02*
X182284D01*
G01X175197D02*
X175985D01*
G01X172048D02*
X172835D01*
G01X165748D02*
X166536D01*
G01X168898D02*
X169685D01*
G01X178347Y297358D02*
X179134D01*
G01X181496D02*
X182284D01*
G01X175197D02*
X175985D01*
G01X172048D02*
X172835D01*
G01X165748D02*
X166536D01*
G01X168898D02*
X169685D01*
G01X179922Y297047D02*
X180709D01*
G01X176772D02*
X177559D01*
G01X170473D02*
X171260D01*
G01X173622D02*
X174410D01*
G01X167323D02*
X168111D01*
G01X166536Y296925D02*
X165748D01*
G01X169685D02*
X168898D01*
G01X172835D02*
X172048D01*
G01X175985D02*
X175197D01*
G01X179134D02*
X178347D01*
G01X182284D02*
X181496D01*
G01X168111Y296456D02*
X167323D01*
G01X171260D02*
X170473D01*
G01X174410D02*
X173622D01*
G01X177559D02*
X176772D01*
G01X180709D02*
X179922D01*
G01X207874Y288846D02*
X170079D01*
G01X207874Y288074D02*
X170079D01*
G01Y288021D02*
X207874D01*
G01X170079Y287582D02*
X207874D01*
G01Y287135D02*
X170079D01*
G01X181505Y298267D02*
X181608Y298370D01*
G01X178356Y298267D02*
X178459Y298370D01*
G01X180866Y300787D02*
X181398Y301318D01*
G01D02*
X180866Y300787D01*
G01X179023Y301039D02*
X179125Y301141D01*
G01X175206Y298267D02*
X175309Y298370D01*
G01X177717Y300787D02*
X178248Y301318D01*
G01D02*
X177717Y300787D01*
G01X175873Y301039D02*
X175975Y301141D01*
G01X172057Y298267D02*
X172159Y298370D01*
G01X174567Y300787D02*
X175099Y301318D01*
G01D02*
X174567Y300787D01*
G01X172724Y301039D02*
X172826Y301141D01*
G01X168907Y298267D02*
X169010Y298370D01*
G01X171418Y300787D02*
X171949Y301318D01*
G01D02*
X171418Y300787D01*
G01X169574Y301039D02*
X169676Y301141D01*
G01X165757Y298267D02*
X165860Y298370D01*
G01X168268Y300787D02*
X168800Y301318D01*
G01D02*
X168268Y300787D01*
G01X166424Y301039D02*
X166527Y301141D01*
G01X179233Y301794D02*
X179764Y301574D01*
G01X176083Y301794D02*
X176614Y301574D01*
G01X172933Y301794D02*
X173465Y301574D01*
G01X169784Y301794D02*
X170315Y301574D01*
G01X166634Y301794D02*
X167166Y301574D01*
G01X181608Y301039D02*
X181505Y301141D01*
G01X179233Y301318D02*
X179764Y300787D01*
G01D02*
X179233Y301318D01*
G01X178459Y301039D02*
X178356Y301141D01*
G01X176083Y301318D02*
X176614Y300787D01*
G01D02*
X176083Y301318D01*
G01X179023Y298370D02*
X179125Y298267D01*
G01X175309Y301039D02*
X175206Y301141D01*
G01X172933Y301318D02*
X173465Y300787D01*
G01D02*
X172933Y301318D01*
G01X175873Y298370D02*
X175975Y298267D01*
G01X172159Y301039D02*
X172057Y301141D01*
G01X169784Y301318D02*
X170315Y300787D01*
G01D02*
X169784Y301318D01*
G01X172724Y298370D02*
X172826Y298267D01*
G01X169010Y301039D02*
X168907Y301141D01*
G01X166634Y301318D02*
X167166Y300787D01*
G01D02*
X166634Y301318D01*
G01X169574Y298370D02*
X169676Y298267D01*
G01X165860Y301039D02*
X165757Y301141D01*
G01X166424Y298370D02*
X166527Y298267D01*
G01X181693Y298626D02*
Y300783D01*
G01X180807Y305118D02*
Y295748D01*
G01X179823Y305118D02*
Y295748D01*
G01X178937Y300783D02*
Y298626D01*
G01X178544D02*
Y300783D01*
G01X177658Y305118D02*
Y295748D01*
G01X176674Y305118D02*
Y295748D01*
G01X175788Y300783D02*
Y298626D01*
G01X175394D02*
Y300783D01*
G01X174508Y305118D02*
Y295748D01*
G01X173524Y305118D02*
Y295748D01*
G01X172638Y300783D02*
Y298626D01*
G01X172244D02*
Y300783D01*
G01X171359Y305118D02*
Y295748D01*
G01X170374Y305118D02*
Y295748D01*
G01X169488Y300783D02*
Y298626D01*
G01X169095D02*
Y300783D01*
G01X168209Y305118D02*
Y295748D01*
G01X167225Y305118D02*
Y295748D01*
G01X166339Y300783D02*
Y298626D01*
G01X165945D02*
Y300783D01*
G01X168111Y315472D02*
X167323D01*
G01X171260D02*
X170473D01*
G01X174410D02*
X173622D01*
G01X177559D02*
X176772D01*
G01X180709D02*
X179922D01*
G01X168111Y314881D02*
X167323D01*
G01X171260D02*
X170473D01*
G01X174410D02*
X173622D01*
G01X177559D02*
X176772D01*
G01X180709D02*
X179922D01*
G01Y313976D02*
X180709D01*
G01X176772D02*
X177559D01*
G01X170473D02*
X171260D01*
G01X173622D02*
X174410D01*
G01X167323D02*
X168111D01*
G01X181418Y313385D02*
X182363D01*
G01X178268D02*
X179213D01*
G01X175118D02*
X176063D01*
G01X171969D02*
X172914D01*
G01X168819D02*
X169764D01*
G01X165670D02*
X166614D01*
G01X168111D02*
X167323D01*
G01X171260D02*
X170473D01*
G01X174410D02*
X173622D01*
G01X177559D02*
X176772D01*
G01X180709D02*
X179922D01*
G01X168111Y312677D02*
X167323D01*
G01X171260D02*
X170473D01*
G01X174410D02*
X173622D01*
G01X177559D02*
X176772D01*
G01X180709D02*
X179922D01*
G01X168111Y311732D02*
X167323D01*
G01X171260D02*
X170473D01*
G01X174410D02*
X173622D01*
G01X177559D02*
X176772D01*
G01X180709D02*
X179922D01*
G01X179803Y311141D02*
X180827D01*
G01X176654D02*
X177677D01*
G01X173504D02*
X174528D01*
G01X170355D02*
X171378D01*
G01X167205D02*
X168229D01*
G01X179922Y310551D02*
X180709D01*
G01X176772D02*
X177559D01*
G01X170473D02*
X171260D01*
G01X173622D02*
X174410D01*
G01X167323D02*
X168111D01*
G01Y306102D02*
X167323D01*
G01X171260D02*
X170473D01*
G01X174410D02*
X173622D01*
G01X177559D02*
X176772D01*
G01X180709D02*
X179922D01*
G01X166536Y305826D02*
X165748D01*
G01X169685D02*
X168898D01*
G01X172835D02*
X172048D01*
G01X175985D02*
X175197D01*
G01X179134D02*
X178347D01*
G01X182284D02*
X181496D01*
G01X166536Y305236D02*
X165748D01*
G01X169685D02*
X168898D01*
G01X172835D02*
X172048D01*
G01X175985D02*
X175197D01*
G01X179134D02*
X178347D01*
G01X182284D02*
X181496D01*
G01X168209Y305118D02*
X167225D01*
G01X171359D02*
X170374D01*
G01X174508D02*
X173524D01*
G01X177658D02*
X176674D01*
G01X180807D02*
X179823D01*
G01X170315Y304940D02*
X168268D01*
G01X173465D02*
X171418D01*
G01X176614D02*
X174567D01*
G01X179764D02*
X177717D01*
G01X182914D02*
X180866D01*
G01X168111Y304921D02*
X167323D01*
G01X171260D02*
X170473D01*
G01X174410D02*
X173622D01*
G01X177559D02*
X176772D01*
G01X180709D02*
X179922D01*
G01X166634Y304409D02*
X165650D01*
G01X169784D02*
X168800D01*
G01X172933D02*
X171949D01*
G01X176083D02*
X175099D01*
G01X179233D02*
X178248D01*
G01X182382D02*
X181398D01*
G01X166536Y304330D02*
X165748D01*
G01X169685D02*
X168898D01*
G01X172835D02*
X172048D01*
G01X175985D02*
X175197D01*
G01X179134D02*
X178347D01*
G01X182284D02*
X181496D01*
G01X179922Y304133D02*
X180709D01*
G01X176772D02*
X177559D01*
G01X170473D02*
X171260D01*
G01X173622D02*
X174410D01*
G01X167323D02*
X168111D01*
G01X178347Y304094D02*
X179134D01*
G01X181496D02*
X182284D01*
G01X175197D02*
X175985D01*
G01X172048D02*
X172835D01*
G01X165748D02*
X166536D01*
G01X168898D02*
X169685D01*
G01X168111Y304015D02*
X167323D01*
G01X171260D02*
X170473D01*
G01X174410D02*
X173622D01*
G01X177559D02*
X176772D01*
G01X180709D02*
X179922D01*
G01X166536Y303917D02*
X165748D01*
G01X169685D02*
X168898D01*
G01X172835D02*
X172048D01*
G01X175985D02*
X175197D01*
G01X179134D02*
X178347D01*
G01X182284D02*
X181496D01*
G01X168504Y303543D02*
X166929D01*
G01X166536D02*
X165748D01*
G01X169685D02*
X168898D01*
G01X174803D02*
X173229D01*
G01X171654D02*
X170079D01*
G01X172835D02*
X172048D01*
G01X177953D02*
X176378D01*
G01X175985D02*
X175197D01*
G01X181103D02*
X179528D01*
G01X179134D02*
X178347D01*
G01X182284D02*
X181496D01*
G01X166536Y303503D02*
X165748D01*
G01X169685D02*
X168898D01*
G01X172835D02*
X172048D01*
G01X175985D02*
X175197D01*
G01X179134D02*
X178347D01*
G01X182284D02*
X181496D01*
G01X181201Y305511D02*
X180807Y305118D01*
G01X179233Y304409D02*
X179764Y304940D01*
G01X178051Y305511D02*
X177658Y305118D01*
G01X176083Y304409D02*
X176614Y304940D01*
G01X174902Y305511D02*
X174508Y305118D01*
G01X172933Y304409D02*
X173465Y304940D01*
G01X181418Y313385D02*
X180827Y312795D01*
G01X171752Y305511D02*
X171359Y305118D01*
G01X169784Y304409D02*
X170315Y304940D01*
G01X178268Y313385D02*
X177677Y312795D01*
G01X168603Y305511D02*
X168209Y305118D01*
G01X166634Y304409D02*
X167166Y304940D01*
G01X175118Y313385D02*
X174528Y312795D01*
G01X171969Y313385D02*
X171378Y312795D01*
G01X168819Y313385D02*
X168229Y312795D01*
G01X179213Y313385D02*
X179803Y312795D01*
G01X176063Y313385D02*
X176654Y312795D01*
G01X172914Y313385D02*
X173504Y312795D01*
G01X180866Y304940D02*
X181398Y304409D01*
G01X179429Y305511D02*
X179823Y305118D01*
G01X169764Y313385D02*
X170355Y312795D01*
G01X177717Y304940D02*
X178248Y304409D01*
G01X176280Y305511D02*
X176674Y305118D01*
G01X166614Y313385D02*
X167205Y312795D01*
G01X174567Y304940D02*
X175099Y304409D01*
G01X173130Y305511D02*
X173524Y305118D01*
G01X171418Y304940D02*
X171949Y304409D01*
G01X169981Y305511D02*
X170374Y305118D01*
G01X168268Y304940D02*
X168800Y304409D01*
G01X166831Y305511D02*
X167225Y305118D01*
G01X181103Y305511D02*
Y303543D01*
G01X180827Y311141D02*
Y312795D01*
G01X179803D02*
Y311141D01*
G01X179528Y305511D02*
Y303543D01*
G01X177953Y305511D02*
Y303543D01*
G01X177677Y311141D02*
Y312795D01*
G01X176654D02*
Y311141D01*
G01X176378Y305511D02*
Y303543D01*
G01X174803Y305511D02*
Y303543D01*
G01X174528Y311141D02*
Y312795D01*
G01X173504D02*
Y311141D01*
G01X173229Y305511D02*
Y303543D01*
G01X171654Y305511D02*
Y303543D01*
G01X171378Y311141D02*
Y312795D01*
G01X170355D02*
Y311141D01*
G01X170079Y305511D02*
Y303543D01*
G01X168504Y305511D02*
Y303543D01*
G01X168229Y311141D02*
Y312795D01*
G01X167205D02*
Y311141D01*
G01X166929Y305511D02*
Y303543D01*
G01X181083Y383120D02*
X182067D01*
G01X174685D02*
X175916D01*
G01X177146D02*
X178130D01*
G01X177638Y382115D02*
X177146D01*
G01X181575D02*
X180837D01*
G01X165827Y376335D02*
X172717D01*
G01X175916Y375078D02*
X174685D01*
G01X179853D02*
X178622D01*
G01X180345Y382868D02*
X181083Y383120D01*
G01X177146Y382115D02*
X176408Y381863D01*
G01Y382868D02*
X177146Y383120D01*
G01X178130D02*
X178868Y382868D01*
G01X180837Y382115D02*
X180345Y381863D01*
G01X182067D02*
X181575Y382115D01*
G01X178130Y381863D02*
X177638Y382115D01*
G01X171979Y381863D02*
X165827Y376335D01*
G01X180345Y381863D02*
X180099Y381612D01*
G01X179607Y382115D02*
X180345Y382868D01*
G01X176408Y381863D02*
X175916Y381361D01*
G01Y382366D02*
X176408Y382868D01*
G01X178868D02*
X179607Y382115D01*
G01X178376Y381612D02*
X178130Y381863D01*
G01X172471Y382617D02*
X171979Y381863D01*
G01X171240Y384125D02*
X170748Y384879D01*
G01X180099Y381612D02*
X179853Y381109D01*
G01X170748Y382617D02*
X171240Y383622D01*
G01X172471Y385130D02*
X172717Y384125D01*
G01X178622Y381109D02*
X178376Y381612D01*
G01X172717Y383622D02*
X172471Y382617D01*
G01X179853Y381109D02*
Y375078D01*
G01X178622D02*
Y381109D01*
G01X175916Y383120D02*
Y382366D01*
G01Y381361D02*
Y375078D01*
G01X174685D02*
Y383120D01*
G01X172717Y376335D02*
Y375078D01*
G01Y384125D02*
Y383622D01*
G01X171240D02*
Y384125D01*
G01X166319Y386638D02*
X168042Y386889D01*
G01X167796Y385633D02*
X166565Y385381D01*
G01X168042Y386889D02*
X169026D01*
G01X168780Y385633D02*
X167796D01*
G01X170010Y385381D02*
X168780Y385633D01*
G01X169026Y386889D02*
X170502Y386638D01*
G01D02*
X171487Y386135D01*
G01X166565Y385381D02*
X165827Y384879D01*
G01X170748D02*
X170010Y385381D01*
G01X171487Y386135D02*
X172471Y385130D01*
G01X182363Y729409D02*
G03I-2245J0D01*
G01X179875Y724853D02*
X179670Y724811D01*
G01X179368Y728659D02*
X180868D01*
G01X178868Y728159D02*
X181368D01*
G01X180777Y725900D02*
X181023D01*
G01X178686D02*
X179670D01*
G01X179711Y725691D02*
X178932D01*
G01Y725063D02*
X179711D01*
G01X179670Y724811D02*
X178932D01*
G01X181023Y723932D02*
X180777D01*
G01X178932D02*
X178686D01*
G01X176622Y722909D02*
X273614D01*
G01X172122D02*
X166122D01*
G01X176622Y718909D02*
X166122D01*
G01X179670Y725900D02*
X179875Y725858D01*
G01X179834Y725649D02*
X179711Y725691D01*
G01X179875Y725858D02*
X180039Y725733D01*
G01X179916Y725565D02*
X179834Y725649D01*
G01X180868Y728659D02*
X181368Y728159D01*
G01X180039Y725733D02*
X180162Y725565D01*
G01D02*
X180203Y725439D01*
G01X179957D02*
X179916Y725565D01*
G01X179711Y725063D02*
X179834Y725104D01*
G01X181368Y728159D02*
Y730659D01*
G01X181023Y725900D02*
Y723932D01*
G01X180868Y728659D02*
Y730159D01*
G01X180777Y723932D02*
Y725565D01*
G01X180531Y725272D02*
Y725607D01*
G01X180203Y725439D02*
Y725272D01*
G01X179957Y725314D02*
Y725439D01*
G01X179368Y730159D02*
Y728659D01*
G01X178932Y724811D02*
Y723932D01*
G01Y725691D02*
Y725063D01*
G01X178868Y730659D02*
Y728159D01*
G01X178686Y723932D02*
Y725900D01*
G01X176622Y745909D02*
Y718909D01*
G01X172122Y745909D02*
Y722909D01*
G01X166122Y718909D02*
Y745909D01*
G01X180039Y724979D02*
X179875Y724853D01*
G01X179368Y728659D02*
X178868Y728159D01*
G01X179834Y725104D02*
X179916Y725188D01*
G01X180777Y725565D02*
X180531Y725272D01*
G01Y725607D02*
X180777Y725900D01*
G01X180162Y725146D02*
X180039Y724979D01*
G01X180203Y725272D02*
X180162Y725146D01*
G01X179916Y725188D02*
X179957Y725314D01*
G01X182363Y739409D02*
G03I-2245J0D01*
G01X166122Y745909D02*
X284114D01*
G01X181368Y740659D02*
X178868D01*
G01X180868Y740159D02*
X179368D01*
G01Y738659D02*
X180868D01*
G01X178868Y738159D02*
X181368D01*
G01X273614Y735909D02*
X176622D01*
G01X273614Y732909D02*
X176622D01*
G01X181368Y730659D02*
X178868D01*
G01X180868Y730159D02*
X179368D01*
G01Y740159D02*
X178868Y740659D01*
G01X180868Y738659D02*
X181368Y738159D01*
G01X179368Y730159D02*
X178868Y730659D01*
G01X181368Y738159D02*
Y740659D01*
G01X180868Y738659D02*
Y740159D01*
G01X179368D02*
Y738659D01*
G01X178868Y740659D02*
Y738159D01*
G01X180868Y730159D02*
X181368Y730659D01*
G01X180868Y740159D02*
X181368Y740659D01*
G01X179368Y738659D02*
X178868Y738159D01*
G01X170670Y1001574D02*
X167914D01*
G01X174607D02*
X171851D01*
G01X178544D02*
X175788D01*
G01X182481D02*
X179725D01*
G01D02*
Y1018110D01*
G01X178544D02*
Y1001574D01*
G01X175788D02*
Y1018110D01*
G01X174607D02*
Y1001574D01*
G01X171851D02*
Y1018110D01*
G01X170670D02*
Y1001574D01*
G01X167914D02*
Y1018110D01*
G01X166733D02*
Y1001574D01*
G01X179725Y1018110D02*
X182481D01*
G01X175788D02*
X178544D01*
G01X171851D02*
X174607D01*
G01X167914D02*
X170670D01*
G01X195571Y235059D02*
G03X196359Y234271I788J0D01*
G01Y237224D02*
G03X195571Y236437I-1J-787D01*
G01X203170Y234271D02*
X196359D01*
G01X195571Y236437D02*
Y235059D01*
G01X182382Y236437D02*
Y235059D01*
G01X203170Y237224D02*
X196359D01*
G01X196263Y277464D02*
X195864D01*
G01X193113D02*
X192714D01*
G01X189963D02*
X189565D01*
G01X186814D02*
X186415D01*
G01X183664D02*
X183266D01*
G01X182914Y286023D02*
X182382D01*
G01X187697D02*
X187166D01*
G01X186063D02*
X185532D01*
G01X184548D02*
X184016D01*
G01X192363D02*
X191831D01*
G01X190847D02*
X190315D01*
G01X189213D02*
X188681D01*
G01X197146D02*
X196614D01*
G01X195512D02*
X194981D01*
G01X193996D02*
X193465D01*
G01X198662D02*
X198130D01*
G01X197350Y284004D02*
X197926D01*
G01X194200D02*
X194777D01*
G01X187901D02*
X188477D01*
G01X191051D02*
X191627D01*
G01X184751D02*
X185328D01*
G01X183744Y283763D02*
X183186D01*
G01X186894D02*
X186335D01*
G01X190043D02*
X189485D01*
G01X193193D02*
X192635D01*
G01X196342D02*
X195784D01*
G01X185433Y283660D02*
X184646D01*
G01X188583D02*
X187796D01*
G01X191733D02*
X190945D01*
G01X194882D02*
X194095D01*
G01X198032D02*
X197244D01*
G01X192665Y283564D02*
X193163D01*
G01X195814D02*
X196312D01*
G01X189515D02*
X190013D01*
G01X183216D02*
X183714D01*
G01X186366D02*
X186863D01*
G01X183709Y283539D02*
X183221D01*
G01X186858D02*
X186371D01*
G01X190008D02*
X189520D01*
G01X193157D02*
X192670D01*
G01X196307D02*
X195820D01*
G01X192520Y283505D02*
X193307D01*
G01X195670D02*
X196457D01*
G01X189370D02*
X190158D01*
G01X183071D02*
X183859D01*
G01X186221D02*
X187008D01*
G01X183859Y283323D02*
X183071D01*
G01X187008D02*
X186221D01*
G01X190158D02*
X189370D01*
G01X193307D02*
X192520D01*
G01X196457D02*
X195670D01*
G01X192520Y283182D02*
X193307D01*
G01X195670D02*
X196457D01*
G01X189370D02*
X190158D01*
G01X183071D02*
X183859D01*
G01X186221D02*
X187008D01*
G01X183859Y282965D02*
X183071D01*
G01X187008D02*
X186221D01*
G01X190158D02*
X189370D01*
G01X193307D02*
X192520D01*
G01X196457D02*
X195670D01*
G01X192681Y282665D02*
X193146D01*
G01X195831D02*
X196296D01*
G01X189531D02*
X189997D01*
G01X183232D02*
X183698D01*
G01X186382D02*
X186847D01*
G01X197244Y282635D02*
X198032D01*
G01X194095D02*
X194882D01*
G01X187796D02*
X188583D01*
G01X190945D02*
X191733D01*
G01X184646D02*
X185433D01*
G01X185319Y282210D02*
X184761D01*
G01X188468D02*
X187910D01*
G01X191618D02*
X191060D01*
G01X194768D02*
X194209D01*
G01X197917D02*
X197359D01*
G01X198130Y280118D02*
X198662D01*
G01X196614D02*
X197146D01*
G01X194981D02*
X195512D01*
G01X193465D02*
X193996D01*
G01X191831D02*
X192363D01*
G01X190315D02*
X190847D01*
G01X188681D02*
X189213D01*
G01X187166D02*
X187697D01*
G01X185532D02*
X186063D01*
G01X184016D02*
X184548D01*
G01X182382D02*
X182914D01*
G01X197244Y279285D02*
X198032D01*
G01X194095D02*
X194882D01*
G01X187796D02*
X188583D01*
G01X190945D02*
X191733D01*
G01X184646D02*
X185433D01*
G01X183859Y278814D02*
X183071D01*
G01X187008D02*
X186221D01*
G01X190158D02*
X189370D01*
G01X193307D02*
X192520D01*
G01X196457D02*
X195670D01*
G01X185433Y278002D02*
X184646D01*
G01X188583D02*
X187796D01*
G01X191733D02*
X190945D01*
G01X194882D02*
X194095D01*
G01X198032D02*
X197244D01*
G01X192577Y277976D02*
X193250D01*
G01X195727D02*
X196400D01*
G01X189428D02*
X190100D01*
G01X183129D02*
X183801D01*
G01X186278D02*
X186951D01*
G01X197244Y277752D02*
X198032D01*
G01X194095D02*
X194882D01*
G01X187796D02*
X188583D01*
G01X190945D02*
X191733D01*
G01X184646D02*
X185433D01*
G01X192648Y277712D02*
X193179D01*
G01X195798D02*
X196329D01*
G01X189498D02*
X190030D01*
G01X183199D02*
X183731D01*
G01X186349D02*
X186880D01*
G01X183729Y277707D02*
X183200D01*
G01X186879D02*
X186350D01*
G01X190029D02*
X189500D01*
G01X193178D02*
X192649D01*
G01X196328D02*
X195799D01*
G01X185433Y277698D02*
X184646D01*
G01X188583D02*
X187796D01*
G01X191733D02*
X190945D01*
G01X194882D02*
X194095D01*
G01X198032D02*
X197244D01*
G01X185433Y277671D02*
X184646D01*
G01X188583D02*
X187796D01*
G01X191733D02*
X190945D01*
G01X194882D02*
X194095D01*
G01X198032D02*
X197244D01*
G01X192717Y277455D02*
X193111D01*
G01X195866D02*
X196260D01*
G01X189567D02*
X189961D01*
G01X183268D02*
X183662D01*
G01X186418D02*
X186811D01*
G01X197146Y276377D02*
X198130D01*
G01X193996D02*
X194981D01*
G01X190847D02*
X191831D01*
G01X187697D02*
X188681D01*
G01X184548D02*
X185532D01*
G01X193465Y275846D02*
X195512D01*
G01X196614D02*
X198662D01*
G01X190315D02*
X192363D01*
G01X184016D02*
X186063D01*
G01X187166D02*
X189213D01*
G01X188977Y274409D02*
X187402D01*
G01X185827D02*
X184252D01*
G01X192126D02*
X190551D01*
G01X198425D02*
X196851D01*
G01X195276D02*
X193701D01*
G01X185433Y277824D02*
X184646Y277823D01*
G01X188583Y277824D02*
X187796Y277823D01*
G01X191733Y277824D02*
X190945Y277823D01*
G01X194882Y277824D02*
X194095Y277823D01*
G01X198032Y277824D02*
X197244Y277823D01*
G01X197146Y276377D02*
X196614Y275846D01*
G01X193996Y276377D02*
X193465Y275846D01*
G01X190847Y276377D02*
X190315Y275846D01*
G01X187697Y276377D02*
X187166Y275846D01*
G01X184548Y276377D02*
X184016Y275846D01*
G01X198130Y276377D02*
X198662Y275846D01*
G01X194981Y276377D02*
X195512Y275846D01*
G01X191831Y276377D02*
X192363Y275846D01*
G01X188681Y276377D02*
X189213Y275846D01*
G01X185532Y276377D02*
X186063Y275846D01*
G01X182382Y276377D02*
X182914Y275846D01*
G01X196260Y277455D02*
X196457Y278189D01*
G01X193111Y277455D02*
X193307Y278189D01*
G01X189961Y277455D02*
X190158Y278189D01*
G01X186811Y277455D02*
X187008Y278189D01*
G01X183662Y277455D02*
X183859Y278189D01*
G01X196312Y283564D02*
X196307Y283539D01*
G01X193163Y283564D02*
X193157Y283539D01*
G01X190013Y283564D02*
X190008Y283539D01*
G01X186863Y283564D02*
X186858Y283539D01*
G01X183714Y283564D02*
X183709Y283539D01*
G01X197926Y284004D02*
X198032Y284521D01*
G01X194777Y284004D02*
X194882Y284521D01*
G01X191627Y284004D02*
X191733Y284521D01*
G01X188477Y284004D02*
X188583Y284521D01*
G01X185328Y284004D02*
X185433Y284521D01*
G01X182178Y284004D02*
X182284Y284521D01*
G01X197359Y282210D02*
X197244Y281616D01*
G01X194209Y282210D02*
X194095Y281616D01*
G01X191060Y282210D02*
X190945Y281616D01*
G01X187910Y282210D02*
X187796Y281616D01*
G01X184761Y282210D02*
X184646Y281616D01*
G01X195670Y281766D02*
X195831Y282665D01*
G01X192520Y281766D02*
X192681Y282665D01*
G01X189370Y281766D02*
X189531Y282665D01*
G01X186221Y281766D02*
X186382Y282665D01*
G01X183071Y281766D02*
X183232Y282665D01*
G01X196296D02*
X196457Y281766D01*
G01X193146Y282665D02*
X193307Y281766D01*
G01X189997Y282665D02*
X190158Y281766D01*
G01X186847Y282665D02*
X187008Y281766D01*
G01X183698Y282665D02*
X183859Y281766D01*
G01X198032Y281616D02*
X197917Y282210D01*
G01X194882Y281616D02*
X194768Y282210D01*
G01X191733Y281616D02*
X191618Y282210D01*
G01X188583Y281616D02*
X188468Y282210D01*
G01X185433Y281616D02*
X185319Y282210D01*
G01X182284Y281616D02*
X182169Y282210D01*
G01X197350Y284004D02*
X197244Y284521D01*
G01X194200Y284004D02*
X194095Y284521D01*
G01X191051Y284004D02*
X190945Y284521D01*
G01X187901Y284004D02*
X187796Y284521D01*
G01X184751Y284004D02*
X184646Y284521D01*
G01X195820Y283539D02*
X195814Y283564D01*
G01X192670Y283539D02*
X192665Y283564D01*
G01X189520Y283539D02*
X189515Y283564D01*
G01X186371Y283539D02*
X186366Y283564D01*
G01X183221Y283539D02*
X183216Y283564D01*
G01X195866Y277455D02*
X195670Y278189D01*
G01X192717Y277455D02*
X192520Y278189D01*
G01X189567Y277455D02*
X189370Y278189D01*
G01X186418Y277455D02*
X186221Y278189D01*
G01X183268Y277455D02*
X183071Y278189D01*
G01X196457Y284919D02*
X196342Y283763D01*
G01X193307Y284919D02*
X193193Y283763D01*
G01X190158Y284919D02*
X190043Y283763D01*
G01X187008Y284919D02*
X186894Y283763D01*
G01X183859Y284919D02*
X183744Y283763D01*
G01X198130Y286023D02*
Y304409D01*
G01Y276377D02*
Y280118D01*
G01X198032Y305826D02*
Y277671D01*
G01X197244D02*
Y305826D01*
G01X197146Y280118D02*
Y276377D01*
G01Y304409D02*
Y286023D01*
G01X196851Y274409D02*
Y271653D01*
G01X196693Y305255D02*
Y271653D01*
G01X196614Y304940D02*
Y275846D01*
G01X196457Y278189D02*
Y315472D01*
G01X195670Y278189D02*
Y315472D01*
G01X195512Y275846D02*
Y304940D01*
G01X195433Y305255D02*
Y271653D01*
G01X195276Y274409D02*
Y271653D01*
G01X194981Y286023D02*
Y304409D01*
G01Y276377D02*
Y280118D01*
G01X194882Y305826D02*
Y277671D01*
G01X194095D02*
Y305826D01*
G01X193996Y280118D02*
Y276377D01*
G01Y304409D02*
Y286023D01*
G01X193701Y274409D02*
Y271653D01*
G01X193544Y305255D02*
Y271653D01*
G01X193465Y304940D02*
Y275846D01*
G01X193307Y278189D02*
Y315472D01*
G01X192520Y278189D02*
Y315472D01*
G01X192363Y275846D02*
Y304940D01*
G01X192284Y305255D02*
Y271653D01*
G01X192126Y274409D02*
Y271653D01*
G01X191831Y286023D02*
Y304409D01*
G01Y276377D02*
Y280118D01*
G01X191733Y305826D02*
Y277671D01*
G01X190945D02*
Y305826D01*
G01X190847Y280118D02*
Y276377D01*
G01Y304409D02*
Y286023D01*
G01X190551Y274409D02*
Y271653D01*
G01X190394Y305255D02*
Y271653D01*
G01X190315Y304940D02*
Y275846D01*
G01X190158Y278189D02*
Y315472D01*
G01X189370Y278189D02*
Y315472D01*
G01X189213Y275846D02*
Y304940D01*
G01X189134Y305255D02*
Y271653D01*
G01X188977Y274409D02*
Y271653D01*
G01X188681Y286023D02*
Y304409D01*
G01Y276377D02*
Y280118D01*
G01X188583Y305826D02*
Y277671D01*
G01X187796D02*
Y305826D01*
G01X187697Y280118D02*
Y276377D01*
G01Y304409D02*
Y286023D01*
G01X187402Y274409D02*
Y271653D01*
G01X187244Y305255D02*
Y271653D01*
G01X187166Y304940D02*
Y275846D01*
G01X187008Y278189D02*
Y315472D01*
G01X186221Y278189D02*
Y315472D01*
G01X186063Y275846D02*
Y304940D01*
G01X185985Y305255D02*
Y271653D01*
G01X185827Y274409D02*
Y271653D01*
G01X185532Y286023D02*
Y304409D01*
G01Y276377D02*
Y280118D01*
G01X185433Y277671D02*
Y305826D01*
G01X184646Y277671D02*
Y305826D01*
G01X184548Y280118D02*
Y276377D01*
G01Y304409D02*
Y286023D01*
G01X184252Y274409D02*
Y271653D01*
G01X184095Y305255D02*
Y271653D01*
G01X184016Y304940D02*
Y275846D01*
G01X183859Y278189D02*
Y315472D01*
G01X183071Y278189D02*
Y315472D01*
G01X182914Y275846D02*
Y304940D01*
G01X182835Y305255D02*
Y271653D01*
G01X182677Y274409D02*
Y271653D01*
G01X182382Y286023D02*
Y304409D01*
G01Y276377D02*
Y280118D01*
G01X182284Y305826D02*
Y277671D01*
G01X195784Y283763D02*
X195670Y284919D01*
G01X192635Y283763D02*
X192520Y284919D01*
G01X189485Y283763D02*
X189370Y284919D01*
G01X186335Y283763D02*
X186221Y284919D01*
G01X183186Y283763D02*
X183071Y284919D01*
G01X196614Y301574D02*
X197146Y301794D01*
G01X193465Y301574D02*
X193996Y301794D01*
G01X190315Y301574D02*
X190847Y301794D01*
G01X187166Y301574D02*
X187697Y301794D01*
G01X184016Y301574D02*
X184548Y301794D01*
G01X185433Y302401D02*
X184646D01*
G01X188583D02*
X187796D01*
G01X191733D02*
X190945D01*
G01X194882D02*
X194095D01*
G01X198032D02*
X197244D01*
G01X185433Y302165D02*
X184646D01*
G01X188583D02*
X187796D01*
G01X191733D02*
X190945D01*
G01X194882D02*
X194095D01*
G01X198032D02*
X197244D01*
G01X192520Y302126D02*
X193307D01*
G01X195670D02*
X196457D01*
G01X189370D02*
X190158D01*
G01X183071D02*
X183859D01*
G01X186221D02*
X187008D01*
G01X192520Y302086D02*
X193307D01*
G01X195670D02*
X196457D01*
G01X189370D02*
X190158D01*
G01X183071D02*
X183859D01*
G01X186221D02*
X187008D01*
G01X185433Y301988D02*
X184646D01*
G01X188583D02*
X187796D01*
G01X191733D02*
X190945D01*
G01X194882D02*
X194095D01*
G01X198032D02*
X197244D01*
G01X183859Y301847D02*
X183071D01*
G01X187008D02*
X186221D01*
G01X190158D02*
X189370D01*
G01X193307D02*
X192520D01*
G01X196457D02*
X195670D01*
G01X197244Y301811D02*
X198032D01*
G01X194095D02*
X194882D01*
G01X187796D02*
X188583D01*
G01X190945D02*
X191733D01*
G01X184646D02*
X185433D01*
G01X184016Y301574D02*
X182914D01*
G01X185433D02*
X184646D01*
G01X187166D02*
X186063D01*
G01X188583D02*
X187796D01*
G01X191733D02*
X190945D01*
G01X190315D02*
X189213D01*
G01X193465D02*
X192363D01*
G01X194882D02*
X194095D01*
G01X196614D02*
X195512D01*
G01X198032D02*
X197244D01*
G01X197146Y301555D02*
X198130D01*
G01X193996D02*
X194981D01*
G01X187697D02*
X188681D01*
G01X190847D02*
X191831D01*
G01X184548D02*
X185532D01*
G01X197244Y301496D02*
X198032D01*
G01X194095D02*
X194882D01*
G01X187796D02*
X188583D01*
G01X190945D02*
X191733D01*
G01X184646D02*
X185433D01*
G01X185532Y301240D02*
X184548D01*
G01X188681D02*
X187697D01*
G01X191831D02*
X190847D01*
G01X194981D02*
X193996D01*
G01X198130D02*
X197146D01*
G01X197244Y301202D02*
X198032D01*
G01X194095D02*
X194882D01*
G01X187796D02*
X188583D01*
G01X190945D02*
X191733D01*
G01X184646D02*
X185433D01*
G01Y301181D02*
X184646D01*
G01X188583D02*
X187796D01*
G01X191733D02*
X190945D01*
G01X194882D02*
X194095D01*
G01X198032D02*
X197244D01*
G01X185424Y301141D02*
X184655D01*
G01X188574D02*
X187805D01*
G01X191724D02*
X190954D01*
G01X194873D02*
X194104D01*
G01X198023D02*
X197253D01*
G01X185433Y301129D02*
X184646D01*
G01X188583D02*
X187796D01*
G01X191733D02*
X190945D01*
G01X194882D02*
X194095D01*
G01X198032D02*
X197244D01*
G01Y301094D02*
X198032D01*
G01X194095D02*
X194882D01*
G01X187796D02*
X188583D01*
G01X190945D02*
X191733D01*
G01X184646D02*
X185433D01*
G01X197356Y301039D02*
X197920D01*
G01X194207D02*
X194771D01*
G01X187907D02*
X188472D01*
G01X191057D02*
X191621D01*
G01X184758D02*
X185322D01*
G01X192520Y301026D02*
X193307D01*
G01X195670D02*
X196457D01*
G01X189370D02*
X190158D01*
G01X183071D02*
X183859D01*
G01X186221D02*
X187008D01*
G01X197244Y301014D02*
X198032D01*
G01X194095D02*
X194882D01*
G01X187796D02*
X188583D01*
G01X190945D02*
X191733D01*
G01X184646D02*
X185433D01*
G01X183859Y300908D02*
X183071D01*
G01X187008D02*
X186221D01*
G01X190158D02*
X189370D01*
G01X193307D02*
X192520D01*
G01X196457D02*
X195670D01*
G01X184016Y300787D02*
X182914D01*
G01X187166D02*
X186063D01*
G01X190315D02*
X189213D01*
G01X193465D02*
X192363D01*
G01X196614D02*
X195512D01*
G01X185237Y300783D02*
X184843D01*
G01X188386D02*
X187992D01*
G01X191536D02*
X191142D01*
G01X194685D02*
X194292D01*
G01X197835D02*
X197441D01*
G01X198130Y300000D02*
X200296D01*
G01X194981D02*
X197146D01*
G01X191831D02*
X193996D01*
G01X188681D02*
X190847D01*
G01X185532D02*
X187697D01*
G01X182382D02*
X184548D01*
G01X192520Y299753D02*
X193307D01*
G01X195670D02*
X196457D01*
G01X189370D02*
X190158D01*
G01X183071D02*
X183859D01*
G01X186221D02*
X187008D01*
G01X192520Y299731D02*
X193307D01*
G01X195670D02*
X196457D01*
G01X189370D02*
X190158D01*
G01X183071D02*
X183859D01*
G01X186221D02*
X187008D01*
G01X183859Y299477D02*
X183071D01*
G01X187008D02*
X186221D01*
G01X190158D02*
X189370D01*
G01X193307D02*
X192520D01*
G01X196457D02*
X195670D01*
G01X183859Y298818D02*
X183071D01*
G01X187008D02*
X186221D01*
G01X190158D02*
X189370D01*
G01X193307D02*
X192520D01*
G01X196457D02*
X195670D01*
G01X197441Y298626D02*
X197835D01*
G01X194292D02*
X194685D01*
G01X187992D02*
X188386D01*
G01X191142D02*
X191536D01*
G01X184843D02*
X185237D01*
G01X185322Y298370D02*
X184758D01*
G01X188472D02*
X187907D01*
G01X191621D02*
X191057D01*
G01X194771D02*
X194207D01*
G01X197920D02*
X197356D01*
G01X197253Y298267D02*
X198023D01*
G01X194104D02*
X194873D01*
G01X187805D02*
X188574D01*
G01X190954D02*
X191724D01*
G01X184655D02*
X185424D01*
G01X183859Y298228D02*
X183071D01*
G01X187008D02*
X186221D01*
G01X185532D02*
X184548D01*
G01X190158D02*
X189370D01*
G01X188681D02*
X187697D01*
G01X191831D02*
X190847D01*
G01X193307D02*
X192520D01*
G01X196457D02*
X195670D01*
G01X194981D02*
X193996D01*
G01X198130D02*
X197146D01*
G01X185433Y298015D02*
X184646D01*
G01X188583D02*
X187796D01*
G01X191733D02*
X190945D01*
G01X194882D02*
X194095D01*
G01X198032D02*
X197244D01*
G01X197146Y297913D02*
X198130D01*
G01X193996D02*
X194981D01*
G01X187697D02*
X188681D01*
G01X190847D02*
X191831D01*
G01X184548D02*
X185532D01*
G01X183859Y297637D02*
X183071D01*
G01X187008D02*
X186221D01*
G01X190158D02*
X189370D01*
G01X193307D02*
X192520D01*
G01X196457D02*
X195670D01*
G01X197146Y297598D02*
X198130D01*
G01X193996D02*
X194981D01*
G01X187697D02*
X188681D01*
G01X190847D02*
X191831D01*
G01X184548D02*
X185532D01*
G01X197244Y297582D02*
X198032D01*
G01X194095D02*
X194882D01*
G01X187796D02*
X188583D01*
G01X190945D02*
X191733D01*
G01X184646D02*
X185433D01*
G01X197244Y297358D02*
X198032D01*
G01X194095D02*
X194882D01*
G01X187796D02*
X188583D01*
G01X190945D02*
X191733D01*
G01X184646D02*
X185433D01*
G01X192520Y297047D02*
X193307D01*
G01X195670D02*
X196457D01*
G01X189370D02*
X190158D01*
G01X183071D02*
X183859D01*
G01X186221D02*
X187008D01*
G01X185433Y296925D02*
X184646D01*
G01X188583D02*
X187796D01*
G01X191733D02*
X190945D01*
G01X194882D02*
X194095D01*
G01X198032D02*
X197244D01*
G01X183859Y296456D02*
X183071D01*
G01X187008D02*
X186221D01*
G01X190158D02*
X189370D01*
G01X193307D02*
X192520D01*
G01X196457D02*
X195670D01*
G01X197253Y298267D02*
X197356Y298370D01*
G01X197920Y301039D02*
X198023Y301141D01*
G01X194104Y298267D02*
X194207Y298370D01*
G01X196614Y300787D02*
X197146Y301318D01*
G01D02*
X196614Y300787D01*
G01X194771Y301039D02*
X194873Y301141D01*
G01X190954Y298267D02*
X191057Y298370D01*
G01X193465Y300787D02*
X193996Y301318D01*
G01D02*
X193465Y300787D01*
G01X191621Y301039D02*
X191724Y301141D01*
G01X187805Y298267D02*
X187907Y298370D01*
G01X190315Y300787D02*
X190847Y301318D01*
G01D02*
X190315Y300787D01*
G01X188472Y301039D02*
X188574Y301141D01*
G01X184655Y298267D02*
X184758Y298370D01*
G01X187166Y300787D02*
X187697Y301318D01*
G01D02*
X187166Y300787D01*
G01X185322Y301039D02*
X185424Y301141D01*
G01X184016Y300787D02*
X184548Y301318D01*
G01D02*
X184016Y300787D01*
G01X182172Y301039D02*
X182275Y301141D01*
G01X198130Y301794D02*
X198662Y301574D01*
G01X194981Y301794D02*
X195512Y301574D01*
G01X191831Y301794D02*
X192363Y301574D01*
G01X188681Y301794D02*
X189213Y301574D01*
G01X185532Y301794D02*
X186063Y301574D01*
G01X182382Y301794D02*
X182914Y301574D01*
G01X198130Y301318D02*
X198662Y300787D01*
G01D02*
X198130Y301318D01*
G01X197356Y301039D02*
X197253Y301141D01*
G01X194981Y301318D02*
X195512Y300787D01*
G01D02*
X194981Y301318D01*
G01X197920Y298370D02*
X198023Y298267D01*
G01X194207Y301039D02*
X194104Y301141D01*
G01X191831Y301318D02*
X192363Y300787D01*
G01D02*
X191831Y301318D01*
G01X194771Y298370D02*
X194873Y298267D01*
G01X191057Y301039D02*
X190954Y301141D01*
G01X188681Y301318D02*
X189213Y300787D01*
G01D02*
X188681Y301318D01*
G01X191621Y298370D02*
X191724Y298267D01*
G01X187907Y301039D02*
X187805Y301141D01*
G01X185532Y301318D02*
X186063Y300787D01*
G01D02*
X185532Y301318D01*
G01X188472Y298370D02*
X188574Y298267D01*
G01X184758Y301039D02*
X184655Y301141D01*
G01X182382Y301318D02*
X182914Y300787D01*
G01D02*
X182382Y301318D01*
G01X185322Y298370D02*
X185424Y298267D01*
G01X182172Y298370D02*
X182275Y298267D01*
G01X197835Y300783D02*
Y298626D01*
G01X197441D02*
Y300783D01*
G01X196555Y305118D02*
Y295748D01*
G01X195571Y305118D02*
Y295748D01*
G01X194685Y300783D02*
Y298626D01*
G01X194292D02*
Y300783D01*
G01X193406Y305118D02*
Y295748D01*
G01X192422Y305118D02*
Y295748D01*
G01X191536Y300783D02*
Y298626D01*
G01X191142D02*
Y300783D01*
G01X190256Y305118D02*
Y295748D01*
G01X189272Y305118D02*
Y295748D01*
G01X188386Y300783D02*
Y298626D01*
G01X187992D02*
Y300783D01*
G01X187107Y305118D02*
Y295748D01*
G01X186122Y305118D02*
Y295748D01*
G01X185237Y300783D02*
Y298626D01*
G01X184843D02*
Y300783D01*
G01X183957Y305118D02*
Y295748D01*
G01X182973Y305118D02*
Y295748D01*
G01X182087Y300783D02*
Y298626D01*
G01X183859Y315472D02*
X183071D01*
G01X187008D02*
X186221D01*
G01X190158D02*
X189370D01*
G01X193307D02*
X192520D01*
G01X196457D02*
X195670D01*
G01X183859Y314881D02*
X183071D01*
G01X187008D02*
X186221D01*
G01X190158D02*
X189370D01*
G01X193307D02*
X192520D01*
G01X196457D02*
X195670D01*
G01X192520Y313976D02*
X193307D01*
G01X195670D02*
X196457D01*
G01X189370D02*
X190158D01*
G01X183071D02*
X183859D01*
G01X186221D02*
X187008D01*
G01X197166Y313385D02*
X198111D01*
G01X194016D02*
X194961D01*
G01X190866D02*
X191811D01*
G01X187717D02*
X188662D01*
G01X184567D02*
X185512D01*
G01X183859D02*
X183071D01*
G01X187008D02*
X186221D01*
G01X190158D02*
X189370D01*
G01X193307D02*
X192520D01*
G01X196457D02*
X195670D01*
G01X183859Y312677D02*
X183071D01*
G01X187008D02*
X186221D01*
G01X190158D02*
X189370D01*
G01X193307D02*
X192520D01*
G01X196457D02*
X195670D01*
G01X183859Y311732D02*
X183071D01*
G01X187008D02*
X186221D01*
G01X190158D02*
X189370D01*
G01X193307D02*
X192520D01*
G01X196457D02*
X195670D01*
G01X195551Y311141D02*
X196575D01*
G01X192402D02*
X193425D01*
G01X189252D02*
X190276D01*
G01X186103D02*
X187126D01*
G01X182953D02*
X183977D01*
G01X192520Y310551D02*
X193307D01*
G01X195670D02*
X196457D01*
G01X189370D02*
X190158D01*
G01X183071D02*
X183859D01*
G01X186221D02*
X187008D01*
G01X183859Y306102D02*
X183071D01*
G01X187008D02*
X186221D01*
G01X190158D02*
X189370D01*
G01X193307D02*
X192520D01*
G01X196457D02*
X195670D01*
G01X185433Y305826D02*
X184646D01*
G01X188583D02*
X187796D01*
G01X191733D02*
X190945D01*
G01X194882D02*
X194095D01*
G01X198032D02*
X197244D01*
G01X185433Y305236D02*
X184646D01*
G01X188583D02*
X187796D01*
G01X191733D02*
X190945D01*
G01X194882D02*
X194095D01*
G01X198032D02*
X197244D01*
G01X183957Y305118D02*
X182973D01*
G01X187107D02*
X186122D01*
G01X190256D02*
X189272D01*
G01X193406D02*
X192422D01*
G01X196555D02*
X195571D01*
G01X186063Y304940D02*
X184016D01*
G01X189213D02*
X187166D01*
G01X192363D02*
X190315D01*
G01X195512D02*
X193465D01*
G01X198662D02*
X196614D01*
G01X183859Y304921D02*
X183071D01*
G01X187008D02*
X186221D01*
G01X190158D02*
X189370D01*
G01X193307D02*
X192520D01*
G01X196457D02*
X195670D01*
G01X185532Y304409D02*
X184548D01*
G01X188681D02*
X187697D01*
G01X191831D02*
X190847D01*
G01X194981D02*
X193996D01*
G01X198130D02*
X197146D01*
G01X185433Y304330D02*
X184646D01*
G01X188583D02*
X187796D01*
G01X191733D02*
X190945D01*
G01X194882D02*
X194095D01*
G01X198032D02*
X197244D01*
G01X192520Y304133D02*
X193307D01*
G01X195670D02*
X196457D01*
G01X189370D02*
X190158D01*
G01X183071D02*
X183859D01*
G01X186221D02*
X187008D01*
G01X197244Y304094D02*
X198032D01*
G01X194095D02*
X194882D01*
G01X187796D02*
X188583D01*
G01X190945D02*
X191733D01*
G01X184646D02*
X185433D01*
G01X183859Y304015D02*
X183071D01*
G01X187008D02*
X186221D01*
G01X190158D02*
X189370D01*
G01X193307D02*
X192520D01*
G01X196457D02*
X195670D01*
G01X185433Y303917D02*
X184646D01*
G01X188583D02*
X187796D01*
G01X191733D02*
X190945D01*
G01X194882D02*
X194095D01*
G01X198032D02*
X197244D01*
G01X184252Y303543D02*
X182677D01*
G01X187402D02*
X185827D01*
G01X185433D02*
X184646D01*
G01X193701D02*
X192126D01*
G01X190551D02*
X188977D01*
G01X188583D02*
X187796D01*
G01X191733D02*
X190945D01*
G01X196851D02*
X195276D01*
G01X194882D02*
X194095D01*
G01X198032D02*
X197244D01*
G01X185433Y303503D02*
X184646D01*
G01X188583D02*
X187796D01*
G01X191733D02*
X190945D01*
G01X194882D02*
X194095D01*
G01X198032D02*
X197244D01*
G01X198130Y304409D02*
X198662Y304940D01*
G01X196949Y305511D02*
X196555Y305118D01*
G01X194981Y304409D02*
X195512Y304940D01*
G01X193800Y305511D02*
X193406Y305118D01*
G01X191831Y304409D02*
X192363Y304940D01*
G01X190650Y305511D02*
X190256Y305118D01*
G01X188681Y304409D02*
X189213Y304940D01*
G01X197166Y313385D02*
X196575Y312795D01*
G01X187500Y305511D02*
X187107Y305118D01*
G01X185532Y304409D02*
X186063Y304940D01*
G01X194016Y313385D02*
X193425Y312795D01*
G01X184351Y305511D02*
X183957Y305118D01*
G01X182382Y304409D02*
X182914Y304940D01*
G01X190866Y313385D02*
X190276Y312795D01*
G01X187717Y313385D02*
X187126Y312795D01*
G01X184567Y313385D02*
X183977Y312795D01*
G01X198111Y313385D02*
X198701Y312795D01*
G01X194961Y313385D02*
X195551Y312795D01*
G01X191811Y313385D02*
X192402Y312795D01*
G01X198327Y305511D02*
X198721Y305118D01*
G01X188662Y313385D02*
X189252Y312795D01*
G01X196614Y304940D02*
X197146Y304409D01*
G01X195177Y305511D02*
X195571Y305118D01*
G01X185512Y313385D02*
X186103Y312795D01*
G01X193465Y304940D02*
X193996Y304409D01*
G01X192028Y305511D02*
X192422Y305118D01*
G01X182363Y313385D02*
X182953Y312795D01*
G01X190315Y304940D02*
X190847Y304409D01*
G01X188878Y305511D02*
X189272Y305118D01*
G01X187166Y304940D02*
X187697Y304409D01*
G01X185729Y305511D02*
X186122Y305118D01*
G01X184016Y304940D02*
X184548Y304409D01*
G01X182579Y305511D02*
X182973Y305118D01*
G01X196851Y305511D02*
Y303543D01*
G01X196575Y311141D02*
Y312795D01*
G01X195551D02*
Y311141D01*
G01X195276Y305511D02*
Y303543D01*
G01X193701Y305511D02*
Y303543D01*
G01X193425Y311141D02*
Y312795D01*
G01X192402D02*
Y311141D01*
G01X192126Y305511D02*
Y303543D01*
G01X190551Y305511D02*
Y303543D01*
G01X190276Y311141D02*
Y312795D01*
G01X189252D02*
Y311141D01*
G01X188977Y305511D02*
Y303543D01*
G01X187402Y305511D02*
Y303543D01*
G01X187126Y311141D02*
Y312795D01*
G01X186103D02*
Y311141D01*
G01X185827Y305511D02*
Y303543D01*
G01X184252Y305511D02*
Y303543D01*
G01X183977Y311141D02*
Y312795D01*
G01X182953D02*
Y311141D01*
G01X182677Y305511D02*
Y303543D01*
G01X188219Y383120D02*
X189203D01*
G01X192156D02*
X193140D01*
G01X185758D02*
X186988D01*
G01X192648Y382115D02*
X191910D01*
G01X188711D02*
X188219D01*
G01X183790Y375078D02*
X182559D01*
G01X186988D02*
X185758D01*
G01X190925D02*
X189695D01*
G01X194863D02*
X193632D01*
G01X191418Y382868D02*
X192156Y383120D01*
G01X188219Y382115D02*
X187481Y381863D01*
G01Y382868D02*
X188219Y383120D01*
G01X193140D02*
X193878Y382868D01*
G01X189203Y383120D02*
X189941Y382868D01*
G01X182067Y383120D02*
X182805Y382868D01*
G01X191910Y382115D02*
X191418Y381863D01*
G01X193140D02*
X192648Y382115D01*
G01X189203Y381863D02*
X188711Y382115D01*
G01X191418Y381863D02*
X191172Y381612D01*
G01X190679Y382115D02*
X191418Y382868D01*
G01X187481Y381863D02*
X186988Y381361D01*
G01Y382366D02*
X187481Y382868D01*
G01X193878D02*
X194370Y382366D01*
G01X193386Y381612D02*
X193140Y381863D01*
G01X189941Y382868D02*
X190679Y382115D01*
G01X189449Y381612D02*
X189203Y381863D01*
G01X182805Y382868D02*
X183298Y382366D01*
G01X182313Y381612D02*
X182067Y381863D01*
G01X193632Y381109D02*
X193386Y381612D01*
G01X189695Y381109D02*
X189449Y381612D01*
G01X182559Y381109D02*
X182313Y381612D01*
G01X191172D02*
X190925Y381109D01*
G01X194370Y382366D02*
X194863Y381109D01*
G01X183298Y382366D02*
X183790Y381109D01*
G01X194863D02*
Y375078D01*
G01X193632D02*
Y381109D01*
G01X190925D02*
Y375078D01*
G01X189695D02*
Y381109D01*
G01X186988Y383120D02*
Y382366D01*
G01Y381361D02*
Y375078D01*
G01X185758D02*
Y383120D01*
G01X183790Y381109D02*
Y375078D01*
G01X182559D02*
Y381109D01*
G01X202363Y729409D02*
G03I-2245J0D01*
G01X192363D02*
G03I-2245J0D01*
G01X189368Y728659D02*
X190868D01*
G01X188868Y728159D02*
X191368D01*
G01X190868Y728659D02*
X191368Y728159D01*
G01X196618Y745909D02*
Y722909D01*
G01X193618D02*
Y745909D01*
G01X191368Y728159D02*
Y730659D01*
G01X190868Y728659D02*
Y730159D01*
G01X189368D02*
Y728659D01*
G01X188868Y730659D02*
Y728159D01*
G01X186618Y745909D02*
Y722909D01*
G01X183618D02*
Y745909D01*
G01X189368Y728659D02*
X188868Y728159D01*
G01X202363Y739409D02*
G03I-2245J0D01*
G01X192363D02*
G03I-2245J0D01*
G01X191368Y740659D02*
X188868D01*
G01X190868Y740159D02*
X189368D01*
G01Y738659D02*
X190868D01*
G01X188868Y738159D02*
X191368D01*
G01Y730659D02*
X188868D01*
G01X190868Y730159D02*
X189368D01*
G01Y740159D02*
X188868Y740659D01*
G01X190868Y738659D02*
X191368Y738159D01*
G01X189368Y730159D02*
X188868Y730659D01*
G01X191368Y738159D02*
Y740659D01*
G01X190868Y738659D02*
Y740159D01*
G01X189368D02*
Y738659D01*
G01X188868Y740659D02*
Y738159D01*
G01X190868Y730159D02*
X191368Y730659D01*
G01X190868Y740159D02*
X191368Y740659D01*
G01X189368Y738659D02*
X188868Y738159D01*
G01X187598Y992126D02*
Y1018109D01*
G01Y992126D02*
G03X191535Y988189I3937J0D01*
G01X261220D02*
X191535D01*
G01X187599Y992126D02*
G03X191536Y988189I3937J0D01*
G01X261221D02*
X191536D01*
G01X187599Y992126D02*
Y1021653D01*
G01X212681Y996063D02*
X195473D01*
G01D02*
Y1023622D01*
G01X212681Y996063D02*
X195473D01*
G01D02*
Y1023622D01*
G01X186418Y1001574D02*
X183662D01*
G01X186418Y1018110D02*
Y1001574D01*
G01X183662D02*
Y1018110D01*
G01X182481D02*
Y1001574D01*
G01X195473Y1023622D02*
X257284D01*
G01X195473D02*
X257284D01*
G01X187599Y1021653D02*
X187598Y1018109D01*
G01X187599Y1021653D02*
X185631Y1023622D01*
G01X183662Y1018110D02*
X186418D01*
G01X187599Y1021653D02*
X185630Y1023622D01*
G01X185855Y1026362D02*
X185355Y1026259D01*
G01X188057Y1031063D02*
X188657D01*
G01X182953D02*
X185355D01*
G01X185455Y1030450D02*
X183553D01*
G01Y1029019D02*
X185455D01*
G01X183553Y1028405D02*
X185455D01*
G01Y1026872D02*
X183553D01*
G01X185355Y1026259D02*
X182953D01*
G01X188657D02*
X188057D01*
G01X185355Y1031063D02*
X185855Y1030960D01*
G01X185755Y1030347D02*
X185455Y1030450D01*
G01Y1028405D02*
X185755Y1028303D01*
G01X186055Y1028712D02*
X186255Y1028610D01*
G01X185855Y1030960D02*
X186255Y1030654D01*
G01X185955Y1030143D02*
X185755Y1030347D01*
G01Y1028303D02*
X185955Y1028099D01*
G01X186255Y1030654D02*
X186555Y1030245D01*
G01X186255Y1028610D02*
X186555Y1028201D01*
G01Y1030245D02*
X186655Y1029939D01*
G01X186055Y1029836D02*
X185955Y1030143D01*
G01X186555Y1028201D02*
X186655Y1027894D01*
G01X185955Y1028099D02*
X186055Y1027792D01*
G01X188657Y1031063D02*
Y1026259D01*
G01X188057D02*
Y1030245D01*
G01X187456Y1029529D02*
Y1030347D01*
G01X186655Y1027894D02*
Y1027383D01*
G01Y1029939D02*
Y1029529D01*
G01X186055Y1029632D02*
Y1029836D01*
G01Y1027792D02*
Y1027486D01*
G01X183553Y1026872D02*
Y1028405D01*
G01Y1030450D02*
Y1029019D01*
G01X182953Y1026259D02*
Y1031063D01*
G01X186655Y1027383D02*
X186555Y1027077D01*
G01X186055Y1027486D02*
X185955Y1027179D01*
G01X186655Y1029529D02*
X186555Y1029223D01*
G01X185955Y1029325D02*
X186055Y1029632D01*
G01X185755Y1026975D02*
X185455Y1026872D01*
G01Y1029019D02*
X185755Y1029121D01*
G01X186255Y1028814D02*
X186055Y1028712D01*
G01X186255Y1026668D02*
X185855Y1026362D01*
G01X185955Y1027179D02*
X185755Y1026975D01*
G01Y1029121D02*
X185955Y1029325D01*
G01X188057Y1030245D02*
X187456Y1029529D01*
G01Y1030347D02*
X188057Y1031063D01*
G01X186555Y1027077D02*
X186255Y1026668D01*
G01X186555Y1029223D02*
X186255Y1028814D01*
G01X206749Y-24191D02*
Y-26991D01*
G01X203957Y236437D02*
G03X203170Y237224I-787J0D01*
G01Y234271D02*
G03X203957Y235059I0J787D01*
G01X219685Y237782D02*
X214528Y236063D01*
G01X219685Y233484D02*
X214528Y235203D01*
G01D02*
Y236063D01*
G01X203957Y236437D02*
Y235059D01*
G01X206693Y242145D02*
G03Y246082I0J1969D01*
G01Y241293D02*
G03Y246935I0J2821D01*
G01Y240440D02*
G03Y247787I0J3673D01*
G01X214528Y248312D02*
X216723D01*
G01X219685Y247774D02*
X214528D01*
G01D02*
Y248312D01*
G01X206693Y242145D02*
Y240440D01*
G01Y247787D02*
Y246082D01*
G01X207874Y262815D02*
G03X209843I985J0D01*
G01X224508Y267736D02*
X209843D01*
G01X214528Y264644D02*
X219685D01*
G01Y264106D02*
X214528D01*
G01D02*
Y264644D01*
G01X209843Y267736D02*
Y262815D01*
G01X207874Y271653D02*
Y262815D01*
G01X215160Y277464D02*
X214762D01*
G01X212011D02*
X211612D01*
G01X208861D02*
X208463D01*
G01X205711D02*
X205313D01*
G01X202562D02*
X202163D01*
G01X199412D02*
X199014D01*
G01X201811Y286023D02*
X201280D01*
G01X200296D02*
X199764D01*
G01X206595D02*
X206063D01*
G01X204961D02*
X204429D01*
G01X203445D02*
X202914D01*
G01X211260D02*
X210729D01*
G01X209744D02*
X209213D01*
G01X208111D02*
X207579D01*
G01X214410D02*
X213878D01*
G01X212894D02*
X212363D01*
G01X213098Y284004D02*
X213674D01*
G01X206799D02*
X207375D01*
G01X209948D02*
X210525D01*
G01X203649D02*
X204225D01*
G01X200500D02*
X201076D01*
G01X199492Y283763D02*
X198934D01*
G01X202642D02*
X202083D01*
G01X205791D02*
X205233D01*
G01X208941D02*
X208383D01*
G01X212090D02*
X211532D01*
G01X215240D02*
X214682D01*
G01X201181Y283660D02*
X200394D01*
G01X204331D02*
X203544D01*
G01X207481D02*
X206693D01*
G01X210630D02*
X209843D01*
G01X213780D02*
X212992D01*
G01X211563Y283564D02*
X212060D01*
G01X214712D02*
X215210D01*
G01X208413D02*
X208911D01*
G01X202114D02*
X202611D01*
G01X205263D02*
X205761D01*
G01X198964D02*
X199462D01*
G01X199457Y283539D02*
X198969D01*
G01X202606D02*
X202119D01*
G01X205756D02*
X205268D01*
G01X208905D02*
X208418D01*
G01X212055D02*
X211568D01*
G01X215205D02*
X214717D01*
G01X211418Y283505D02*
X212205D01*
G01X214567D02*
X215355D01*
G01X208268D02*
X209055D01*
G01X201969D02*
X202756D01*
G01X205118D02*
X205906D01*
G01X198819D02*
X199607D01*
G01Y283323D02*
X198819D01*
G01X202756D02*
X201969D01*
G01X205906D02*
X205118D01*
G01X209055D02*
X208268D01*
G01X212205D02*
X211418D01*
G01X215355D02*
X214567D01*
G01X211418Y283182D02*
X212205D01*
G01X214567D02*
X215355D01*
G01X208268D02*
X209055D01*
G01X201969D02*
X202756D01*
G01X205118D02*
X205906D01*
G01X198819D02*
X199607D01*
G01Y282965D02*
X198819D01*
G01X202756D02*
X201969D01*
G01X205906D02*
X205118D01*
G01X209055D02*
X208268D01*
G01X212205D02*
X211418D01*
G01X215355D02*
X214567D01*
G01X211579Y282665D02*
X212044D01*
G01X214728D02*
X215194D01*
G01X208429D02*
X208894D01*
G01X202130D02*
X202595D01*
G01X205279D02*
X205745D01*
G01X198980D02*
X199446D01*
G01X212992Y282635D02*
X213780D01*
G01X206693D02*
X207481D01*
G01X209843D02*
X210630D01*
G01X203544D02*
X204331D01*
G01X200394D02*
X201181D01*
G01X201067Y282210D02*
X200509D01*
G01X204216D02*
X203658D01*
G01X207366D02*
X206808D01*
G01X210516D02*
X209957D01*
G01X213665D02*
X213107D01*
G01X213878Y280118D02*
X214410D01*
G01X212363D02*
X212894D01*
G01X210729D02*
X211260D01*
G01X209213D02*
X209744D01*
G01X207579D02*
X208111D01*
G01X206063D02*
X206595D01*
G01X204429D02*
X204961D01*
G01X202914D02*
X203445D01*
G01X201280D02*
X201811D01*
G01X199764D02*
X200296D01*
G01X212992Y279285D02*
X213780D01*
G01X206693D02*
X207481D01*
G01X209843D02*
X210630D01*
G01X203544D02*
X204331D01*
G01X200394D02*
X201181D01*
G01X199607Y278814D02*
X198819D01*
G01X202756D02*
X201969D01*
G01X205906D02*
X205118D01*
G01X209055D02*
X208268D01*
G01X212205D02*
X211418D01*
G01X215355D02*
X214567D01*
G01X201181Y278002D02*
X200394D01*
G01X204331D02*
X203544D01*
G01X207481D02*
X206693D01*
G01X210630D02*
X209843D01*
G01X213780D02*
X212992D01*
G01X211475Y277976D02*
X212148D01*
G01X214625D02*
X215297D01*
G01X208325D02*
X208998D01*
G01X202026D02*
X202699D01*
G01X205176D02*
X205848D01*
G01X198877D02*
X199549D01*
G01X212992Y277752D02*
X213780D01*
G01X206693D02*
X207481D01*
G01X209843D02*
X210630D01*
G01X203544D02*
X204331D01*
G01X200394D02*
X201181D01*
G01X211546Y277712D02*
X212077D01*
G01X214695D02*
X215227D01*
G01X208396D02*
X208927D01*
G01X202097D02*
X202628D01*
G01X205246D02*
X205778D01*
G01X198947D02*
X199479D01*
G01X199477Y277707D02*
X198948D01*
G01X202627D02*
X202098D01*
G01X205777D02*
X205248D01*
G01X208926D02*
X208397D01*
G01X212076D02*
X211547D01*
G01X215225D02*
X214696D01*
G01X201181Y277698D02*
X200394D01*
G01X204331D02*
X203544D01*
G01X207481D02*
X206693D01*
G01X210630D02*
X209843D01*
G01X213780D02*
X212992D01*
G01X201181Y277671D02*
X200394D01*
G01X204331D02*
X203544D01*
G01X207481D02*
X206693D01*
G01X210630D02*
X209843D01*
G01X213780D02*
X212992D01*
G01X211614Y277455D02*
X212008D01*
G01X214764D02*
X215158D01*
G01X208465D02*
X208859D01*
G01X202166D02*
X202559D01*
G01X205315D02*
X205709D01*
G01X199016D02*
X199410D01*
G01X212894Y276377D02*
X213878D01*
G01X209744D02*
X210729D01*
G01X206595D02*
X207579D01*
G01X203445D02*
X204429D01*
G01X200296D02*
X201280D01*
G01X212363Y275846D02*
X214410D01*
G01X209213D02*
X211260D01*
G01X202914D02*
X204961D01*
G01X206063D02*
X208111D01*
G01X199764D02*
X201811D01*
G01X201575Y274409D02*
X200000D01*
G01X207874D02*
X206300D01*
G01X204725D02*
X203150D01*
G01X211024D02*
X209449D01*
G01X214174D02*
X212599D01*
G01X201181Y277824D02*
X200394Y277823D01*
G01X204331Y277824D02*
X203544Y277823D01*
G01X207481Y277824D02*
X206693Y277823D01*
G01X210630Y277824D02*
X209843Y277823D01*
G01X213780Y277824D02*
X212992Y277823D01*
G01X212894Y276377D02*
X212363Y275846D01*
G01X209744Y276377D02*
X209213Y275846D01*
G01X206595Y276377D02*
X206063Y275846D01*
G01X203445Y276377D02*
X202914Y275846D01*
G01X200296Y276377D02*
X199764Y275846D01*
G01X213878Y276377D02*
X214410Y275846D01*
G01X210729Y276377D02*
X211260Y275846D01*
G01X207579Y276377D02*
X208111Y275846D01*
G01X204429Y276377D02*
X204961Y275846D01*
G01X201280Y276377D02*
X201811Y275846D01*
G01X212008Y277455D02*
X212205Y278189D01*
G01X208859Y277455D02*
X209055Y278189D01*
G01X205709Y277455D02*
X205906Y278189D01*
G01X202559Y277455D02*
X202756Y278189D01*
G01X199410Y277455D02*
X199607Y278189D01*
G01X212060Y283564D02*
X212055Y283539D01*
G01X208911Y283564D02*
X208905Y283539D01*
G01X205761Y283564D02*
X205756Y283539D01*
G01X202611Y283564D02*
X202606Y283539D01*
G01X199462Y283564D02*
X199457Y283539D01*
G01X213674Y284004D02*
X213780Y284521D01*
G01X210525Y284004D02*
X210630Y284521D01*
G01X207375Y284004D02*
X207481Y284521D01*
G01X204225Y284004D02*
X204331Y284521D01*
G01X201076Y284004D02*
X201181Y284521D01*
G01X213107Y282210D02*
X212992Y281616D01*
G01X209957Y282210D02*
X209843Y281616D01*
G01X206808Y282210D02*
X206693Y281616D01*
G01X203658Y282210D02*
X203544Y281616D01*
G01X200509Y282210D02*
X200394Y281616D01*
G01X214567Y281766D02*
X214728Y282665D01*
G01X211418Y281766D02*
X211579Y282665D01*
G01X208268Y281766D02*
X208429Y282665D01*
G01X205118Y281766D02*
X205279Y282665D01*
G01X201969Y281766D02*
X202130Y282665D01*
G01X198819Y281766D02*
X198980Y282665D01*
G01X212205Y284919D02*
X212090Y283763D01*
G01X209055Y284919D02*
X208941Y283763D01*
G01X205906Y284919D02*
X205791Y283763D01*
G01X202756Y284919D02*
X202642Y283763D01*
G01X199607Y284919D02*
X199492Y283763D01*
G01X214567Y278189D02*
Y315472D01*
G01X212044Y282665D02*
X212205Y281766D01*
G01X208894Y282665D02*
X209055Y281766D01*
G01X205745Y282665D02*
X205906Y281766D01*
G01X202595Y282665D02*
X202756Y281766D01*
G01X199446Y282665D02*
X199607Y281766D01*
G01X213780Y281616D02*
X213665Y282210D01*
G01X210630Y281616D02*
X210516Y282210D01*
G01X207481Y281616D02*
X207366Y282210D01*
G01X204331Y281616D02*
X204216Y282210D01*
G01X201181Y281616D02*
X201067Y282210D01*
G01X213098Y284004D02*
X212992Y284521D01*
G01X209948Y284004D02*
X209843Y284521D01*
G01X206799Y284004D02*
X206693Y284521D01*
G01X203649Y284004D02*
X203544Y284521D01*
G01X200500Y284004D02*
X200394Y284521D01*
G01X214717Y283539D02*
X214712Y283564D01*
G01X211568Y283539D02*
X211563Y283564D01*
G01X208418Y283539D02*
X208413Y283564D01*
G01X205268Y283539D02*
X205263Y283564D01*
G01X202119Y283539D02*
X202114Y283564D01*
G01X198969Y283539D02*
X198964Y283564D01*
G01X214764Y277455D02*
X214567Y278189D01*
G01X211614Y277455D02*
X211418Y278189D01*
G01X208465Y277455D02*
X208268Y278189D01*
G01X205315Y277455D02*
X205118Y278189D01*
G01X202166Y277455D02*
X201969Y278189D01*
G01X199016Y277455D02*
X198819Y278189D01*
G01X214410Y275846D02*
Y304940D01*
G01X214331Y271653D02*
Y305255D01*
G01X214174Y274409D02*
Y271653D01*
G01X213878Y286023D02*
Y304409D01*
G01Y276377D02*
Y280118D01*
G01X213780Y277671D02*
Y305826D01*
G01X212992Y277671D02*
Y305826D01*
G01X212894Y280118D02*
Y276377D01*
G01Y304409D02*
Y286023D01*
G01X212599Y274409D02*
Y271653D01*
G01X212441D02*
Y305255D01*
G01X212363Y304940D02*
Y275846D01*
G01X212205Y278189D02*
Y315472D01*
G01X211418Y278189D02*
Y315472D01*
G01X211260Y275846D02*
Y304940D01*
G01X211181Y305255D02*
Y271653D01*
G01X211024Y274409D02*
Y271653D01*
G01X210729Y286023D02*
Y304409D01*
G01Y276377D02*
Y280118D01*
G01X210630Y305826D02*
Y277671D01*
G01X209843D02*
Y305826D01*
G01X209744Y280118D02*
Y276377D01*
G01Y304409D02*
Y286023D01*
G01X209449Y274409D02*
Y271653D01*
G01X209292Y305255D02*
Y271653D01*
G01X209213Y304940D02*
Y275846D01*
G01X209055Y278189D02*
Y315472D01*
G01X208268Y278189D02*
Y315472D01*
G01X208111Y275846D02*
Y304940D01*
G01X208032Y305255D02*
Y271653D01*
G01X207874Y274409D02*
Y288846D01*
G01Y274409D02*
Y271653D01*
G01X207579Y286023D02*
Y304409D01*
G01Y276377D02*
Y280118D01*
G01X207481Y305826D02*
Y277671D01*
G01X206693D02*
Y305826D01*
G01X206595Y280118D02*
Y276377D01*
G01Y304409D02*
Y286023D01*
G01X206300Y274409D02*
Y271653D01*
G01X206142Y305255D02*
Y271653D01*
G01X206063Y304940D02*
Y275846D01*
G01X205906Y278189D02*
Y315472D01*
G01X205118Y278189D02*
Y315472D01*
G01X204961Y275846D02*
Y304940D01*
G01X204882Y305255D02*
Y271653D01*
G01X204725Y274409D02*
Y271653D01*
G01X204429Y286023D02*
Y304409D01*
G01Y276377D02*
Y280118D01*
G01X204331Y305826D02*
Y277671D01*
G01X203544D02*
Y305826D01*
G01X203445Y280118D02*
Y276377D01*
G01Y304409D02*
Y286023D01*
G01X203150Y274409D02*
Y271653D01*
G01X202992Y305255D02*
Y271653D01*
G01X202914Y304940D02*
Y275846D01*
G01X202756Y278189D02*
Y315472D01*
G01X201969Y278189D02*
Y315472D01*
G01X201811Y275846D02*
Y304940D01*
G01X201733Y305255D02*
Y271653D01*
G01X201575Y274409D02*
Y271653D01*
G01X201280Y286023D02*
Y304409D01*
G01Y276377D02*
Y280118D01*
G01X201181Y305826D02*
Y277671D01*
G01X200394D02*
Y305826D01*
G01X200296Y280118D02*
Y276377D01*
G01Y304409D02*
Y286023D01*
G01X200000Y274409D02*
Y271653D01*
G01X199843Y305255D02*
Y271653D01*
G01X199764Y304940D02*
Y275846D01*
G01X199607Y278189D02*
Y315472D01*
G01X198819Y278189D02*
Y315472D01*
G01X198662Y275846D02*
Y304940D01*
G01X198583Y305255D02*
Y271653D01*
G01X198425Y274409D02*
Y271653D01*
G01X214682Y283763D02*
X214567Y284919D01*
G01X211532Y283763D02*
X211418Y284919D01*
G01X208383Y283763D02*
X208268Y284919D01*
G01X205233Y283763D02*
X205118Y284919D01*
G01X202083Y283763D02*
X201969Y284919D01*
G01X198934Y283763D02*
X198819Y284919D01*
G01X212363Y301574D02*
X212894Y301794D01*
G01X209213Y301574D02*
X209744Y301794D01*
G01X206063Y301574D02*
X206595Y301794D01*
G01X202914Y301574D02*
X203445Y301794D01*
G01X199764Y301574D02*
X200296Y301794D01*
G01X201181Y302401D02*
X200394D01*
G01X204331D02*
X203544D01*
G01X207481D02*
X206693D01*
G01X210630D02*
X209843D01*
G01X213780D02*
X212992D01*
G01X201181Y302165D02*
X200394D01*
G01X204331D02*
X203544D01*
G01X207481D02*
X206693D01*
G01X210630D02*
X209843D01*
G01X213780D02*
X212992D01*
G01X211418Y302126D02*
X212205D01*
G01X214567D02*
X215355D01*
G01X208268D02*
X209055D01*
G01X201969D02*
X202756D01*
G01X205118D02*
X205906D01*
G01X198819D02*
X199607D01*
G01X211418Y302086D02*
X212205D01*
G01X214567D02*
X215355D01*
G01X208268D02*
X209055D01*
G01X201969D02*
X202756D01*
G01X205118D02*
X205906D01*
G01X198819D02*
X199607D01*
G01X201181Y301988D02*
X200394D01*
G01X204331D02*
X203544D01*
G01X207481D02*
X206693D01*
G01X210630D02*
X209843D01*
G01X213780D02*
X212992D01*
G01X199607Y301847D02*
X198819D01*
G01X202756D02*
X201969D01*
G01X205906D02*
X205118D01*
G01X209055D02*
X208268D01*
G01X212205D02*
X211418D01*
G01X215355D02*
X214567D01*
G01X212992Y301811D02*
X213780D01*
G01X206693D02*
X207481D01*
G01X209843D02*
X210630D01*
G01X203544D02*
X204331D01*
G01X200394D02*
X201181D01*
G01Y301574D02*
X200394D01*
G01X199764D02*
X198662D01*
G01X204331D02*
X203544D01*
G01X202914D02*
X201811D01*
G01X206063D02*
X204961D01*
G01X207481D02*
X206693D01*
G01X210630D02*
X209843D01*
G01X209213D02*
X208111D01*
G01X213780D02*
X212992D01*
G01X212363D02*
X211260D01*
G01X215512D02*
X214410D01*
G01X212894Y301555D02*
X213878D01*
G01X206595D02*
X207579D01*
G01X209744D02*
X210729D01*
G01X203445D02*
X204429D01*
G01X200296D02*
X201280D01*
G01X212992Y301496D02*
X213780D01*
G01X206693D02*
X207481D01*
G01X209843D02*
X210630D01*
G01X203544D02*
X204331D01*
G01X200394D02*
X201181D01*
G01X201280Y301240D02*
X200296D01*
G01X204429D02*
X203445D01*
G01X207579D02*
X206595D01*
G01X210729D02*
X209744D01*
G01X213878D02*
X212894D01*
G01X212992Y301202D02*
X213780D01*
G01X206693D02*
X207481D01*
G01X209843D02*
X210630D01*
G01X203544D02*
X204331D01*
G01X200394D02*
X201181D01*
G01Y301181D02*
X200394D01*
G01X204331D02*
X203544D01*
G01X207481D02*
X206693D01*
G01X210630D02*
X209843D01*
G01X213780D02*
X212992D01*
G01X201172Y301141D02*
X200403D01*
G01X204322D02*
X203553D01*
G01X207472D02*
X206702D01*
G01X210621D02*
X209852D01*
G01X213771D02*
X213001D01*
G01X201181Y301129D02*
X200394D01*
G01X204331D02*
X203544D01*
G01X207481D02*
X206693D01*
G01X210630D02*
X209843D01*
G01X213780D02*
X212992D01*
G01Y301094D02*
X213780D01*
G01X206693D02*
X207481D01*
G01X209843D02*
X210630D01*
G01X203544D02*
X204331D01*
G01X200394D02*
X201181D01*
G01X213104Y301039D02*
X213668D01*
G01X206805D02*
X207369D01*
G01X209955D02*
X210519D01*
G01X203655D02*
X204220D01*
G01X200506D02*
X201070D01*
G01X211418Y301026D02*
X212205D01*
G01X214567D02*
X215355D01*
G01X208268D02*
X209055D01*
G01X201969D02*
X202756D01*
G01X205118D02*
X205906D01*
G01X198819D02*
X199607D01*
G01X212992Y301014D02*
X213780D01*
G01X206693D02*
X207481D01*
G01X209843D02*
X210630D01*
G01X203544D02*
X204331D01*
G01X200394D02*
X201181D01*
G01X199607Y300908D02*
X198819D01*
G01X202756D02*
X201969D01*
G01X205906D02*
X205118D01*
G01X209055D02*
X208268D01*
G01X212205D02*
X211418D01*
G01X215355D02*
X214567D01*
G01X199764Y300787D02*
X198662D01*
G01X202914D02*
X201811D01*
G01X206063D02*
X204961D01*
G01X209213D02*
X208111D01*
G01X212363D02*
X211260D01*
G01X215512D02*
X214410D01*
G01X200985Y300783D02*
X200591D01*
G01X204134D02*
X203740D01*
G01X207284D02*
X206890D01*
G01X210433D02*
X210040D01*
G01X213583D02*
X213189D01*
G01X210729Y300000D02*
X212894D01*
G01X213878D02*
X216044D01*
G01X207579D02*
X209744D01*
G01X201280D02*
X203445D01*
G01X204429D02*
X206595D01*
G01X211418Y299753D02*
X212205D01*
G01X214567D02*
X215355D01*
G01X208268D02*
X209055D01*
G01X201969D02*
X202756D01*
G01X205118D02*
X205906D01*
G01X198819D02*
X199607D01*
G01X211418Y299731D02*
X212205D01*
G01X214567D02*
X215355D01*
G01X208268D02*
X209055D01*
G01X201969D02*
X202756D01*
G01X205118D02*
X205906D01*
G01X198819D02*
X199607D01*
G01Y299477D02*
X198819D01*
G01X202756D02*
X201969D01*
G01X205906D02*
X205118D01*
G01X209055D02*
X208268D01*
G01X212205D02*
X211418D01*
G01X215355D02*
X214567D01*
G01X199607Y298818D02*
X198819D01*
G01X202756D02*
X201969D01*
G01X205906D02*
X205118D01*
G01X209055D02*
X208268D01*
G01X212205D02*
X211418D01*
G01X215355D02*
X214567D01*
G01X213189Y298626D02*
X213583D01*
G01X206890D02*
X207284D01*
G01X210040D02*
X210433D01*
G01X203740D02*
X204134D01*
G01X200591D02*
X200985D01*
G01X201070Y298370D02*
X200506D01*
G01X204220D02*
X203655D01*
G01X207369D02*
X206805D01*
G01X210519D02*
X209955D01*
G01X213668D02*
X213104D01*
G01X213001Y298267D02*
X213771D01*
G01X206702D02*
X207472D01*
G01X209852D02*
X210621D01*
G01X203553D02*
X204322D01*
G01X200403D02*
X201172D01*
G01X199607Y298228D02*
X198819D01*
G01X201280D02*
X200296D01*
G01X202756D02*
X201969D01*
G01X205906D02*
X205118D01*
G01X204429D02*
X203445D01*
G01X209055D02*
X208268D01*
G01X207579D02*
X206595D01*
G01X210729D02*
X209744D01*
G01X212205D02*
X211418D01*
G01X215355D02*
X214567D01*
G01X213878D02*
X212894D01*
G01X201181Y298015D02*
X200394D01*
G01X204331D02*
X203544D01*
G01X207481D02*
X206693D01*
G01X210630D02*
X209843D01*
G01X213780D02*
X212992D01*
G01X212894Y297913D02*
X213878D01*
G01X206595D02*
X207579D01*
G01X209744D02*
X210729D01*
G01X203445D02*
X204429D01*
G01X200296D02*
X201280D01*
G01X199607Y297637D02*
X198819D01*
G01X202756D02*
X201969D01*
G01X205906D02*
X205118D01*
G01X209055D02*
X208268D01*
G01X212205D02*
X211418D01*
G01X215355D02*
X214567D01*
G01X212894Y297598D02*
X213878D01*
G01X206595D02*
X207579D01*
G01X209744D02*
X210729D01*
G01X203445D02*
X204429D01*
G01X200296D02*
X201280D01*
G01X212992Y297582D02*
X213780D01*
G01X206693D02*
X207481D01*
G01X209843D02*
X210630D01*
G01X203544D02*
X204331D01*
G01X200394D02*
X201181D01*
G01X212992Y297358D02*
X213780D01*
G01X206693D02*
X207481D01*
G01X209843D02*
X210630D01*
G01X203544D02*
X204331D01*
G01X200394D02*
X201181D01*
G01X211418Y297047D02*
X212205D01*
G01X214567D02*
X215355D01*
G01X208268D02*
X209055D01*
G01X201969D02*
X202756D01*
G01X205118D02*
X205906D01*
G01X198819D02*
X199607D01*
G01X201181Y296925D02*
X200394D01*
G01X204331D02*
X203544D01*
G01X207481D02*
X206693D01*
G01X210630D02*
X209843D01*
G01X213780D02*
X212992D01*
G01X199607Y296456D02*
X198819D01*
G01X202756D02*
X201969D01*
G01X205906D02*
X205118D01*
G01X209055D02*
X208268D01*
G01X212205D02*
X211418D01*
G01X215355D02*
X214567D01*
G01X213878Y301794D02*
X214410Y301574D01*
G01X213001Y298267D02*
X213104Y298370D01*
G01X213668Y301039D02*
X213771Y301141D01*
G01X209852Y298267D02*
X209955Y298370D01*
G01X212363Y300787D02*
X212894Y301318D01*
G01D02*
X212363Y300787D01*
G01X210519Y301039D02*
X210621Y301141D01*
G01X206702Y298267D02*
X206805Y298370D01*
G01X209213Y300787D02*
X209744Y301318D01*
G01D02*
X209213Y300787D01*
G01X207369Y301039D02*
X207472Y301141D01*
G01X203553Y298267D02*
X203655Y298370D01*
G01X206063Y300787D02*
X206595Y301318D01*
G01D02*
X206063Y300787D01*
G01X204220Y301039D02*
X204322Y301141D01*
G01X200403Y298267D02*
X200506Y298370D01*
G01X202914Y300787D02*
X203445Y301318D01*
G01D02*
X202914Y300787D01*
G01X201070Y301039D02*
X201172Y301141D01*
G01X199764Y300787D02*
X200296Y301318D01*
G01D02*
X199764Y300787D01*
G01X210729Y301794D02*
X211260Y301574D01*
G01X207579Y301794D02*
X208111Y301574D01*
G01X204429Y301794D02*
X204961Y301574D01*
G01X201280Y301794D02*
X201811Y301574D01*
G01X213878Y301318D02*
X214410Y300787D01*
G01D02*
X213878Y301318D01*
G01X213104Y301039D02*
X213001Y301141D01*
G01X210729Y301318D02*
X211260Y300787D01*
G01D02*
X210729Y301318D01*
G01X213668Y298370D02*
X213771Y298267D01*
G01X209955Y301039D02*
X209852Y301141D01*
G01X207579Y301318D02*
X208111Y300787D01*
G01D02*
X207579Y301318D01*
G01X210519Y298370D02*
X210621Y298267D01*
G01X206805Y301039D02*
X206702Y301141D01*
G01X204429Y301318D02*
X204961Y300787D01*
G01D02*
X204429Y301318D01*
G01X207369Y298370D02*
X207472Y298267D01*
G01X203655Y301039D02*
X203553Y301141D01*
G01X201280Y301318D02*
X201811Y300787D01*
G01D02*
X201280Y301318D01*
G01X204220Y298370D02*
X204322Y298267D01*
G01X200506Y301039D02*
X200403Y301141D01*
G01X201070Y298370D02*
X201172Y298267D01*
G01X214469Y305118D02*
Y295748D01*
G01X213583Y300783D02*
Y298626D01*
G01X213189D02*
Y300783D01*
G01X212303Y305118D02*
Y295748D01*
G01X211319Y305118D02*
Y295748D01*
G01X210433Y300783D02*
Y298626D01*
G01X210040D02*
Y300783D01*
G01X209154Y305118D02*
Y295748D01*
G01X208170Y305118D02*
Y295748D01*
G01X207284Y300783D02*
Y298626D01*
G01X206890D02*
Y300783D01*
G01X206004Y305118D02*
Y295748D01*
G01X205020Y305118D02*
Y295748D01*
G01X204134Y300783D02*
Y298626D01*
G01X203740D02*
Y300783D01*
G01X202855Y305118D02*
Y295748D01*
G01X201870Y305118D02*
Y295748D01*
G01X200985Y300783D02*
Y298626D01*
G01X200591D02*
Y300783D01*
G01X199705Y305118D02*
Y295748D01*
G01X198721Y305118D02*
Y295748D01*
G01X199607Y315472D02*
X198819D01*
G01X202756D02*
X201969D01*
G01X205906D02*
X205118D01*
G01X209055D02*
X208268D01*
G01X212205D02*
X211418D01*
G01X215355D02*
X214567D01*
G01X199607Y314881D02*
X198819D01*
G01X202756D02*
X201969D01*
G01X205906D02*
X205118D01*
G01X209055D02*
X208268D01*
G01X212205D02*
X211418D01*
G01X215355D02*
X214567D01*
G01X211418Y313976D02*
X212205D01*
G01X214567D02*
X215355D01*
G01X208268D02*
X209055D01*
G01X201969D02*
X202756D01*
G01X205118D02*
X205906D01*
G01X198819D02*
X199607D01*
G01X212914Y313385D02*
X213859D01*
G01X209764D02*
X210709D01*
G01X206614D02*
X207559D01*
G01X203465D02*
X204410D01*
G01X200315D02*
X201260D01*
G01X199607D02*
X198819D01*
G01X202756D02*
X201969D01*
G01X205906D02*
X205118D01*
G01X209055D02*
X208268D01*
G01X212205D02*
X211418D01*
G01X215355D02*
X214567D01*
G01X199607Y312677D02*
X198819D01*
G01X202756D02*
X201969D01*
G01X205906D02*
X205118D01*
G01X209055D02*
X208268D01*
G01X212205D02*
X211418D01*
G01X215355D02*
X214567D01*
G01X199607Y311732D02*
X198819D01*
G01X202756D02*
X201969D01*
G01X205906D02*
X205118D01*
G01X209055D02*
X208268D01*
G01X212205D02*
X211418D01*
G01X215355D02*
X214567D01*
G01X214449Y311141D02*
X215473D01*
G01X211300D02*
X212323D01*
G01X208150D02*
X209174D01*
G01X205000D02*
X206024D01*
G01X201851D02*
X202874D01*
G01X198701D02*
X199725D01*
G01X211418Y310551D02*
X212205D01*
G01X214567D02*
X215355D01*
G01X208268D02*
X209055D01*
G01X201969D02*
X202756D01*
G01X205118D02*
X205906D01*
G01X198819D02*
X199607D01*
G01Y306102D02*
X198819D01*
G01X202756D02*
X201969D01*
G01X205906D02*
X205118D01*
G01X209055D02*
X208268D01*
G01X212205D02*
X211418D01*
G01X215355D02*
X214567D01*
G01X201181Y305826D02*
X200394D01*
G01X204331D02*
X203544D01*
G01X207481D02*
X206693D01*
G01X210630D02*
X209843D01*
G01X213780D02*
X212992D01*
G01X201181Y305236D02*
X200394D01*
G01X204331D02*
X203544D01*
G01X207481D02*
X206693D01*
G01X210630D02*
X209843D01*
G01X213780D02*
X212992D01*
G01X214469Y305118D02*
X215453D01*
G01X199705D02*
X198721D01*
G01X202855D02*
X201870D01*
G01X206004D02*
X205020D01*
G01X209154D02*
X208170D01*
G01X212303D02*
X211319D01*
G01X201811Y304940D02*
X199764D01*
G01X204961D02*
X202914D01*
G01X208111D02*
X206063D01*
G01X211260D02*
X209213D01*
G01X214410D02*
X212363D01*
G01X199607Y304921D02*
X198819D01*
G01X202756D02*
X201969D01*
G01X205906D02*
X205118D01*
G01X209055D02*
X208268D01*
G01X212205D02*
X211418D01*
G01X215355D02*
X214567D01*
G01X201280Y304409D02*
X200296D01*
G01X204429D02*
X203445D01*
G01X207579D02*
X206595D01*
G01X210729D02*
X209744D01*
G01X213878D02*
X212894D01*
G01X201181Y304330D02*
X200394D01*
G01X204331D02*
X203544D01*
G01X207481D02*
X206693D01*
G01X210630D02*
X209843D01*
G01X213780D02*
X212992D01*
G01X211418Y304133D02*
X212205D01*
G01X214567D02*
X215355D01*
G01X208268D02*
X209055D01*
G01X201969D02*
X202756D01*
G01X205118D02*
X205906D01*
G01X198819D02*
X199607D01*
G01X212992Y304094D02*
X213780D01*
G01X206693D02*
X207481D01*
G01X209843D02*
X210630D01*
G01X203544D02*
X204331D01*
G01X200394D02*
X201181D01*
G01X199607Y304015D02*
X198819D01*
G01X202756D02*
X201969D01*
G01X205906D02*
X205118D01*
G01X209055D02*
X208268D01*
G01X212205D02*
X211418D01*
G01X215355D02*
X214567D01*
G01X201181Y303917D02*
X200394D01*
G01X204331D02*
X203544D01*
G01X207481D02*
X206693D01*
G01X210630D02*
X209843D01*
G01X213780D02*
X212992D01*
G01X203150Y303543D02*
X201575D01*
G01X200000D02*
X198425D01*
G01X201181D02*
X200394D01*
G01X206300D02*
X204725D01*
G01X204331D02*
X203544D01*
G01X212599D02*
X211024D01*
G01X209449D02*
X207874D01*
G01X207481D02*
X206693D01*
G01X210630D02*
X209843D01*
G01X215748D02*
X214174D01*
G01X213780D02*
X212992D01*
G01X201181Y303503D02*
X200394D01*
G01X204331D02*
X203544D01*
G01X207481D02*
X206693D01*
G01X210630D02*
X209843D01*
G01X213780D02*
X212992D01*
G01X213878Y304409D02*
X214410Y304940D01*
G01X212697Y305511D02*
X212303Y305118D01*
G01X210729Y304409D02*
X211260Y304940D01*
G01X209548Y305511D02*
X209154Y305118D01*
G01X207579Y304409D02*
X208111Y304940D01*
G01X206398Y305511D02*
X206004Y305118D01*
G01X204429Y304409D02*
X204961Y304940D01*
G01X212914Y313385D02*
X212323Y312795D01*
G01X203248Y305511D02*
X202855Y305118D01*
G01X201280Y304409D02*
X201811Y304940D01*
G01X209764Y313385D02*
X209174Y312795D01*
G01X200099Y305511D02*
X199705Y305118D01*
G01X206614Y313385D02*
X206024Y312795D01*
G01X203465Y313385D02*
X202874Y312795D01*
G01X200315Y313385D02*
X199725Y312795D01*
G01X213859Y313385D02*
X214449Y312795D01*
G01X210709Y313385D02*
X211300Y312795D01*
G01X207559Y313385D02*
X208150Y312795D01*
G01X214075Y305511D02*
X214469Y305118D01*
G01X204410Y313385D02*
X205000Y312795D01*
G01X212363Y304940D02*
X212894Y304409D01*
G01X210925Y305511D02*
X211319Y305118D01*
G01X201260Y313385D02*
X201851Y312795D01*
G01X209213Y304940D02*
X209744Y304409D01*
G01X207776Y305511D02*
X208170Y305118D01*
G01X206063Y304940D02*
X206595Y304409D01*
G01X204626Y305511D02*
X205020Y305118D01*
G01X202914Y304940D02*
X203445Y304409D01*
G01X201477Y305511D02*
X201870Y305118D01*
G01X199764Y304940D02*
X200296Y304409D01*
G01X214449Y312795D02*
Y311141D01*
G01X214174Y305511D02*
Y303543D01*
G01X212599Y305511D02*
Y303543D01*
G01X212323Y311141D02*
Y312795D01*
G01X211300D02*
Y311141D01*
G01X211024Y305511D02*
Y303543D01*
G01X209449Y305511D02*
Y303543D01*
G01X209174Y311141D02*
Y312795D01*
G01X208150D02*
Y311141D01*
G01X207874Y305511D02*
Y303543D01*
G01X206300Y305511D02*
Y303543D01*
G01X206024Y311141D02*
Y312795D01*
G01X205000D02*
Y311141D01*
G01X204725Y305511D02*
Y303543D01*
G01X203150Y305511D02*
Y303543D01*
G01X202874Y311141D02*
Y312795D01*
G01X201851D02*
Y311141D01*
G01X201575Y305511D02*
Y303543D01*
G01X200000Y305511D02*
Y303543D01*
G01X199725Y311141D02*
Y312795D01*
G01X198701D02*
Y311141D01*
G01X198425Y305511D02*
Y303543D01*
G01X212363Y729409D02*
G03I-2245J0D01*
G01X209368Y728659D02*
X210868D01*
G01X199368D02*
X200868D01*
G01X208868Y728159D02*
X211368D01*
G01X198868D02*
X201368D01*
G01X210868Y728659D02*
X211368Y728159D01*
G01X200868Y728659D02*
X201368Y728159D01*
G01X213618Y722909D02*
Y745909D01*
G01X211368Y728159D02*
Y730659D01*
G01X210868Y728659D02*
Y730159D01*
G01X209368D02*
Y728659D01*
G01X208868Y730659D02*
Y728159D01*
G01X206618Y745909D02*
Y722909D01*
G01X203618D02*
Y745909D01*
G01X201368Y728159D02*
Y730659D01*
G01X200868Y728659D02*
Y730159D01*
G01X199368D02*
Y728659D01*
G01X198868Y730659D02*
Y728159D01*
G01X209368Y728659D02*
X208868Y728159D01*
G01X199368Y728659D02*
X198868Y728159D01*
G01X212363Y739409D02*
G03I-2245J0D01*
G01X201368Y740659D02*
X198868D01*
G01X211368D02*
X208868D01*
G01X200868Y740159D02*
X199368D01*
G01X210868D02*
X209368D01*
G01Y738659D02*
X210868D01*
G01X199368D02*
X200868D01*
G01X208868Y738159D02*
X211368D01*
G01X198868D02*
X201368D01*
G01Y730659D02*
X198868D01*
G01X211368D02*
X208868D01*
G01X200868Y730159D02*
X199368D01*
G01X210868D02*
X209368D01*
G01Y740159D02*
X208868Y740659D01*
G01X210868Y738659D02*
X211368Y738159D01*
G01X199368Y740159D02*
X198868Y740659D01*
G01X209368Y730159D02*
X208868Y730659D01*
G01X200868Y738659D02*
X201368Y738159D01*
G01X199368Y730159D02*
X198868Y730659D01*
G01X211368Y738159D02*
Y740659D01*
G01X210868Y738659D02*
Y740159D01*
G01X209368D02*
Y738659D01*
G01X208868Y740659D02*
Y738159D01*
G01X201368D02*
Y740659D01*
G01X200868Y738659D02*
Y740159D01*
G01X199368D02*
Y738659D01*
G01X198868Y740659D02*
Y738159D01*
G01X210868Y730159D02*
X211368Y730659D01*
G01X210868Y740159D02*
X211368Y740659D01*
G01X200868Y730159D02*
X201368Y730659D01*
G01X209368Y738659D02*
X208868Y738159D01*
G01X200868Y740159D02*
X201368Y740659D01*
G01X199368Y738659D02*
X198868Y738159D01*
G01X212681Y988189D02*
G03Y996063I0J3937D01*
G01Y988189D02*
G03Y996063I0J3937D01*
G01X225591Y234960D02*
G03I-1575J0D01*
G01X219685Y237137D02*
X218368Y236707D01*
G01X217930Y236600D02*
X214967Y235633D01*
G01X224508Y236338D02*
X223524D01*
G01Y236233D02*
X224508D01*
G01Y236161D02*
X223524D01*
G01X224508Y235937D02*
X223524D01*
G01X224508Y234586D02*
X223524D01*
G01Y234574D02*
X224508D01*
G01Y234278D02*
X223524D01*
G01X224508Y234173D02*
X223524D01*
G01X224508Y233996D02*
X223524D01*
G01Y232992D02*
X224508D01*
G01Y229153D02*
X223524D01*
G01X224508Y228366D02*
X223524D01*
G01X219685Y234129D02*
X218368Y234558D01*
G01X217930Y234666D02*
X214967Y235633D01*
G01X226378Y228385D02*
Y318937D01*
G01X224508Y267736D02*
Y228366D01*
G01X223524D02*
Y267813D01*
G01X222048Y267736D02*
Y231122D01*
G01X219685Y234129D02*
Y233484D01*
G01X218368Y236707D02*
Y234558D01*
G01X217930Y236600D02*
Y234666D01*
G01X222706Y245928D02*
G03X222992Y246572I-697J695D01*
G01X222203Y244033D02*
G03X222055Y242830I696J-696D01*
G01X225591Y246771D02*
G03I-1575J0D01*
G01X221507Y244729D02*
G03X221211Y242323I1391J-1392D01*
G01X223401Y245232D02*
G03X223975Y246521I-1391J1392D01*
G01X217600Y246377D02*
X217271Y246270D01*
G01X218478Y252287D02*
X218149Y252180D01*
G01X217052Y242617D02*
X216503Y242402D01*
G01X217052Y240361D02*
X216832Y240253D01*
G01X217052Y242079D02*
X216832Y241972D01*
G01X219246Y244121D02*
X219027Y244014D01*
G01X217052Y246807D02*
X216832Y246700D01*
G01X218588Y251750D02*
X217930Y251642D01*
G01X217491Y250783D02*
X216942Y250676D01*
G01X217491Y250246D02*
X217052Y250138D01*
G01X217491Y246915D02*
X217052Y246807D01*
G01X216942Y250676D02*
X216723Y250568D01*
G01X219027Y251965D02*
X218588Y251750D01*
G01X218698Y252394D02*
X218478Y252287D01*
G01X223628Y240211D02*
X222785Y239704D01*
G01X222614Y241898D02*
X221771Y241392D01*
G01X218807Y244229D02*
X218478Y244014D01*
G01X217271Y246270D02*
X216942Y246055D01*
G01X217491Y252287D02*
X217381D01*
G01X217930Y252180D02*
X218149D01*
G01X217491Y250783D02*
X219685D01*
G01Y250246D02*
X217491D01*
G01X224508Y249330D02*
X223524D01*
G01X217161Y248312D02*
X219685D01*
G01X224508Y248149D02*
X223524D01*
G01Y248044D02*
X224508D01*
G01Y247748D02*
X223524D01*
G01X217491Y246915D02*
X218368D01*
G01X223524Y246385D02*
X224508D01*
G01X217600Y246377D02*
X218259D01*
G01X224508Y246089D02*
X223524D01*
G01X224508Y245984D02*
X223524D01*
G01X224508Y244803D02*
X223524D01*
G01X219027Y244014D02*
X221441D01*
G01X216174D02*
X216832D01*
G01X218478D02*
X217381D01*
G01X221441Y243476D02*
X216174D01*
G01X217052Y242617D02*
X219685D01*
G01Y242079D02*
X217052D01*
G01Y240898D02*
X219685D01*
G01Y240361D02*
X217052D01*
G01X216942Y239179D02*
X219685D01*
G01X216174D02*
X216503D01*
G01X219685Y238641D02*
X216174D01*
G01X224508Y238523D02*
X223524D01*
G01X224508Y237519D02*
X223524D01*
G01X216832Y240253D02*
X216723Y240146D01*
G01X216613Y240790D02*
X216284Y240468D01*
G01X219466Y244336D02*
X219246Y244121D01*
G01X216832Y241972D02*
X216723Y241865D01*
G01X216503Y242402D02*
X216284Y242187D01*
G01X216832Y246700D02*
X216503Y246377D01*
G01X219246Y252180D02*
X219027Y251965D01*
G01X217052Y250138D02*
X216832Y249923D01*
G01X219027Y252717D02*
X218698Y252394D01*
G01X216723Y250568D02*
X216503Y250353D01*
G01X223401Y245232D02*
X222203Y244033D01*
G01X222706Y245928D02*
X221507Y244729D01*
G01X218807Y246807D02*
X218368Y246915D01*
G01X217930Y251642D02*
X217271Y251750D01*
G01X219027Y244551D02*
X218807Y244229D01*
G01X216503Y246377D02*
X216284Y246055D01*
G01X219466Y252502D02*
X219246Y252180D01*
G01X218588Y246270D02*
X218259Y246377D01*
G01X216503Y250353D02*
X216284Y250031D01*
G01X219575Y244551D02*
X219466Y244336D01*
G01X216723Y240146D02*
X216613Y239931D01*
G01X216723Y241865D02*
X216613Y241650D01*
G01X216942Y246055D02*
X216723Y245626D01*
G01X219137Y252932D02*
X219027Y252717D01*
G01X216832Y249923D02*
X216723Y249708D01*
G01X217052Y244229D02*
X217381Y244014D01*
G01X217161Y252394D02*
X217381Y252287D01*
G01X216832Y251965D02*
X217271Y251750D01*
G01X218588Y246270D02*
X218807Y246163D01*
G01X216613Y244121D02*
X216832Y244014D01*
G01Y241005D02*
X217052Y240898D01*
G01X216284Y240468D02*
X216174Y240146D01*
G01X216284Y242187D02*
X216174Y241865D01*
G01X219575Y252824D02*
X219466Y252502D01*
G01X216284Y250031D02*
X216174Y249708D01*
G01X219685Y244981D02*
X219575Y244551D01*
G01X219137Y244981D02*
X219027Y244551D01*
G01X219246Y253362D02*
X219137Y252932D01*
G01X216832Y252717D02*
X217161Y252394D01*
G01X216613Y252180D02*
X216832Y251965D01*
G01X216942Y248526D02*
X217161Y248312D01*
G01X216503Y248526D02*
X216723Y248312D01*
G01X216393Y244336D02*
X216613Y244121D01*
G01X216723Y241113D02*
X216832Y241005D01*
G01X216284Y241113D02*
X216613Y240790D01*
G01X216723Y239393D02*
X216942Y239179D01*
G01X216284Y239393D02*
X216503Y239179D01*
G01X218807Y246807D02*
X219356Y246377D01*
G01X216284Y246055D02*
X216174Y245626D01*
G01X216723Y249708D02*
X216613Y249279D01*
G01X219685Y253469D02*
X219575Y252824D01*
G01X216723Y254006D02*
X216613Y253362D01*
G01X224508Y256687D02*
X223975Y246521D01*
G01X223524Y256712D02*
X222992Y246572D01*
G01X221441Y244014D02*
Y243476D01*
G01X219685Y237782D02*
Y237137D01*
G01Y239179D02*
Y238641D01*
G01Y240898D02*
Y240361D01*
G01Y242617D02*
Y242079D01*
G01Y245626D02*
Y244981D01*
G01Y248312D02*
Y247774D01*
G01Y250783D02*
Y250246D01*
G01X219137Y245411D02*
Y244981D01*
G01X217930Y255081D02*
Y252180D01*
G01X217491Y254544D02*
Y252287D01*
G01X216723Y244981D02*
Y245626D01*
G01X216613Y239931D02*
Y239716D01*
G01Y241650D02*
Y241327D01*
G01X216174Y249279D02*
Y249708D01*
G01Y244981D02*
Y245626D01*
G01Y243476D02*
Y244014D01*
G01Y241435D02*
Y241865D01*
G01Y239716D02*
Y240146D01*
G01Y238641D02*
Y239179D01*
G01X219137Y254114D02*
X219246Y253362D01*
G01X216174Y253469D02*
X216284Y252824D01*
G01X219575Y246055D02*
X219685Y245626D01*
G01X219027Y245840D02*
X219137Y245411D01*
G01X216613Y253362D02*
X216723Y252932D01*
G01X216613Y249279D02*
X216723Y248849D01*
G01X216174Y249279D02*
X216284Y248849D01*
G01X216723Y244981D02*
X216832Y244551D01*
G01X216174Y244981D02*
X216284Y244551D01*
G01Y252824D02*
X216393Y252502D01*
G01X216174Y241435D02*
X216284Y241113D01*
G01X216613Y239716D02*
X216723Y239393D01*
G01X216174Y239716D02*
X216284Y239393D01*
G01X216723Y252932D02*
X216832Y252717D01*
G01X216284Y244551D02*
X216393Y244336D01*
G01X216613Y241327D02*
X216723Y241113D01*
G01X222055Y242830D02*
X223628Y240211D01*
G01X221211Y242323D02*
X222785Y239704D01*
G01X216393Y252502D02*
X216613Y252180D01*
G01X219356Y246377D02*
X219575Y246055D01*
G01X218807Y246163D02*
X219027Y245840D01*
G01X216723Y248849D02*
X216942Y248526D01*
G01X216284Y248849D02*
X216503Y248526D01*
G01X216832Y244551D02*
X217052Y244229D01*
G01X225591Y260551D02*
G03I-1575J0D01*
G01X224507Y267736D02*
G03X224408Y268274I-1967J-84D01*
G01X217710Y263247D02*
X217271Y263139D01*
G01X217710Y262709D02*
X217271Y262602D01*
G01X218588Y260453D02*
X218149Y260346D01*
G01X217491Y255081D02*
X217052Y254973D01*
G01X218917Y260023D02*
X218149Y259809D01*
G01X217052Y258841D02*
X216723Y258734D01*
G01X217271Y263139D02*
X216942Y263032D01*
G01X217600Y258949D02*
X217052Y258841D01*
G01X217600Y258412D02*
X217052Y258304D01*
G01X217710Y263247D02*
X218149D01*
G01X224508Y263110D02*
X223524D01*
G01X217710Y262709D02*
X218149D01*
G01X224508Y261929D02*
X223524D01*
G01Y261823D02*
X224508D01*
G01Y261528D02*
X223524D01*
G01X218149Y260346D02*
X217710D01*
G01X223524Y260164D02*
X224508D01*
G01Y259869D02*
X223524D01*
G01X218149Y259809D02*
X217710D01*
G01X224508Y259763D02*
X223524D01*
G01X217600Y258949D02*
X219685D01*
G01X224508Y258582D02*
X223524D01*
G01X219685Y258412D02*
X217600D01*
G01X224508Y257696D02*
X223524D01*
G01X224508Y256712D02*
X223524D01*
G01X217161Y256477D02*
X219685D01*
G01X216174D02*
X216723D01*
G01X219685Y255940D02*
X216174D01*
G01X217491Y255081D02*
X217930D01*
G01X217271Y254544D02*
X217491D01*
G01X217271D02*
X216942Y254329D01*
G01X219246Y260238D02*
X218917Y260023D01*
G01Y260668D02*
X218588Y260453D01*
G01X217271Y262602D02*
X216942Y262387D01*
G01Y263032D02*
X216613Y262817D01*
G01X217052Y254973D02*
X216613Y254651D01*
G01X219466Y260453D02*
X219246Y260238D01*
G01X217052Y258304D02*
X216832Y258089D01*
G01X219137Y260883D02*
X218917Y260668D01*
G01X216723Y258734D02*
X216503Y258519D01*
G01X216942Y262387D02*
X216723Y262172D01*
G01X216613Y262817D02*
X216393Y262602D01*
G01X218917Y263032D02*
X218149Y263247D01*
G01X218588Y262602D02*
X218149Y262709D01*
G01X217710Y260346D02*
X217271Y260453D01*
G01X217710Y259809D02*
X217271Y259916D01*
G01X219027Y254973D02*
X218588Y255081D01*
G01X217271Y259916D02*
X216942Y260023D01*
G01X218917Y254436D02*
X218588Y254544D01*
G01X216942Y254329D02*
X216723Y254006D01*
G01X216503Y258519D02*
X216284Y258197D01*
G01X216613Y254651D02*
X216284Y254114D01*
G01X219575Y260668D02*
X219466Y260453D01*
G01X216832Y258089D02*
X216723Y257874D01*
G01X216393Y262602D02*
X216284Y262387D01*
G01X218917Y263032D02*
X219246Y262817D01*
G01X218588Y262602D02*
X218917Y262387D01*
G01X216942Y260668D02*
X217271Y260453D01*
G01X216613Y260238D02*
X216942Y260023D01*
G01X216284Y258197D02*
X216174Y257874D01*
G01X219246Y262817D02*
X219466Y262602D01*
G01X218917Y262387D02*
X219137Y262172D01*
G01X216723Y260883D02*
X216942Y260668D01*
G01X216393Y260453D02*
X216613Y260238D01*
G01X219027Y254973D02*
X219356Y254651D01*
G01X216942Y256692D02*
X217161Y256477D01*
G01X216503Y256692D02*
X216723Y256477D01*
G01X219685Y261098D02*
X219575Y260668D01*
G01X219246Y261313D02*
X219137Y260883D01*
G01X216723Y257874D02*
X216613Y257444D01*
G01X216723Y262172D02*
X216613Y261742D01*
G01X216284Y262387D02*
X216174Y261957D01*
G01X216284Y254114D02*
X216174Y253469D01*
G01X219685Y256477D02*
Y255940D01*
G01Y258949D02*
Y258412D01*
G01Y261957D02*
Y261098D01*
G01Y264644D02*
Y264106D01*
G01X219246Y261742D02*
Y261313D01*
G01X218588Y254544D02*
Y255081D01*
G01X216613Y261313D02*
Y261742D01*
G01X216174Y257444D02*
Y257874D01*
G01Y261098D02*
Y261957D01*
G01Y255940D02*
Y256477D01*
G01X219575Y254221D02*
X219685Y253469D01*
G01X219575Y262387D02*
X219685Y261957D01*
G01X219137Y262172D02*
X219246Y261742D01*
G01X216613Y261313D02*
X216723Y260883D01*
G01X216174Y261098D02*
X216284Y260668D01*
G01X216613Y257444D02*
X216723Y257015D01*
G01X216174Y257444D02*
X216284Y257015D01*
G01X223329Y271529D02*
X224408Y268274D01*
G01X222294Y271520D02*
X223524Y267813D01*
G01X219466Y262602D02*
X219575Y262387D01*
G01X219356Y254651D02*
X219575Y254221D01*
G01X216284Y260668D02*
X216393Y260453D01*
G01X218917Y254436D02*
X219137Y254114D01*
G01X216723Y257015D02*
X216942Y256692D01*
G01X216284Y257015D02*
X216503Y256692D01*
G01X222244Y271830D02*
G03X222294Y271520I985J0D01*
G01X218504Y273523D02*
G03X219685Y272342I1181J0D01*
G01Y281003D02*
G03X218504Y279822I0J-1181D01*
G01X223229Y272148D02*
G03X223329Y271529I1968J0D01*
G01X218760Y282100D02*
G03Y284041I1713J970D01*
G01X217973Y281911D02*
G03Y284230I2500J1159D01*
G01X223544Y283070D02*
G03I-3071J0D01*
G01X216044Y286023D02*
X215512D01*
G01X217559D02*
X217028D01*
G01X216248Y284004D02*
X216824D01*
G01X216929Y283660D02*
X216142D01*
G01Y282635D02*
X216929D01*
G01X216815Y282210D02*
X216257D01*
G01X223229Y281102D02*
X217973D01*
G01X219685Y281003D02*
X223229D01*
G01X217028Y280118D02*
X217559D01*
G01X215512D02*
X216044D01*
G01X216142Y279285D02*
X216929D01*
G01X223229Y278740D02*
X217973D01*
G01X216929Y278002D02*
X216142D01*
G01X217973Y277952D02*
X223229D01*
G01X216142Y277752D02*
X216929D01*
G01Y277698D02*
X216142D01*
G01X216929Y277671D02*
X216142D01*
G01X216044Y276377D02*
X217028D01*
G01X215512Y275846D02*
X217559D01*
G01X217323Y274409D02*
X215748D01*
G01X217973Y272637D02*
X223229D01*
G01Y272342D02*
X219685D01*
G01X216929Y277824D02*
X216142Y277823D01*
G01X216044Y276377D02*
X215512Y275846D01*
G01X222776Y271653D02*
X220079Y274350D01*
G01X221260Y272637D02*
X222244Y271653D01*
G01X217028Y276377D02*
X217559Y275846D01*
G01X215158Y277455D02*
X215355Y278189D01*
G01X215210Y283564D02*
X215205Y283539D01*
G01X216824Y284004D02*
X216929Y284521D01*
G01X216257Y282210D02*
X216142Y281616D01*
G01X215355Y284919D02*
X215240Y283763D01*
G01X223229Y271653D02*
Y316929D01*
G01X222244Y271653D02*
Y295629D01*
G01X221260Y272637D02*
Y272342D01*
G01Y281102D02*
Y272637D01*
G01X220079Y274350D02*
Y295748D01*
G01X218760Y284041D02*
Y282100D01*
G01X218504Y279822D02*
Y273523D01*
G01X217973Y287401D02*
Y271653D01*
G01X217559Y275846D02*
Y304940D01*
G01X217323Y274409D02*
Y271653D01*
G01X217028Y286023D02*
Y304409D01*
G01Y276377D02*
Y280118D01*
G01X216929Y305826D02*
Y277671D01*
G01X216142D02*
Y305826D01*
G01X216044Y280118D02*
Y276377D01*
G01Y304409D02*
Y286023D01*
G01X215748Y274409D02*
Y271653D01*
G01X215591D02*
Y305255D01*
G01X215512Y304940D02*
Y275846D01*
G01X215355Y278189D02*
Y315472D01*
G01X215194Y282665D02*
X215355Y281766D01*
G01X216929Y281616D02*
X216815Y282210D01*
G01X216248Y284004D02*
X216142Y284521D01*
G01X215512Y301574D02*
X216044Y301794D01*
G01X216929Y302401D02*
X216142D01*
G01X216929Y302165D02*
X216142D01*
G01X216929Y301988D02*
X216142D01*
G01Y301811D02*
X216929D01*
G01Y301574D02*
X216142D01*
G01X223229D02*
X217559D01*
G01X216044Y301555D02*
X217028D01*
G01X216142Y301496D02*
X216929D01*
G01X217028Y301240D02*
X216044D01*
G01X216142Y301202D02*
X216929D01*
G01Y301181D02*
X216142D01*
G01X216920Y301141D02*
X216151D01*
G01X216929Y301129D02*
X216142D01*
G01Y301094D02*
X216929D01*
G01X216254Y301039D02*
X216818D01*
G01X216142Y301014D02*
X216929D01*
G01X223229Y300787D02*
X217559D01*
G01X216733Y300783D02*
X216339D01*
G01X217028Y300000D02*
X223229D01*
G01X216339Y298626D02*
X216733D01*
G01X216818Y298370D02*
X216254D01*
G01X216151Y298267D02*
X216920D01*
G01X217028Y298228D02*
X216044D01*
G01X216929Y298015D02*
X216142D01*
G01X216044Y297913D02*
X217028D01*
G01X216044Y297598D02*
X217028D01*
G01X216142Y297582D02*
X216929D01*
G01X216142Y297358D02*
X216929D01*
G01Y296925D02*
X216142D01*
G01X222244Y295728D02*
X223229D01*
G01Y295629D02*
X222244D01*
G01Y294547D02*
X223229D01*
G01Y294153D02*
X222244D01*
G01X223229Y293366D02*
X222115D01*
G01X221260Y288543D02*
X222244D01*
G01Y288051D02*
X223229D01*
G01Y287401D02*
X217973D01*
G01X223229Y286614D02*
X217973D01*
G01X222266Y288966D02*
X221300Y289153D01*
G01X217028Y301794D02*
X217559Y301574D01*
G01X216151Y298267D02*
X216254Y298370D01*
G01X216818Y301039D02*
X216920Y301141D01*
G01X215512Y300787D02*
X216044Y301318D01*
G01D02*
X215512Y300787D01*
G01X217028Y301318D02*
X217559Y300787D01*
G01D02*
X217028Y301318D01*
G01X216254Y301039D02*
X216151Y301141D01*
G01X216818Y298370D02*
X216920Y298267D01*
G01X223229Y293940D02*
X222266Y288966D01*
G01X222244Y294035D02*
X221300Y289153D01*
G01X222244Y295629D02*
Y295728D01*
G01X221260Y305511D02*
Y288543D01*
G01X216733Y300783D02*
Y298626D01*
G01X216339D02*
Y300783D01*
G01X215453Y305118D02*
Y295748D01*
G01X223229Y316929D02*
X220079D01*
G01Y316141D02*
X223229D01*
G01X216063Y313385D02*
X223229D01*
G01X220079Y312598D02*
X223229D01*
G01X220079Y312204D02*
X223229D01*
G01Y311417D02*
X220079D01*
G01Y310629D02*
X223229D01*
G01X216929Y305826D02*
X216142D01*
G01X216929Y305236D02*
X216142D01*
G01X217559Y304940D02*
X215512D01*
G01X217028Y304409D02*
X216044D01*
G01X216929Y304330D02*
X216142D01*
G01Y304094D02*
X216929D01*
G01Y303917D02*
X216142D01*
G01X216929Y303543D02*
X216142D01*
G01X216929Y303503D02*
X216142D01*
G01X217028Y304409D02*
X217559Y304940D01*
G01X215847Y305511D02*
X215453Y305118D01*
G01X216063Y313385D02*
X215473Y312795D01*
G01X215512Y304940D02*
X216044Y304409D01*
G01X220079Y312598D02*
Y316929D01*
G01Y312204D02*
Y307086D01*
G01X215748Y305511D02*
Y303543D01*
G01X215473Y311141D02*
Y312795D01*
G01X232363Y729409D02*
G03I-2245J0D01*
G01X222363D02*
G03I-2245J0D01*
G01X229368Y728659D02*
X230868D01*
G01X219368D02*
X220868D01*
G01X228868Y728159D02*
X231368D01*
G01X218868D02*
X221368D01*
G01X230868Y728659D02*
X231368Y728159D01*
G01X220868Y728659D02*
X221368Y728159D01*
G01X230868Y728659D02*
Y730159D01*
G01X229368D02*
Y728659D01*
G01X228868Y730659D02*
Y728159D01*
G01X226618Y745909D02*
Y722909D01*
G01X223618D02*
Y745909D01*
G01X221368Y728159D02*
Y730659D01*
G01X220868Y728659D02*
Y730159D01*
G01X219368D02*
Y728659D01*
G01X218868Y730659D02*
Y728159D01*
G01X217018Y716909D02*
Y721909D01*
G01X216618Y745909D02*
Y722909D01*
G01X229368Y728659D02*
X228868Y728159D01*
G01X219368Y728659D02*
X218868Y728159D01*
G01X232363Y739409D02*
G03I-2245J0D01*
G01X222363D02*
G03I-2245J0D01*
G01X221368Y740659D02*
X218868D01*
G01X231368D02*
X228868D01*
G01X220868Y740159D02*
X219368D01*
G01X230868D02*
X229368D01*
G01Y738659D02*
X230868D01*
G01X219368D02*
X220868D01*
G01X228868Y738159D02*
X231368D01*
G01X218868D02*
X221368D01*
G01Y730659D02*
X218868D01*
G01X231368D02*
X228868D01*
G01X220868Y730159D02*
X219368D01*
G01X230868D02*
X229368D01*
G01Y740159D02*
X228868Y740659D01*
G01X230868Y738659D02*
X231368Y738159D01*
G01X219368Y740159D02*
X218868Y740659D01*
G01X229368Y730159D02*
X228868Y730659D01*
G01X220868Y738659D02*
X221368Y738159D01*
G01X219368Y730159D02*
X218868Y730659D01*
G01X230868Y738659D02*
Y740159D01*
G01X229368D02*
Y738659D01*
G01X228868Y740659D02*
Y738159D01*
G01X221368D02*
Y740659D01*
G01X220868Y738659D02*
Y740159D01*
G01X219368D02*
Y738659D01*
G01X218868Y740659D02*
Y738159D01*
G01X230868Y730159D02*
X231368Y730659D01*
G01X230868Y740159D02*
X231368Y740659D01*
G01X220868Y730159D02*
X221368Y730659D01*
G01X229368Y738659D02*
X228868Y738159D01*
G01X220868Y740159D02*
X221368Y740659D01*
G01X219368Y738659D02*
X218868Y738159D01*
G01X222751Y1008622D02*
G03X231333I4291J0D01*
G01D02*
G03X222751I-4291J0D01*
G01X236025Y164487D02*
Y70866D01*
G01D02*
G03X247836Y59055I11811J0D01*
G01X236025Y164487D02*
Y70866D01*
G01D02*
G03X247836Y59055I11811J0D01*
G01X243898Y70866D02*
G03X247835Y66928I3937J-1D01*
G01X243898Y224448D02*
Y70866D01*
G01D02*
G03X247835Y66929I3937J0D01*
G01X243898Y70866D02*
G03X247835Y66929I3937J0D01*
G01X243898Y175196D02*
Y70866D01*
G01Y224448D02*
Y70866D01*
G01X243899Y164487D02*
G03X236025I-3937J0D01*
G01X243899D02*
G03X236025I-3937J0D01*
G01Y189684D02*
G03X243899I3937J0D01*
G01X236025D02*
G03X243899I3937J0D01*
G01X293111Y175196D02*
X243898D01*
G01X236025Y189684D02*
Y216574D01*
G01Y189684D02*
Y216574D01*
G01D02*
G03X232088Y220511I-3937J0D01*
G01X236025Y216574D02*
G03X232088Y220511I-3937J0D01*
G01X243898Y224448D02*
G03X239961Y228385I-3937J0D01*
G01X243898Y224448D02*
G03X239961Y228385I-3937J0D01*
G01X232087D02*
Y429133D01*
G01X242363Y729409D02*
G03I-2245J0D01*
G01X239368Y728659D02*
X240868D01*
G01X238868Y728159D02*
X241368D01*
G01X285906Y721122D02*
X233218D01*
G01X290118Y716909D02*
X233218D01*
G01X240868Y728659D02*
X241368Y728159D01*
G01X246618Y745909D02*
Y722909D01*
G01X243618D02*
Y745909D01*
G01X241368Y728159D02*
Y730659D01*
G01X240868Y728659D02*
Y730159D01*
G01X239368D02*
Y728659D01*
G01X238868Y730659D02*
Y728159D01*
G01X236618Y745909D02*
Y722909D01*
G01X233618D02*
Y745909D01*
G01X233218Y716909D02*
Y721909D01*
G01X231368Y728159D02*
Y730659D01*
G01X239368Y728659D02*
X238868Y728159D01*
G01X242363Y739409D02*
G03I-2245J0D01*
G01X241368Y740659D02*
X238868D01*
G01X240868Y740159D02*
X239368D01*
G01Y738659D02*
X240868D01*
G01X238868Y738159D02*
X241368D01*
G01Y730659D02*
X238868D01*
G01X240868Y730159D02*
X239368D01*
G01Y740159D02*
X238868Y740659D01*
G01X240868Y738659D02*
X241368Y738159D01*
G01X239368Y730159D02*
X238868Y730659D01*
G01X241368Y738159D02*
Y740659D01*
G01X240868Y738659D02*
Y740159D01*
G01X239368D02*
Y738659D01*
G01X238868Y740659D02*
Y738159D01*
G01X231368D02*
Y740659D01*
G01X240868Y730159D02*
X241368Y730659D01*
G01X240868Y740159D02*
X241368Y740659D01*
G01X239368Y738659D02*
X238868Y738159D01*
G01X237877Y996063D02*
G03Y988189I0J-3937D01*
G01Y996063D02*
G03Y988189I0J-3937D01*
G01X257284Y996063D02*
X237877D01*
G01X257284D02*
X237877D01*
G01X247836Y59055D02*
X285237D01*
G01X247836D02*
X285237D01*
G01X247835Y66929D02*
X289174D01*
G01X247835D02*
X289174D01*
G01X247835D02*
X289174D01*
G01X276378Y92126D02*
G03I-6299J0D01*
G01X258212Y121227D02*
X253298D01*
G01X260670Y120868D02*
X263478D01*
G01Y120151D02*
X260670D01*
G01X253298Y117283D02*
X252244D01*
G01X259265D02*
X258212D01*
G01X263478Y120868D02*
Y120151D01*
G01X260670D02*
Y120868D01*
G01X259265Y125708D02*
Y117283D01*
G01X258212D02*
Y121227D01*
G01X253298D02*
Y117283D01*
G01X252244D02*
Y125708D01*
G01X258212D02*
X259265D01*
G01X252244D02*
X253298D01*
G01X260670Y123019D02*
X263478D01*
G01X253298Y122302D02*
X258212D01*
G01X263478D02*
X260670D01*
G01X263478Y123019D02*
Y122302D01*
G01X260670D02*
Y123019D01*
G01X258212Y122302D02*
Y125708D01*
G01X253298D02*
Y122302D01*
G01X276378Y155118D02*
G03I-6299J0D01*
G01X262510Y318031D02*
X269292D01*
G01X254803D02*
X260661D01*
G01X269292Y316220D02*
X254803D01*
G01X262510Y326483D02*
Y318031D01*
G01X260661D02*
Y326483D01*
G01X254803Y316220D02*
Y318031D01*
G01X260661Y330708D02*
X259427D01*
G01X264359D02*
X263127D01*
G01X254803Y328294D02*
X269292D01*
G01X260661Y326483D02*
X254803D01*
G01X269292D02*
X262510D01*
G01X263127Y330708D02*
Y335538D01*
G01X260661D02*
Y330708D01*
G01X259427D02*
Y335538D01*
G01X254803Y326483D02*
Y328294D01*
G01X263127Y337952D02*
X265284Y338254D01*
G01X269292Y351233D02*
X259427D01*
G01X265284Y348818D02*
X263743D01*
G01X261585Y339461D02*
X260969D01*
G01Y337952D02*
X263127D01*
G01Y335538D02*
X264359D01*
G01X259427D02*
X260661D01*
G01X264051Y347309D02*
X263127Y347007D01*
G01X258194Y348215D02*
X257270Y347913D01*
G01X263743Y348818D02*
X262202Y348215D01*
G01X260969Y339461D02*
X259119Y339763D01*
G01X258811Y338254D02*
X260969Y337952D01*
G01X257270Y346102D02*
X258194Y346705D01*
G01X263127Y340065D02*
X264051Y339763D01*
G01X259119D02*
X258194Y340065D01*
G01X257270Y347913D02*
X256037Y347007D01*
G01X257270Y338858D02*
X258811Y338254D01*
G01X263127Y347007D02*
X262510Y346404D01*
G01X262202Y348215D02*
X261277Y347309D01*
G01X256037Y339763D02*
X257270Y338858D01*
G01X258194Y340065D02*
X257270Y340669D01*
G01X262510Y346404D02*
X261894Y345498D01*
G01X256653Y345196D02*
X257270Y346102D01*
G01X261277Y347309D02*
X260352Y345800D01*
G01X256037Y347007D02*
X255112Y345498D01*
G01Y341272D02*
X256037Y339763D01*
G01X261894Y341574D02*
X262510Y340669D01*
G01X260352Y341272D02*
X261585Y339461D01*
G01X257270Y340669D02*
X256653Y341574D01*
G01X262510Y340669D02*
X263127Y340065D01*
G01X261894Y345498D02*
X261585Y344593D01*
G01X256345Y344291D02*
X256653Y345196D01*
G01X260352Y345800D02*
X260044Y344291D01*
G01X255112Y345498D02*
X254803Y343989D01*
G01X260044Y342782D02*
X260352Y341272D01*
G01X254803Y342782D02*
X255112Y341272D01*
G01X261585Y342480D02*
X261894Y341574D01*
G01X256653D02*
X256345Y342480D01*
G01X261585Y344593D02*
Y342480D01*
G01X260044Y344291D02*
Y342782D01*
G01X259427Y351233D02*
Y352742D01*
G01X258194Y346705D02*
Y348215D01*
G01X256345Y342480D02*
Y344291D01*
G01X254803Y343989D02*
Y342782D01*
G01X259427Y366325D02*
X260352D01*
G01X261585D02*
X269292D01*
G01Y364816D02*
X259427D01*
G01X261894Y362401D02*
X269292D01*
G01Y360892D02*
X261894D01*
G01Y357572D02*
X269292D01*
G01Y356063D02*
X261894D01*
G01X259427Y352742D02*
X260352D01*
G01X261585D02*
X269292D01*
G01X260352Y361798D02*
X261894Y362401D01*
G01Y356063D02*
X261277Y355761D01*
G01X261894Y360892D02*
X261277Y360590D01*
G01Y357874D02*
X261894Y357572D01*
G01X261277Y355761D02*
X260969Y355459D01*
G01X259736Y356365D02*
X260661Y357270D01*
G01X261277Y360590D02*
X260969Y360288D01*
G01X259736Y361194D02*
X260352Y361798D01*
G01X260969Y366929D02*
X261585Y366325D01*
G01X260352D02*
X259736Y366929D01*
G01X260969Y358176D02*
X261277Y357874D01*
G01X260661Y357270D02*
X259736Y358176D01*
G01X260969Y353346D02*
X261585Y352742D01*
G01X260352D02*
X259736Y353346D01*
G01X260969Y355459D02*
X260661Y354855D01*
G01X260969Y360288D02*
X260661Y359685D01*
G01Y358779D02*
X260969Y358176D01*
G01X259427Y355459D02*
X259736Y356365D01*
G01X259427Y360288D02*
X259736Y361194D01*
G01X260661Y367834D02*
X260969Y366929D01*
G01X259736D02*
X259427Y367834D01*
G01X259736Y358176D02*
X259427Y359081D01*
G01X260661Y354252D02*
X260969Y353346D01*
G01X259736D02*
X259427Y354252D01*
G01X260661Y354855D02*
Y354252D01*
G01Y359685D02*
Y358779D01*
G01Y368438D02*
Y367834D01*
G01X259427Y364816D02*
Y366325D01*
G01Y367834D02*
Y369042D01*
G01Y359081D02*
Y360288D01*
G01Y354252D02*
Y355459D01*
G01X261894Y375984D02*
X269292D01*
G01Y374475D02*
X261894D01*
G01Y371154D02*
X269292D01*
G01Y369645D02*
X261894D01*
G01X260352Y375380D02*
X261894Y375984D01*
G01Y369645D02*
X261277Y369343D01*
G01X261894Y374475D02*
X261277Y374173D01*
G01Y371456D02*
X261894Y371154D01*
G01X261277Y369343D02*
X260969Y369042D01*
G01X259736Y369947D02*
X260661Y370853D01*
G01X261277Y374173D02*
X260969Y373871D01*
G01X259736Y374776D02*
X260352Y375380D01*
G01X260969Y371758D02*
X261277Y371456D01*
G01X260661Y370853D02*
X259736Y371758D01*
G01X260661Y372362D02*
X260969Y371758D01*
G01Y369042D02*
X260661Y368438D01*
G01X260969Y373871D02*
X260661Y373267D01*
G01X259427Y369042D02*
X259736Y369947D01*
G01X259427Y373871D02*
X259736Y374776D01*
G01Y371758D02*
X259427Y372664D01*
G01X260661Y373267D02*
Y372362D01*
G01X259427Y372664D02*
Y373871D01*
G01X262363Y729409D02*
G03I-2245J0D01*
G01X252363D02*
G03I-2245J0D01*
G01X259368Y728659D02*
X260868D01*
G01X249368D02*
X250868D01*
G01X258868Y728159D02*
X261368D01*
G01X251368D02*
X248868D01*
G01X260868Y728659D02*
X261368Y728159D01*
G01X250868Y728659D02*
X251368Y728159D01*
G01X263618Y722909D02*
Y745909D01*
G01X261368Y728159D02*
Y730659D01*
G01X260868Y728659D02*
Y730159D01*
G01X259368D02*
Y728659D01*
G01X258868Y730659D02*
Y728159D01*
G01X256618Y745909D02*
Y722909D01*
G01X253618D02*
Y745909D01*
G01X251368Y728159D02*
Y730659D01*
G01X250868Y728659D02*
Y730159D01*
G01X249368D02*
Y728659D01*
G01X248868Y730659D02*
Y728159D01*
G01X259368Y728659D02*
X258868Y728159D01*
G01X249368Y728659D02*
X248868Y728159D01*
G01X262363Y739409D02*
G03I-2245J0D01*
G01X252363D02*
G03I-2245J0D01*
G01X251368Y740659D02*
X248868D01*
G01X261368D02*
X258868D01*
G01X250868Y740159D02*
X249368D01*
G01X260868D02*
X259368D01*
G01Y738659D02*
X260868D01*
G01X249368D02*
X250868D01*
G01X258868Y738159D02*
X261368D01*
G01X251368D02*
X248868D01*
G01X251368Y730659D02*
X248868D01*
G01X261368D02*
X258868D01*
G01X250868Y730159D02*
X249368D01*
G01X260868D02*
X259368D01*
G01Y740159D02*
X258868Y740659D01*
G01X260868Y738659D02*
X261368Y738159D01*
G01X249368Y740159D02*
X248868Y740659D01*
G01X259368Y730159D02*
X258868Y730659D01*
G01X250868Y738659D02*
X251368Y738159D01*
G01X249368Y730159D02*
X248868Y730659D01*
G01X261368Y738159D02*
Y740659D01*
G01X260868Y738659D02*
Y740159D01*
G01X259368D02*
Y738659D01*
G01X258868Y740659D02*
Y738159D01*
G01X251368D02*
Y740659D01*
G01X250868Y738659D02*
Y740159D01*
G01X249368D02*
Y738659D01*
G01X248868Y740659D02*
Y738159D01*
G01X260868Y730159D02*
X261368Y730659D01*
G01X260868Y740159D02*
X261368Y740659D01*
G01X250868Y730159D02*
X251368Y730659D01*
G01X259368Y738659D02*
X258868Y738159D01*
G01X250868Y740159D02*
X251368Y740659D01*
G01X249368Y738659D02*
X248868Y738159D01*
G01X261220Y988189D02*
G03X265157Y992126I0J3937D01*
G01X261221Y988189D02*
G03X265158Y992126I0J3937D01*
G01X257284Y1023622D02*
Y996063D01*
G01Y1023622D02*
Y996063D01*
G01X269095Y117462D02*
X269972Y118000D01*
G01X268919Y118359D02*
X269446Y118717D01*
G01X276642Y122123D02*
X276467Y121944D01*
G01X269972Y118000D02*
X270499Y118538D01*
G01X273834Y122123D02*
X273483Y121765D01*
G01X268042Y117283D02*
X269095Y117462D01*
G01X268042Y118179D02*
X268919Y118359D01*
G01X269446Y118717D02*
X270148Y119792D01*
G01X276467Y121944D02*
X276291Y121585D01*
G01X270499Y118538D02*
X270850Y119255D01*
G01X273483Y117283D02*
X272605D01*
G01X276291D02*
X275414D01*
G01X279100D02*
X278222D01*
G01X270850Y119255D02*
X271025Y119792D01*
G01X267164Y118359D02*
X268042Y118179D01*
G01X266988Y117462D02*
X268042Y117283D01*
G01X271025Y119792D02*
X271201Y120689D01*
G01X270148Y119792D02*
X270324Y120868D01*
G01X279100Y121585D02*
Y117283D01*
G01X278222D02*
Y121585D01*
G01X276291D02*
Y117283D01*
G01X265760Y120868D02*
X265935Y119792D01*
G01X264882Y120689D02*
X265058Y119792D01*
G01X275414Y117283D02*
Y121585D01*
G01X273483Y121765D02*
Y117283D01*
G01X272605D02*
Y123019D01*
G01X271201Y120689D02*
Y122302D01*
G01X270324Y120868D02*
Y122123D01*
G01X265760D02*
Y120868D01*
G01X264882Y122302D02*
Y120689D01*
G01X265058Y119792D02*
X265233Y119255D01*
G01X278749Y122481D02*
X279100Y121585D01*
G01X278222D02*
X278047Y121944D01*
G01X275414Y121585D02*
X275238Y121944D01*
G01X265233Y119255D02*
X265584Y118538D01*
G01X265935Y119792D02*
X266637Y118717D01*
G01X278047Y121944D02*
X277871Y122123D01*
G01X275238Y121944D02*
X275063Y122123D01*
G01X265584Y118538D02*
X266111Y118000D01*
G01X266637Y118717D02*
X267164Y118359D01*
G01X266111Y118000D02*
X266988Y117462D01*
G01X276642Y122840D02*
X277169Y123019D01*
G01X274361Y122302D02*
X273834Y122123D01*
G01Y122840D02*
X274361Y123019D01*
G01X276994Y122302D02*
X276642Y122123D01*
G01X266988Y125529D02*
X266111Y124991D01*
G01X267164Y124633D02*
X266637Y124274D01*
G01X276116Y122302D02*
X276642Y122840D01*
G01X273483Y122481D02*
X273834Y122840D01*
G01X266111Y124991D02*
X265584Y124453D01*
G01X268042Y125708D02*
X266988Y125529D01*
G01X268042Y124812D02*
X267164Y124633D01*
G01X266637Y124274D02*
X265935Y123199D01*
G01X265584Y124453D02*
X265233Y123736D01*
G01X277169Y123019D02*
X277871D01*
G01X272605D02*
X273483D01*
G01X274361D02*
X275063D01*
G01X274712Y122302D02*
X274361D01*
G01X277520D02*
X276994D01*
G01X265233Y123736D02*
X265058Y123199D01*
G01X277871Y123019D02*
X278398Y122840D01*
G01X275063Y123019D02*
X275589Y122840D01*
G01X268919Y124633D02*
X268042Y124812D01*
G01X269095Y125529D02*
X268042Y125708D01*
G01X265058Y123199D02*
X264882Y122302D01*
G01X265935Y123199D02*
X265760Y122123D01*
G01X270324D02*
X270148Y123199D01*
G01X271201Y122302D02*
X271025Y123199D01*
G01X269972Y124991D02*
X269095Y125529D01*
G01X277871Y122123D02*
X277520Y122302D01*
G01X275063Y122123D02*
X274712Y122302D01*
G01X273483Y123019D02*
Y122481D01*
G01X271025Y123199D02*
X270850Y123736D01*
G01D02*
X270499Y124453D01*
G01X270148Y123199D02*
X269446Y124274D01*
G01X278398Y122840D02*
X278749Y122481D01*
G01X275589Y122840D02*
X276116Y122302D01*
G01X270499Y124453D02*
X269972Y124991D01*
G01X269446Y124274D02*
X268919Y124633D01*
G01X269292Y318031D02*
Y316220D01*
G01Y328294D02*
Y326483D01*
G01X264359Y335538D02*
Y330708D01*
G01X264976Y347309D02*
X264051D01*
G01Y339763D02*
X264976D01*
G01D02*
X265901Y340065D01*
G01X265284Y338254D02*
X266825Y338858D01*
G01X265901Y340065D02*
X266825Y340669D01*
G01Y348215D02*
X265284Y348818D01*
G01X265901Y347007D02*
X264976Y347309D01*
G01X266825Y338858D02*
X268059Y339763D01*
G01Y347309D02*
X266825Y348215D01*
G01Y346404D02*
X265901Y347007D01*
G01X266825Y340669D02*
X267442Y341574D01*
G01X268059Y339763D02*
X268983Y341272D01*
G01Y345800D02*
X268059Y347309D01*
G01X267442Y345498D02*
X266825Y346404D01*
G01X267442Y341574D02*
X267750Y342480D01*
G01X268983Y341272D02*
X269292Y342782D01*
G01Y344291D02*
X268983Y345800D01*
G01X267750Y344593D02*
X267442Y345498D01*
G01X269292Y342782D02*
Y344291D01*
G01Y352742D02*
Y351233D01*
G01X267750Y342480D02*
Y344593D01*
G01X269292Y357572D02*
Y356063D01*
G01Y362401D02*
Y360892D01*
G01Y366325D02*
Y364816D01*
G01Y371154D02*
Y369645D01*
G01Y375984D02*
Y374475D01*
G01X272363Y729409D02*
G03I-2245J0D01*
G01X269368Y728659D02*
X270868D01*
G01X268868Y728159D02*
X271368D01*
G01X284114Y722909D02*
X278114D01*
G01X284114Y718909D02*
X273614D01*
G01X270868Y728659D02*
X271368Y728159D01*
G01X278114Y745909D02*
Y722909D01*
G01X273614Y718909D02*
Y745909D01*
G01X271368Y728159D02*
Y730659D01*
G01X270868Y728659D02*
Y730159D01*
G01X269368D02*
Y728659D01*
G01X268868Y730659D02*
Y728159D01*
G01X266618Y745909D02*
Y722909D01*
G01X269368Y728659D02*
X268868Y728159D01*
G01X272363Y739409D02*
G03I-2245J0D01*
G01X271368Y740659D02*
X268868D01*
G01X270868Y740159D02*
X269368D01*
G01Y738659D02*
X270868D01*
G01X268868Y738159D02*
X271368D01*
G01Y730659D02*
X268868D01*
G01X270868Y730159D02*
X269368D01*
G01Y740159D02*
X268868Y740659D01*
G01X270868Y738659D02*
X271368Y738159D01*
G01X269368Y730159D02*
X268868Y730659D01*
G01X271368Y738159D02*
Y740659D01*
G01X270868Y738659D02*
Y740159D01*
G01X269368D02*
Y738659D01*
G01X268868Y740659D02*
Y738159D01*
G01X270868Y730159D02*
X271368Y730659D01*
G01X270868Y740159D02*
X271368Y740659D01*
G01X269368Y738659D02*
X268868Y738159D01*
G01X265157Y1018109D02*
Y992126D01*
G01X265158Y1021653D02*
Y992126D01*
G01X278150Y1001574D02*
X280906D01*
G01X274213D02*
X276969D01*
G01X266339D02*
X269095D01*
G01X273032D02*
X270276D01*
G01X278150Y1018110D02*
Y1001574D01*
G01X276969D02*
Y1018110D01*
G01X274213D02*
Y1001574D01*
G01X273032Y1014173D02*
Y1001574D01*
G01X270276D02*
Y1014173D01*
G01X269095Y1001574D02*
Y1018110D01*
G01X266339D02*
Y1001574D01*
G01X265158Y1021653D02*
X265157Y1018109D01*
G01X543505Y1023622D02*
X267127D01*
G01D02*
X265158Y1021653D01*
G01X543504Y1023622D02*
X267126D01*
G01X269095Y1018110D02*
X266339D01*
G01X545473D02*
X265158D01*
G01X276969D02*
X274213D01*
G01X280906D02*
X278150D01*
G01X270276Y1014173D02*
X273032D01*
G01X267126Y1023622D02*
X265158Y1021653D01*
G01X285237Y3937D02*
G03X297048Y-7874I11811J0D01*
G01X285237Y59055D02*
Y3937D01*
G01D02*
G03X297048Y-7874I11811J0D01*
G01X285237Y59055D02*
Y3937D01*
G01X293111D02*
G03X297047Y0I3937J0D01*
G01X293110Y62992D02*
Y3937D01*
G01X293111D02*
G03X297048Y0I3937J0D01*
G01X293111Y62992D02*
Y3937D01*
G01Y62992D02*
G03X289174Y66929I-3937J0D01*
G01X293111Y62992D02*
G03X289174Y66929I-3937J0D01*
G01X293111Y62992D02*
G03X289174Y66929I-3937J0D01*
G01X293111Y175196D02*
Y65748D01*
G01X284541Y122123D02*
X284366Y121944D01*
G01X281733Y122123D02*
X281381Y121765D01*
G01X284366Y121944D02*
X284190Y121585D01*
G01X281381Y117283D02*
X280504D01*
G01X284190D02*
X283313D01*
G01X286998D02*
X286121D01*
G01X286998Y121585D02*
Y117283D01*
G01X286121D02*
Y121585D01*
G01X284190D02*
Y117283D01*
G01X283313D02*
Y121585D01*
G01X281381Y121765D02*
Y117283D01*
G01X280504D02*
Y123019D01*
G01X286647Y122481D02*
X286998Y121585D01*
G01X286121D02*
X285945Y121944D01*
G01X283313Y121585D02*
X283137Y121944D01*
G01X285945D02*
X285770Y122123D01*
G01X283137Y121944D02*
X282961Y122123D01*
G01X284541Y122840D02*
X285068Y123019D01*
G01X282259Y122302D02*
X281733Y122123D01*
G01Y122840D02*
X282259Y123019D01*
G01X284892Y122302D02*
X284541Y122123D01*
G01X284014Y122302D02*
X284541Y122840D01*
G01X281381Y122481D02*
X281733Y122840D01*
G01X282259Y123019D02*
X282961D01*
G01X285068D02*
X285770D01*
G01X280504D02*
X281381D01*
G01X285419Y122302D02*
X284892D01*
G01X282610D02*
X282259D01*
G01X285770Y123019D02*
X286296Y122840D01*
G01X282961Y123019D02*
X283488Y122840D01*
G01X281381Y123019D02*
Y122481D01*
G01X285770Y122123D02*
X285419Y122302D01*
G01X282961Y122123D02*
X282610Y122302D01*
G01X286296Y122840D02*
X286647Y122481D01*
G01X283488Y122840D02*
X284014Y122302D01*
G01X286418Y175196D02*
Y429133D01*
G01X285906Y721122D02*
X285118Y721909D01*
G01X290118Y751909D02*
Y716909D01*
G01X285906Y721122D02*
Y747696D01*
G01X285118Y721909D02*
Y746909D01*
G01X284114Y745909D02*
Y718909D01*
G01X285906Y747696D02*
X285118Y746909D01*
G01X293898Y1001574D02*
X296654D01*
G01X286024D02*
X288780D01*
G01X289961D02*
X292717D01*
G01X282087D02*
X284843D01*
G01X296654D02*
Y1018110D01*
G01X293898D02*
Y1001574D01*
G01X292717D02*
Y1018110D01*
G01X289961D02*
Y1001574D01*
G01X288780D02*
Y1018110D01*
G01X286024D02*
Y1001574D01*
G01X284843D02*
Y1018110D01*
G01X282087D02*
Y1001574D01*
G01X280906D02*
Y1018110D01*
G01X284843D02*
X282087D01*
G01X288780D02*
X286024D01*
G01X292717D02*
X289961D01*
G01X296654D02*
X293898D01*
G01X297037Y-7874D02*
X301187D01*
G01D02*
G03Y0I0J3937D01*
G01X297037Y-7874D02*
X301187D01*
G01D02*
G03Y0I0J3937D01*
G01X297047D02*
X1108209D01*
G01X297048D02*
X1108209D01*
G01X309646Y1001574D02*
X312402D01*
G01X305709D02*
X308465D01*
G01X301772D02*
X304528D01*
G01X297835D02*
X300591D01*
G01X312402D02*
Y1018110D01*
G01X309646D02*
Y1001574D01*
G01X308465D02*
Y1018110D01*
G01X305709D02*
Y1001574D01*
G01X304528D02*
Y1018110D01*
G01X301772D02*
Y1001574D01*
G01X300591D02*
Y1018110D01*
G01X297835D02*
Y1001574D01*
G01X300591Y1018110D02*
X297835D01*
G01X304528D02*
X301772D01*
G01X308465D02*
X305709D01*
G01X312402D02*
X309646D01*
G01X318510Y-7874D02*
X515333D01*
G01X318510Y0D02*
G03Y-7874I0J-3937D01*
G01D02*
X515333D01*
G01X318510Y0D02*
G03Y-7874I0J-3937D01*
G01X332087Y422637D02*
G03Y395078I0J-13780D01*
G01X338977Y408858D02*
G03I-6890J0D01*
G01D02*
G03I-6890J0D01*
G01X329331Y1001574D02*
X332087D01*
G01X325394D02*
X328150D01*
G01X321457D02*
X324213D01*
G01X317520D02*
X320276D01*
G01X313583D02*
X316339D01*
G01X329331Y1018110D02*
Y1001574D01*
G01X328150D02*
Y1018110D01*
G01X325394D02*
Y1001574D01*
G01X324213D02*
Y1018110D01*
G01X321457D02*
Y1001574D01*
G01X320276D02*
Y1018110D01*
G01X317520D02*
Y1001574D01*
G01X316339D02*
Y1018110D01*
G01X313583D02*
Y1001574D01*
G01X316339Y1018110D02*
X313583D01*
G01X320276D02*
X317520D01*
G01X324213D02*
X321457D01*
G01X328150D02*
X325394D01*
G01X332087D02*
X329331D01*
G01X341929Y96456D02*
G03X369488I13780J0D01*
G01X341929Y246063D02*
Y96456D01*
G01X463977Y108267D02*
X341929D01*
G01Y246063D02*
X463977D01*
G01X338800Y299803D02*
X340276D01*
G01X330433D02*
X331910D01*
G01X342244Y296033D02*
X346181D01*
G01X331910Y295028D02*
X338800D01*
G01X346181D02*
X342244D01*
G01X338800Y293520D02*
X331910D01*
G01X342244Y293018D02*
X346181D01*
G01Y292013D02*
X342244D01*
G01X331910Y287992D02*
X330433D01*
G01X340276D02*
X338800D01*
G01X342244Y295028D02*
Y296033D01*
G01Y292013D02*
Y293018D01*
G01X340276Y299803D02*
Y287992D01*
G01X338800Y295028D02*
Y299803D01*
G01Y287992D02*
Y293520D01*
G01X331910D02*
Y287992D01*
G01Y299803D02*
Y295028D01*
G01X330433Y287992D02*
Y299803D01*
G01X884646Y324212D02*
X343898D01*
G01D02*
Y422637D01*
G01Y387204D02*
G03X336024Y395078I-7874J0D01*
G01X332087D02*
X336024D01*
G01X560433Y422637D02*
X332087D01*
G01X345079Y1001574D02*
X347835D01*
G01X341142D02*
X343898D01*
G01X333268D02*
X336024D01*
G01X337205D02*
X339961D01*
G01X345079Y1018110D02*
Y1001574D01*
G01X343898D02*
Y1018110D01*
G01X341142D02*
Y1001574D01*
G01X339961D02*
Y1018110D01*
G01X337205D02*
Y1001574D01*
G01X336024D02*
Y1018110D01*
G01X333268D02*
Y1001574D01*
G01X332087D02*
Y1018110D01*
G01X336024D02*
X333268D01*
G01X339961D02*
X337205D01*
G01X343898D02*
X341142D01*
G01X347835D02*
X345079D01*
G01X362599Y96456D02*
G03I-6890J0D01*
G01D02*
G03I-6890J0D01*
G01X452166Y127952D02*
X353740D01*
G01D02*
Y226377D01*
G01X355906Y220826D02*
X359292Y224212D01*
G01X353740Y226377D02*
X452166D01*
G01X355906Y224212D02*
X359292D01*
G01X355906D02*
Y220826D01*
G01X354548Y299049D02*
X355532Y299552D01*
G01D02*
X357254Y299803D01*
G01X357008Y298546D02*
X355778Y298295D01*
G01D02*
X355040Y297792D01*
G01X357254Y299803D02*
X358238D01*
G01X349626D02*
X351103D01*
G01X357992Y298546D02*
X357008D01*
G01X354548Y297039D02*
X353317D01*
G01X355040Y289248D02*
X361929D01*
G01X351103Y287992D02*
X349626D01*
G01X361929D02*
X353071D01*
G01X361191Y294777D02*
X355040Y289248D01*
G01X353071D02*
X359961Y295531D01*
G01X353563Y298044D02*
X354548Y299049D01*
G01X359223Y298295D02*
X357992Y298546D01*
G01X358238Y299803D02*
X359715Y299552D01*
G01X349626Y297792D02*
X348150Y296033D01*
G01Y298044D02*
X349626Y299803D01*
G01X361683Y295531D02*
X361191Y294777D01*
G01X355040Y297792D02*
X354548Y297039D01*
G01X359961Y297792D02*
X359223Y298295D01*
G01X359715Y299552D02*
X360699Y299049D01*
G01X359961Y295531D02*
X360453Y296536D01*
G01X361929D02*
X361683Y295531D01*
G01Y298044D02*
X361929Y297039D01*
G01X360453D02*
X359961Y297792D01*
G01X360699Y299049D02*
X361683Y298044D01*
G01X353317Y297039D02*
X353563Y298044D01*
G01X361929Y289248D02*
Y287992D01*
G01Y297039D02*
Y296536D01*
G01X360453D02*
Y297039D01*
G01X353071Y287992D02*
Y289248D01*
G01X351103Y299803D02*
Y287992D01*
G01X349626D02*
Y297792D01*
G01X348150Y296033D02*
Y298044D01*
G01X346181Y293018D02*
Y292013D01*
G01Y296033D02*
Y295028D01*
G01X356890Y1001574D02*
X359646D01*
G01X360827D02*
X363583D01*
G01X352953D02*
X355709D01*
G01X349016D02*
X351772D01*
G01X360827Y1018110D02*
Y1001574D01*
G01X359646D02*
Y1018110D01*
G01X356890D02*
Y1001574D01*
G01X355709D02*
Y1018110D01*
G01X352953D02*
Y1001574D01*
G01X351772D02*
Y1018110D01*
G01X349016D02*
Y1001574D01*
G01X347835D02*
Y1018110D01*
G01X351772D02*
X349016D01*
G01X355709D02*
X352953D01*
G01X359646D02*
X356890D01*
G01X363583D02*
X360827D01*
G01X376142Y6023D02*
G03X384016I3937J0D01*
G01X376536D02*
Y9960D01*
G01X375914Y7147D02*
Y6803D01*
G01X374174Y9960D02*
Y6023D01*
G01X372599Y9960D02*
Y6023D01*
G01D02*
X376536D01*
G01X375914Y6803D02*
X373158Y7721D01*
G01X375210Y7377D02*
X375914Y7147D01*
G01Y8755D02*
X375210Y8525D01*
G01X373392Y7951D02*
X374975Y8468D01*
G01X373158Y8181D02*
X375914Y9099D01*
G01D02*
Y8755D01*
G01X375210Y8525D02*
Y7377D01*
G01X374975Y8468D02*
Y7434D01*
G01X373158Y7721D02*
Y8181D01*
G01X376536Y9960D02*
X372599D01*
G01X383622D02*
X376536D01*
G01X374975Y7434D02*
X373392Y7951D01*
G01X377363Y108267D02*
G03X369488Y100393I-1J-7874D01*
G01Y96456D02*
Y100393D01*
G01X378524Y121760D02*
X385414D01*
G01Y120253D02*
X378524D01*
G01Y114724D02*
X377048D01*
G01X378524Y120253D02*
Y114724D01*
G01Y126535D02*
Y121760D01*
G01X377048Y114724D02*
Y126535D01*
G01D02*
X378524D01*
G01X377431Y295028D02*
X376693Y294777D01*
G01Y295782D02*
X377431Y296033D01*
G01X369557Y295782D02*
X370296Y296033D01*
G01X366359Y295028D02*
X365620Y294777D01*
G01Y295782D02*
X366359Y296033D01*
G01X370050Y295028D02*
X369557Y294777D01*
G01X374971Y296033D02*
X376201D01*
G01X377431D02*
X378416D01*
G01X370296D02*
X371280D01*
G01X366359D02*
X367343D01*
G01X363898D02*
X365128D01*
G01X370788Y295028D02*
X370050D01*
G01X366851D02*
X366359D01*
G01X377924D02*
X377431D01*
G01X365128Y287992D02*
X363898D01*
G01X369065D02*
X367835D01*
G01X373002D02*
X371772D01*
G01X376201D02*
X374971D01*
G01X380138D02*
X378908D01*
G01X376693Y294777D02*
X376201Y294274D01*
G01Y295279D02*
X376693Y295782D01*
G01X369557Y294777D02*
X369311Y294526D01*
G01X368819Y295028D02*
X369557Y295782D01*
G01X365620Y294777D02*
X365128Y294274D01*
G01Y295279D02*
X365620Y295782D01*
G01X378416Y296033D02*
X379154Y295782D01*
G01X371280Y296033D02*
X372018Y295782D01*
G01X367343Y296033D02*
X368081Y295782D01*
G01X378416Y294777D02*
X377924Y295028D01*
G01X371280Y294777D02*
X370788Y295028D01*
G01X367343Y294777D02*
X366851Y295028D01*
G01X369311Y294526D02*
X369065Y294023D01*
G01X372510Y295279D02*
X373002Y294023D01*
G01X378908D02*
X378662Y294526D01*
G01X371772Y294023D02*
X371526Y294526D01*
G01X367835Y294023D02*
X367589Y294526D01*
G01X378662D02*
X378416Y294777D01*
G01X372018Y295782D02*
X372510Y295279D01*
G01X371526Y294526D02*
X371280Y294777D01*
G01X368081Y295782D02*
X368819Y295028D01*
G01X367589Y294526D02*
X367343Y294777D01*
G01X378908Y287992D02*
Y294023D01*
G01X376201Y294274D02*
Y287992D01*
G01Y296033D02*
Y295279D01*
G01X374971Y287992D02*
Y296033D01*
G01X373002Y294023D02*
Y287992D01*
G01X371772D02*
Y294023D01*
G01X369065D02*
Y287992D01*
G01X367835D02*
Y294023D01*
G01X365128Y294274D02*
Y287992D01*
G01Y296033D02*
Y295279D01*
G01X363898Y287992D02*
Y296033D01*
G01X369646Y630433D02*
X366693D01*
G01X369646Y641490D02*
Y630433D01*
G01X366693D02*
Y654055D01*
G01X369646Y644505D02*
X383425D01*
G01Y641490D02*
X369646D01*
G01Y654055D02*
Y644505D01*
G01X366693Y654055D02*
X369646D01*
G01X376575Y1001574D02*
X379331D01*
G01X372638D02*
X375394D01*
G01X368701D02*
X371457D01*
G01X364764D02*
X367520D01*
G01X376575Y1018110D02*
Y1001574D01*
G01X375394D02*
Y1018110D01*
G01X372638D02*
Y1001574D01*
G01X371457D02*
Y1018110D01*
G01X368701D02*
Y1001574D01*
G01X367520D02*
Y1018110D01*
G01X364764D02*
Y1001574D01*
G01X363583D02*
Y1018110D01*
G01X367520D02*
X364764D01*
G01X371457D02*
X368701D01*
G01X375394D02*
X372638D01*
G01X379331D02*
X376575D01*
G01X387559Y9960D02*
Y6023D01*
G01X387193Y7419D02*
Y7074D01*
G01X385985Y6023D02*
Y9960D01*
G01X384437Y7074D02*
Y7419D01*
G01X383622Y6023D02*
Y9960D01*
G01X387193Y7074D02*
X384437D01*
G01X387559Y6023D02*
X383622D01*
G01X385551Y8108D02*
X387193Y9141D01*
G01Y8682D02*
X385845Y7821D01*
G01X387193Y9141D02*
Y8682D01*
G01X384437D02*
Y9141D01*
G01X383622Y9960D02*
X387559D01*
G01X384437Y7419D02*
X385786D01*
G01X386255D02*
X387193D01*
G01X385845Y7821D02*
X386255Y7419D01*
G01X385786D02*
X384437Y8682D01*
G01Y9141D02*
X385551Y8108D01*
G01X392796Y121760D02*
X388859D01*
G01Y119750D02*
X392796D01*
G01Y118745D02*
X388859D01*
G01X386890Y114724D02*
X385414D01*
G01X392796Y119750D02*
Y118745D01*
G01Y122766D02*
Y121760D01*
G01X388859D02*
Y122766D01*
G01Y118745D02*
Y119750D01*
G01X386890Y126535D02*
Y114724D01*
G01X385414Y121760D02*
Y126535D01*
G01Y114724D02*
Y120253D01*
G01X396240Y124525D02*
X394764Y122766D01*
G01Y124776D02*
X396240Y126535D01*
G01X385414D02*
X386890D01*
G01X388859Y122766D02*
X392796D01*
G01X394764D02*
Y124776D01*
G01X422835Y155000D02*
X383071D01*
G01D02*
Y199330D01*
G01D02*
X422835D01*
G01X380630Y295782D02*
X381368Y296033D01*
G01X381122Y295028D02*
X380630Y294777D01*
G01X381368Y296033D02*
X382353D01*
G01X381861Y295028D02*
X381122D01*
G01X384075Y287992D02*
X382845D01*
G01X380630Y294777D02*
X380384Y294526D01*
G01X379892Y295028D02*
X380630Y295782D01*
G01X382353Y296033D02*
X383091Y295782D01*
G01X380384Y294526D02*
X380138Y294023D01*
G01X382353Y294777D02*
X381861Y295028D01*
G01X383583Y295279D02*
X384075Y294023D01*
G01X382845D02*
X382599Y294526D01*
G01X383091Y295782D02*
X383583Y295279D01*
G01X382599Y294526D02*
X382353Y294777D01*
G01X379154Y295782D02*
X379892Y295028D01*
G01X384075Y294023D02*
Y287992D01*
G01X382845D02*
Y294023D01*
G01X380138D02*
Y287992D01*
G01X386378Y630433D02*
X383425D01*
G01X386378Y654055D02*
Y630433D01*
G01X383425D02*
Y641490D01*
G01X390315Y646516D02*
X398189D01*
G01Y644505D02*
X390315D01*
G01Y640485D02*
X398189D01*
G01Y638474D02*
X390315D01*
G01Y644505D02*
Y646516D01*
G01Y638474D02*
Y640485D01*
G01X383425Y644505D02*
Y654055D01*
G01D02*
X386378D01*
G01X392323Y1001574D02*
X395079D01*
G01X384449D02*
X387205D01*
G01X388386D02*
X391142D01*
G01X380512D02*
X383268D01*
G01X395079D02*
Y1018110D01*
G01X392323D02*
Y1001574D01*
G01X391142D02*
Y1018110D01*
G01X388386D02*
Y1001574D01*
G01X387205D02*
Y1018110D01*
G01X384449D02*
Y1001574D01*
G01X383268D02*
Y1018110D01*
G01X380512D02*
Y1001574D01*
G01X379331D02*
Y1018110D01*
G01X383268D02*
X380512D01*
G01X387205D02*
X384449D01*
G01X391142D02*
X388386D01*
G01X395079D02*
X392323D01*
G01X430906Y23622D02*
G03I-17717J0D01*
G01X421258Y17322D02*
G03X405121I-8068J6299D01*
G01X402200Y21396D02*
X401693Y20792D01*
G01Y21482D02*
X402200Y22086D01*
G01X403937Y22637D02*
Y24606D01*
G01X402707Y22086D02*
Y18031D01*
G01X402200D02*
Y21396D01*
G01X401969Y24606D02*
Y22637D01*
G01X401693Y20792D02*
Y21482D01*
G01X401969Y22637D02*
X403937D01*
G01X402200Y22086D02*
X402707D01*
G01Y18031D02*
X402200D01*
G01X405121Y17322D02*
X421258D01*
G01X403937Y24606D02*
X401969D01*
G01X409282Y114975D02*
X410512Y115729D01*
G01X405345Y122012D02*
X404114Y121258D01*
G01X409774Y116734D02*
X409036Y116232D01*
G01X404607Y120001D02*
X405591Y120755D01*
G01X410512Y115729D02*
X411250Y116734D01*
G01X410266Y117488D02*
X409774Y116734D01*
G01X411250D02*
X411742Y117991D01*
G01X406575Y122263D02*
X405345Y122012D01*
G01X405591Y120755D02*
X406575Y121006D01*
G01X409036Y116232D02*
X408051Y115980D01*
G01X410512Y118242D02*
X410266Y117488D01*
G01X408051Y114724D02*
X409282Y114975D01*
G01X411742Y117991D02*
Y118996D01*
G01X410512Y118745D02*
Y118242D01*
G01X404114Y121258D02*
Y125279D01*
G01X402884Y126535D02*
Y120001D01*
G01X400916Y115980D02*
Y114724D01*
G01X399685D02*
Y115980D01*
G01X409282Y122012D02*
X408051Y122263D01*
G01X406575Y121006D02*
X408051D01*
G01X402884Y120001D02*
X404607D01*
G01X404361Y117740D02*
X402884D01*
G01X399685Y115980D02*
X400916D01*
G01X408051D02*
X406575D01*
G01Y114724D02*
X408051D01*
G01X397717D02*
X396240D01*
G01X400916D02*
X399685D01*
G01X397717Y126535D02*
Y114724D01*
G01X396240D02*
Y124525D01*
G01X410266Y119499D02*
X410512Y118745D01*
G01X411742Y118996D02*
X411250Y120253D01*
G01X404853Y116734D02*
X404361Y117740D01*
G01X402884D02*
X403376Y116734D01*
G01X409774Y120253D02*
X410266Y119499D01*
G01X411250Y120253D02*
X410512Y121258D01*
G01X403376Y116734D02*
X404114Y115729D01*
G01X409036Y120755D02*
X409774Y120253D01*
G01X405591Y116232D02*
X404853Y116734D01*
G01X410512Y121258D02*
X409282Y122012D01*
G01X404114Y115729D02*
X405345Y114975D01*
G01X408051Y121006D02*
X409036Y120755D01*
G01X406575Y115980D02*
X405591Y116232D01*
G01X405345Y114975D02*
X406575Y114724D01*
G01X396240Y126535D02*
X397717D01*
G01X411250D02*
X402884D01*
G01X404114Y125279D02*
X411250D01*
G01D02*
Y126535D01*
G01X408051Y122263D02*
X406575D01*
G01X403314Y324574D02*
X407763D01*
G01X505315Y320275D02*
X399016D01*
G01X407763Y324574D02*
X403314Y329022D01*
G01Y324574D02*
Y329022D01*
G01X399016Y426574D02*
Y320275D01*
G01X505315Y426574D02*
X399016D01*
G01X419843Y630433D02*
X402126D01*
G01D02*
Y632946D01*
G01X406063D02*
X419843D01*
G01X418366Y644003D02*
X406063Y632946D01*
G01X402126D02*
X415906Y645511D01*
G01X398189Y640485D02*
Y638474D01*
G01Y646516D02*
Y644505D01*
G01X407048Y653552D02*
X410492Y654055D01*
G01X410000Y651542D02*
X407540Y651039D01*
G01X410492Y654055D02*
X412461D01*
G01X411969Y651542D02*
X410000D01*
G01X405079Y648526D02*
X402618D01*
G01X405079Y652547D02*
X407048Y653552D01*
G01X407540Y651039D02*
X406063Y650034D01*
G01X402618Y648526D02*
X403111Y650537D01*
G01D02*
X405079Y652547D01*
G01X406063Y650034D02*
X405079Y648526D01*
G01X408071Y1001574D02*
X410827D01*
G01X404134D02*
X406890D01*
G01X400197D02*
X402953D01*
G01X396260D02*
X399016D01*
G01X410827D02*
Y1018110D01*
G01X408071D02*
Y1001574D01*
G01X406890D02*
Y1018110D01*
G01X404134D02*
Y1001574D01*
G01X402953D02*
Y1018110D01*
G01X400197D02*
Y1001574D01*
G01X399016D02*
Y1018110D01*
G01X396260D02*
Y1001574D01*
G01X399016Y1018110D02*
X396260D01*
G01X402953D02*
X400197D01*
G01X406890D02*
X404134D01*
G01X410827D02*
X408071D01*
G01X423386Y6023D02*
G03X431260I3937J0D01*
G01X423780D02*
Y9960D01*
G01X423158Y7147D02*
Y6803D01*
G01X421418Y9960D02*
Y6023D01*
G01X419843Y9960D02*
Y6023D01*
G01D02*
X423780D01*
G01X421418D02*
X423386D01*
G01X423158Y6803D02*
X420402Y7721D01*
G01X422454Y7377D02*
X423158Y7147D01*
G01Y8755D02*
X422454Y8525D01*
G01X420637Y7951D02*
X422220Y8468D01*
G01X420402Y8181D02*
X423158Y9099D01*
G01X424410Y22637D02*
Y24606D01*
G01X423158Y9099D02*
Y8755D01*
G01X422454Y8525D02*
Y7377D01*
G01X422441Y24606D02*
Y22637D01*
G01X422220Y8468D02*
Y7434D01*
G01X420402Y7721D02*
Y8181D01*
G01X414174Y22637D02*
Y24606D01*
G01X412205D02*
Y22637D01*
G01X422441D02*
X424410D01*
G01X412205D02*
X414174D01*
G01X423780Y9960D02*
X419843D01*
G01X433229D02*
X421418D01*
G01X422220Y7434D02*
X420637Y7951D01*
G01X414174Y24606D02*
X412205D01*
G01X424410D02*
X422441D01*
G01X427244Y121760D02*
X426506Y121509D01*
G01X416172Y121760D02*
X415433Y121509D01*
G01X419863Y121760D02*
X419370Y121509D01*
G01X426506D02*
X426014Y121006D01*
G01Y122012D02*
X426506Y122514D01*
G01X419370Y121509D02*
X419124Y121258D01*
G01X418632Y121760D02*
X419370Y122514D01*
G01X415433Y121509D02*
X414941Y121006D01*
G01Y122012D02*
X415433Y122514D01*
G01X419124Y121258D02*
X418878Y120755D01*
G01X426014Y121006D02*
Y114724D01*
G01Y122766D02*
Y122012D01*
G01X424784Y114724D02*
Y122766D01*
G01X422815Y120755D02*
Y114724D01*
G01X421585D02*
Y120755D01*
G01X418878D02*
Y114724D01*
G01X417648D02*
Y120755D01*
G01X414941Y121006D02*
Y114724D01*
G01Y122766D02*
Y122012D01*
G01X413711Y114724D02*
Y122766D01*
G01X416664Y121760D02*
X416172D01*
G01X420601D02*
X419863D01*
G01X427737D02*
X427244D01*
G01X414941Y114724D02*
X413711D01*
G01X422815D02*
X421585D01*
G01X418878D02*
X417648D01*
G01X426014D02*
X424784D01*
G01X422323Y122012D02*
X422815Y120755D01*
G01X421585D02*
X421339Y121258D01*
G01X417648Y120755D02*
X417402Y121258D01*
G01X421831Y122514D02*
X422323Y122012D01*
G01X421339Y121258D02*
X421093Y121509D01*
G01X417894Y122514D02*
X418632Y121760D01*
G01X417402Y121258D02*
X417156Y121509D01*
G01X428229D02*
X427737Y121760D01*
G01X421093Y121509D02*
X420601Y121760D01*
G01X417156Y121509D02*
X416664Y121760D01*
G01X426506Y122514D02*
X427244Y122766D01*
G01X419370Y122514D02*
X420109Y122766D01*
G01X415433Y122514D02*
X416172Y122766D01*
G01X427244D02*
X428229D01*
G01X424784D02*
X426014D01*
G01X420109D02*
X421093D01*
G01X413711D02*
X414941D01*
G01X416172D02*
X417156D01*
G01X421093D02*
X421831Y122514D01*
G01X417156Y122766D02*
X417894Y122514D01*
G01X422835Y199330D02*
Y155000D01*
G01X422855Y333070D02*
X421378D01*
G01X422855Y338599D02*
Y333070D01*
G01X421378D02*
Y344881D01*
G01D02*
X422855D01*
G01Y340107D02*
X429744D01*
G01Y338599D02*
X422855D01*
G01Y344881D02*
Y340107D01*
G01X426240Y630433D02*
X423780D01*
G01X426240Y632946D02*
Y630433D01*
G01X423780D02*
Y632946D01*
G01X419843D02*
Y630433D01*
G01X423780Y632946D02*
X426240D01*
G01X419351Y645511D02*
X418366Y644003D01*
G01X415906Y645511D02*
X416890Y647521D01*
G01X419843D02*
X419351Y645511D01*
G01X414429Y651039D02*
X411969Y651542D01*
G01X412461Y654055D02*
X415414Y653552D01*
G01D02*
X417382Y652547D01*
G01X415906Y650034D02*
X414429Y651039D01*
G01X417382Y652547D02*
X419351Y650537D01*
G01X416890Y648526D02*
X415906Y650034D01*
G01X419351Y650537D02*
X419843Y648526D01*
G01D02*
Y647521D01*
G01X416890D02*
Y648526D01*
G01X427756Y1001574D02*
X430512D01*
G01X423819D02*
X426575D01*
G01X419882D02*
X422638D01*
G01X415945D02*
X418701D01*
G01X412008D02*
X414764D01*
G01X427756Y1018110D02*
Y1001574D01*
G01X426575D02*
Y1018110D01*
G01X423819D02*
Y1001574D01*
G01X422638D02*
Y1018110D01*
G01X419882D02*
Y1001574D01*
G01X418701D02*
Y1018110D01*
G01X415945D02*
Y1001574D01*
G01X414764D02*
Y1018110D01*
G01X412008D02*
Y1001574D01*
G01X414764Y1018110D02*
X412008D01*
G01X418701D02*
X415945D01*
G01X422638D02*
X419882D01*
G01X426575D02*
X423819D01*
G01X430512D02*
X427756D01*
G01X434803Y9960D02*
Y6023D01*
G01X434437Y7419D02*
Y7074D01*
G01X433229Y6023D02*
Y9960D01*
G01X431681Y7074D02*
Y7419D01*
G01X430866Y6023D02*
Y9960D01*
G01X434437Y7074D02*
X431681D01*
G01X431260Y6023D02*
X433229D01*
G01X434803D02*
X430866D01*
G01X432796Y8108D02*
X434437Y9141D01*
G01Y8682D02*
X433089Y7821D01*
G01X434437Y9141D02*
Y8682D01*
G01X431681D02*
Y9141D01*
G01X430866Y9960D02*
X434803D01*
G01X431681Y7419D02*
X433030D01*
G01X433499D02*
X434437D01*
G01X433089Y7821D02*
X433499Y7419D01*
G01X433030D02*
X431681Y8682D01*
G01Y9141D02*
X432796Y8108D01*
G01X430935Y121760D02*
X430443Y121509D01*
G01D02*
X430197Y121258D01*
G01X429705Y121760D02*
X430443Y122514D01*
G01X430197Y121258D02*
X429951Y120755D01*
G01X433888D02*
Y114724D01*
G01X432658D02*
Y120755D01*
G01X429951D02*
Y114724D01*
G01X428721D02*
Y120755D01*
G01X433396Y122012D02*
X433888Y120755D01*
G01X431674Y121760D02*
X430935D01*
G01X429951Y114724D02*
X428721D01*
G01X433888D02*
X432658D01*
G01Y120755D02*
X432412Y121258D01*
G01X428721Y120755D02*
X428475Y121258D01*
G01X432904Y122514D02*
X433396Y122012D01*
G01X432412Y121258D02*
X432166Y121509D01*
G01X428967Y122514D02*
X429705Y121760D01*
G01X428475Y121258D02*
X428229Y121509D01*
G01X432166D02*
X431674Y121760D01*
G01X430443Y122514D02*
X431181Y122766D01*
G01D02*
X432166D01*
G01D02*
X432904Y122514D01*
G01X428229Y122766D02*
X428967Y122514D01*
G01X428544Y246063D02*
G03X436418Y253937I0J7874D01*
G01X457087Y257874D02*
G03I-6890J0D01*
G01D02*
G03I-6890J0D01*
G01X463977D02*
G03X436418I-13779J0D01*
G01D02*
Y253937D01*
G01X444016Y334327D02*
X445246D01*
G01X431221Y333070D02*
X429744D01*
G01X445246D02*
X444016D01*
G01X442048D02*
X440571D01*
G01X444016D02*
Y334327D01*
G01X442048Y344881D02*
Y333070D01*
G01X440571D02*
Y342871D01*
G01X431221Y344881D02*
Y333070D01*
G01X429744D02*
Y338599D01*
G01X470138Y349940D02*
X434193D01*
G01X440571Y344881D02*
X442048D01*
G01X429744D02*
X431221D01*
G01X433189Y341112D02*
X437126D01*
G01Y340107D02*
X433189D01*
G01Y338096D02*
X437126D01*
G01Y337091D02*
X433189D01*
G01X440571Y342871D02*
X439095Y341112D01*
G01Y343122D02*
X440571Y344881D01*
G01X439095Y341112D02*
Y343122D01*
G01X437126Y338096D02*
Y337091D01*
G01Y341112D02*
Y340107D01*
G01X434193Y349940D02*
Y396909D01*
G01X433189Y337091D02*
Y338096D01*
G01Y340107D02*
Y341112D01*
G01X429744Y340107D02*
Y344881D01*
G01X434193Y396909D02*
X470138D01*
G01X436083Y630433D02*
X433130D01*
G01X445925D02*
X442973D01*
G01D02*
Y650034D01*
G01X436083Y654055D02*
Y630433D01*
G01X433130D02*
Y650034D01*
G01X440020Y646516D02*
Y650537D01*
G01X430177Y646516D02*
Y650537D01*
G01X442973Y650034D02*
X440020Y646516D01*
G01X433130Y650034D02*
X430177Y646516D01*
G01X442973Y654055D02*
X445925D01*
G01X433130D02*
X436083D01*
G01X440020Y650537D02*
X442973Y654055D01*
G01X430177Y650537D02*
X433130Y654055D01*
G01X443504Y1001574D02*
X446260D01*
G01X439567D02*
X442323D01*
G01X431693D02*
X434449D01*
G01X435630D02*
X438386D01*
G01X443504Y1018110D02*
Y1001574D01*
G01X442323D02*
Y1018110D01*
G01X439567D02*
Y1001574D01*
G01X438386D02*
Y1018110D01*
G01X435630D02*
Y1001574D01*
G01X434449D02*
Y1018110D01*
G01X431693D02*
Y1001574D01*
G01X430512D02*
Y1018110D01*
G01X434449D02*
X431693D01*
G01X438386D02*
X435630D01*
G01X442323D02*
X439567D01*
G01X446260D02*
X443504D01*
G01X452166Y226377D02*
Y127952D01*
G01X452382Y333070D02*
X453613Y333322D01*
G01X453366Y334578D02*
X452382Y334327D01*
G01X453613Y333322D02*
X454843Y334076D01*
G01X452382Y334327D02*
X450906D01*
G01Y333070D02*
X452382D01*
G01X459272D02*
X458042D01*
G01X454105Y335081D02*
X453366Y334578D01*
G01X450906Y334327D02*
X449922Y334578D01*
G01X449675Y333322D02*
X450906Y333070D01*
G01X454843Y334076D02*
X455581Y335081D01*
G01X454597Y335835D02*
X454105Y335081D01*
G01X449922Y334578D02*
X449183Y335081D01*
G01X448445Y334076D02*
X449675Y333322D01*
G01X455581Y335081D02*
X456073Y336337D01*
G01X449183Y335081D02*
X448691Y336086D01*
G01X447215D02*
X447707Y335081D01*
G01D02*
X448445Y334076D01*
G01X459272Y339353D02*
Y333070D01*
G01X458042D02*
Y341112D01*
G01X445246Y334327D02*
Y333070D01*
G01X450906Y340609D02*
X449675Y340358D01*
G01X449922Y339102D02*
X450906Y339353D01*
G01X460502Y340107D02*
X459764Y339855D01*
G01Y340861D02*
X460502Y341112D01*
G01X455581Y344881D02*
X447215D01*
G01X448445Y343625D02*
X455581D01*
G01X460502Y341112D02*
X461487D01*
G01X458042D02*
X459272D01*
G01X452382Y340609D02*
X450906D01*
G01X460994Y340107D02*
X460502D01*
G01X450906Y339353D02*
X452382D01*
G01X447215Y338348D02*
X448937D01*
G01X448691Y336086D02*
X447215D01*
G01X449675Y340358D02*
X448445Y339604D01*
G01X448937Y338348D02*
X449922Y339102D01*
G01X459764Y339855D02*
X459272Y339353D01*
G01Y340358D02*
X459764Y340861D01*
G01X452382Y339353D02*
X453366Y339102D01*
G01X453613Y340358D02*
X452382Y340609D01*
G01X453366Y339102D02*
X454105Y338599D01*
G01X454843Y339604D02*
X453613Y340358D01*
G01X461487Y339855D02*
X460994Y340107D01*
G01X454843Y336589D02*
X454597Y335835D01*
G01Y337845D02*
X454843Y337091D01*
G01X456073Y337342D02*
X455581Y338599D01*
G01X454105D02*
X454597Y337845D01*
G01X455581Y338599D02*
X454843Y339604D01*
G01X459272Y341112D02*
Y340358D01*
G01X456073Y336337D02*
Y337342D01*
G01X455581Y343625D02*
Y344881D01*
G01X454843Y337091D02*
Y336589D01*
G01X448445Y339604D02*
Y343625D01*
G01X447215Y344881D02*
Y338348D01*
G01X452323Y630433D02*
X449863D01*
G01X460197D02*
X457737D01*
G01X460197Y642495D02*
Y630433D01*
G01X457737D02*
Y642495D01*
G01X452323Y642998D02*
Y630433D01*
G01X449863D02*
Y646516D01*
G01X445925Y654055D02*
Y630433D01*
G01X454784Y646516D02*
X456752D01*
G01X449863D02*
X452323D01*
G01X455768Y644505D02*
X454784D01*
G01X456752Y644003D02*
X455768Y644505D01*
G01X456752Y646516D02*
X458229Y646013D01*
G01D02*
X459705Y644505D01*
G01X457244Y643500D02*
X456752Y644003D01*
G01X457737Y642495D02*
X457244Y643500D01*
G01X454784Y644505D02*
X453307Y644003D01*
G01Y646013D02*
X454784Y646516D01*
G01X452323D02*
Y645008D01*
G01X461181Y644003D02*
X460689Y643500D01*
G01X459705Y644505D02*
X461181Y646013D01*
G01X453307Y644003D02*
X452323Y642998D01*
G01Y645008D02*
X453307Y646013D01*
G01X460689Y643500D02*
X460197Y642495D01*
G01X459252Y1001574D02*
X462008D01*
G01X455315D02*
X458071D01*
G01X451378D02*
X454134D01*
G01X447441D02*
X450197D01*
G01X459252Y1018110D02*
Y1001574D01*
G01X458071D02*
Y1018110D01*
G01X455315D02*
Y1001574D01*
G01X454134D02*
Y1018110D01*
G01X451378D02*
Y1001574D01*
G01X450197D02*
Y1018110D01*
G01X447441D02*
Y1001574D01*
G01X446260D02*
Y1018110D01*
G01X450197D02*
X447441D01*
G01X454134D02*
X451378D01*
G01X458071D02*
X455315D01*
G01X462008D02*
X459252D01*
G01X468504Y324212D02*
Y0D01*
G01Y58267D02*
X513780D01*
G01X468504Y101574D02*
X513780D01*
G01X463977Y108267D02*
Y257874D01*
G01X513780Y233464D02*
X468504D01*
G01Y276771D02*
X513780D01*
G01X463209Y333070D02*
X461979D01*
G01X467146D02*
X465916D01*
G01X470345D02*
X469114D01*
G01X474282D02*
X473051D01*
G01X478219D02*
X476988D01*
G01D02*
Y339102D01*
G01X474282D02*
Y333070D01*
G01X473051D02*
Y339102D01*
G01X470345Y339353D02*
Y333070D01*
G01X469114D02*
Y341112D01*
G01X467146Y339102D02*
Y333070D01*
G01X465916D02*
Y339102D01*
G01X463209D02*
Y333070D01*
G01X461979D02*
Y339102D01*
G01X474774Y340861D02*
X475512Y341112D01*
G01X471575Y340107D02*
X470837Y339855D01*
G01Y340861D02*
X471575Y341112D01*
G01X463701Y340861D02*
X464439Y341112D01*
G01X475266Y340107D02*
X474774Y339855D01*
G01X464193Y340107D02*
X463701Y339855D01*
G01X475512Y341112D02*
X476496D01*
G01X469114D02*
X470345D01*
G01X471575D02*
X472559D01*
G01X464439D02*
X465424D01*
G01X464931Y340107D02*
X464193D01*
G01X472067D02*
X471575D01*
G01X476004D02*
X475266D01*
G01X474774Y339855D02*
X474528Y339604D01*
G01X474036Y340107D02*
X474774Y340861D01*
G01X470837Y339855D02*
X470345Y339353D01*
G01Y340358D02*
X470837Y340861D01*
G01X463701Y339855D02*
X463455Y339604D01*
G01X462963Y340107D02*
X463701Y340861D01*
G01X476496Y341112D02*
X477235Y340861D01*
G01X472559Y341112D02*
X473298Y340861D01*
G01X465424Y341112D02*
X466162Y340861D01*
G01X461487Y341112D02*
X462225Y340861D01*
G01X474528Y339604D02*
X474282Y339102D01*
G01X463455Y339604D02*
X463209Y339102D01*
G01X476988D02*
X476742Y339604D01*
G01X477235Y340861D02*
X477727Y340358D01*
G01X476742Y339604D02*
X476496Y339855D01*
G01X473298Y340861D02*
X474036Y340107D01*
G01X472805Y339604D02*
X472559Y339855D01*
G01X466162Y340861D02*
X466654Y340358D01*
G01X465670Y339604D02*
X465424Y339855D01*
G01X462225Y340861D02*
X462963Y340107D01*
G01X461733Y339604D02*
X461487Y339855D01*
G01X476496D02*
X476004Y340107D01*
G01X472559Y339855D02*
X472067Y340107D01*
G01X465424Y339855D02*
X464931Y340107D01*
G01X470345Y341112D02*
Y340358D01*
G01X470138Y396909D02*
Y349940D01*
G01X466654Y340358D02*
X467146Y339102D01*
G01X473051D02*
X472805Y339604D01*
G01X465916Y339102D02*
X465670Y339604D01*
G01X461979Y339102D02*
X461733Y339604D01*
G01X468071Y630433D02*
X465611D01*
G01X474469D02*
X472008D01*
G01X474469Y642998D02*
Y630433D01*
G01X472008D02*
Y646516D01*
G01X468071Y642495D02*
Y630433D01*
G01X465611D02*
Y642495D01*
G01X476929Y646516D02*
X478898D01*
G01X472008D02*
X474469D01*
G01X462658D02*
X464626D01*
G01X463642Y644505D02*
X462166D01*
G01X477914D02*
X476929D01*
G01X464626Y646516D02*
X466103Y646013D01*
G01X464626Y644003D02*
X463642Y644505D01*
G01X466103Y646013D02*
X467087Y645008D01*
G01X465118Y643500D02*
X464626Y644003D01*
G01X465611Y642495D02*
X465118Y643500D01*
G01X467087Y645008D02*
X468071Y642495D01*
G01X474469Y646516D02*
Y645008D01*
G01X476929Y644505D02*
X475453Y644003D01*
G01Y646013D02*
X476929Y646516D01*
G01X461181Y646013D02*
X462658Y646516D01*
G01X462166Y644505D02*
X461181Y644003D01*
G01X475453D02*
X474469Y642998D01*
G01Y645008D02*
X475453Y646013D01*
G01X475000Y1001574D02*
X477756D01*
G01X471063D02*
X473819D01*
G01X467126D02*
X469882D01*
G01X463189D02*
X465945D01*
G01X475000Y1018110D02*
Y1001574D01*
G01X473819D02*
Y1018110D01*
G01X471063D02*
Y1001574D01*
G01X469882D02*
Y1018110D01*
G01X467126D02*
Y1001574D01*
G01X465945D02*
Y1018110D01*
G01X463189D02*
Y1001574D01*
G01X462008D02*
Y1018110D01*
G01X465945D02*
X463189D01*
G01X469882D02*
X467126D01*
G01X473819D02*
X471063D01*
G01X477756D02*
X475000D01*
G01X497244Y79921D02*
G03I-6299J0D01*
G01X484764Y154409D02*
Y155885D01*
G01X496575Y154409D02*
X484764D01*
G01X492554Y170157D02*
Y166220D01*
G01X491549D02*
Y170157D01*
G01X491047Y162775D02*
Y155885D01*
G01X489539D02*
Y162775D01*
G01Y170157D02*
Y166220D01*
G01X488534D02*
Y170157D01*
G01X484764Y162775D02*
Y164252D01*
G01X491549Y170157D02*
X492554D01*
G01X488534D02*
X489539D01*
G01X492554Y166220D02*
X491549D01*
G01X489539D02*
X488534D01*
G01X484764Y164252D02*
X496575D01*
G01X489539Y162775D02*
X484764D01*
G01X496575D02*
X491047D01*
G01Y155885D02*
X496575D01*
G01X484764D02*
X489539D01*
G01X493057Y172372D02*
X493811Y172618D01*
G01X488282Y180738D02*
X487528Y180492D01*
G01X493811Y172618D02*
X494816Y173110D01*
G01X487528Y180492D02*
X486523Y180000D01*
G01X490544Y186889D02*
X490041Y186643D01*
G01X493057Y173602D02*
X494565Y174586D01*
G01X488282Y179507D02*
X486774Y178523D01*
G01X486523Y180000D02*
X485769Y179261D01*
G01X490041Y186643D02*
X489790Y186397D01*
G01X488785Y187135D02*
X489539Y187874D01*
G01X486774Y178523D02*
X486272Y177785D01*
G01X485769Y179261D02*
X485015Y178031D01*
G01X489790Y186397D02*
X489539Y185905D01*
G01X488534Y186397D02*
X488785Y187135D01*
G01X486272Y177785D02*
X486021Y176555D01*
G01X485015Y178031D02*
X484764Y176555D01*
G01X496575Y186889D02*
X490544D01*
G01X489790Y179753D02*
X488282Y179507D01*
G01X491549Y173356D02*
X493057Y173602D01*
G01X489539Y180984D02*
X488282Y180738D01*
G01X491800Y172126D02*
X493057Y172372D01*
G01X489539Y185905D02*
Y185413D01*
G01X488534Y182952D02*
Y184183D01*
G01Y185413D02*
Y186397D01*
G01X484764Y176555D02*
X485015Y175078D01*
G01X486021Y176555D02*
X486272Y175324D01*
G01X489539Y185413D02*
X489790Y184675D01*
G01X488785D02*
X488534Y185413D01*
G01X493811Y180492D02*
X493057Y180738D01*
G01D02*
X491800Y180984D01*
G01X488282Y172372D02*
X489539Y172126D01*
G01X493057Y179507D02*
X491549Y179753D01*
G01X488282Y173602D02*
X489790Y173356D01*
G01X488534Y184183D02*
X489287D01*
G01X490293D02*
X496575D01*
G01Y182952D02*
X488534D01*
G01X491800Y180984D02*
X489539D01*
G01X491549Y179753D02*
X489790D01*
G01Y173356D02*
X491549D01*
G01X489539Y172126D02*
X491800D01*
G01X485015Y175078D02*
X485769Y173848D01*
G01X486272Y175324D02*
X486774Y174586D01*
G01X489790Y184675D02*
X490293Y184183D01*
G01X489287D02*
X488785Y184675D01*
G01X485769Y173848D02*
X486523Y173110D01*
G01X494565Y178523D02*
X493057Y179507D01*
G01X486774Y174586D02*
X488282Y173602D01*
G01X494816Y180000D02*
X493811Y180492D01*
G01X486523Y173110D02*
X487528Y172618D01*
G01D02*
X488282Y172372D01*
G01X489287Y191565D02*
X490544Y192057D01*
G01X489287Y202637D02*
X490544Y203129D01*
G01Y190826D02*
X490041Y190580D01*
G01X490544Y197962D02*
X490041Y197716D01*
G01X490544Y201899D02*
X490041Y201653D01*
G01Y190580D02*
X489790Y190334D01*
G01X488785Y191072D02*
X489287Y191565D01*
G01X490041Y197716D02*
X489790Y197470D01*
G01X488785Y198208D02*
X489539Y198946D01*
G01X490041Y201653D02*
X489790Y201407D01*
G01X488785Y202145D02*
X489287Y202637D01*
G01X489790Y190334D02*
X489539Y189842D01*
G01X489790Y197470D02*
X489539Y196978D01*
G01X489790Y201407D02*
X489539Y200915D01*
G01X488534Y190334D02*
X488785Y191072D01*
G01X488534Y197470D02*
X488785Y198208D01*
G01X488534Y201407D02*
X488785Y202145D01*
G01X490544Y203129D02*
X496575D01*
G01Y201899D02*
X490544D01*
G01Y199192D02*
X496575D01*
G01Y197962D02*
X490544D01*
G01X488534Y195255D02*
X489287D01*
G01X490293D02*
X496575D01*
G01Y194025D02*
X488534D01*
G01X490544Y192057D02*
X496575D01*
G01Y190826D02*
X490544D01*
G01Y188120D02*
X496575D01*
G01X489539Y189842D02*
Y189104D01*
G01Y200915D02*
Y200177D01*
G01Y196978D02*
Y196486D01*
G01X488534Y200423D02*
Y201407D01*
G01Y196486D02*
Y197470D01*
G01Y194025D02*
Y195255D01*
G01Y189350D02*
Y190334D01*
G01X488785Y199685D02*
X488534Y200423D01*
G01X489539Y196486D02*
X489790Y195748D01*
G01X488785D02*
X488534Y196486D01*
G01X488785Y188612D02*
X488534Y189350D01*
G01X489539Y200177D02*
X489790Y199685D01*
G01X489539Y189104D02*
X489790Y188612D01*
G01X490041Y199439D02*
X490544Y199192D01*
G01X489790Y199685D02*
X490041Y199439D01*
G01X489539Y198946D02*
X488785Y199685D01*
G01X489790Y195748D02*
X490293Y195255D01*
G01X489287D02*
X488785Y195748D01*
G01X489790Y188612D02*
X490041Y188366D01*
G01X489539Y187874D02*
X488785Y188612D01*
G01X490041Y188366D02*
X490544Y188120D01*
G01X497244Y255118D02*
G03I-6299J0D01*
G01X478219Y339102D02*
Y333070D01*
G01X477727Y340358D02*
X478219Y339102D01*
G01X482343Y630433D02*
X479882D01*
G01X490217D02*
X487756D01*
G01X490217Y642495D02*
Y630433D01*
G01X487756D02*
Y642495D01*
G01X482343D02*
Y630433D01*
G01X479882D02*
Y642495D01*
G01X484803Y646516D02*
X486772D01*
G01X485788Y644505D02*
X484311D01*
G01X486772Y646516D02*
X488248Y646013D01*
G01X478898Y646516D02*
X480374Y646013D01*
G01X486772Y644003D02*
X485788Y644505D01*
G01X478898Y644003D02*
X477914Y644505D01*
G01X488248Y646013D02*
X489233Y645008D01*
G01X487264Y643500D02*
X486772Y644003D01*
G01X480374Y646013D02*
X481851Y644505D01*
G01X479390Y643500D02*
X478898Y644003D01*
G01X487756Y642495D02*
X487264Y643500D01*
G01X479882Y642495D02*
X479390Y643500D01*
G01X489233Y645008D02*
X490217Y642495D01*
G01X483327Y646013D02*
X484803Y646516D01*
G01X484311Y644505D02*
X483327Y644003D01*
G01X482835Y643500D02*
X482343Y642495D01*
G01X483327Y644003D02*
X482835Y643500D01*
G01X481851Y644505D02*
X483327Y646013D01*
G01X490748Y1001574D02*
X493504D01*
G01X482874D02*
X485630D01*
G01X486811D02*
X489567D01*
G01X478937D02*
X481693D01*
G01X493504D02*
Y1018110D01*
G01X490748D02*
Y1001574D01*
G01X489567D02*
Y1018110D01*
G01X486811D02*
Y1001574D01*
G01X485630D02*
Y1018110D01*
G01X482874D02*
Y1001574D01*
G01X481693D02*
Y1018110D01*
G01X478937D02*
Y1001574D01*
G01X477756D02*
Y1018110D01*
G01X481693D02*
X478937D01*
G01X485630D02*
X482874D01*
G01X489567D02*
X486811D01*
G01X493504D02*
X490748D01*
G01X506077Y58267D02*
X513780Y65970D01*
G01X496575Y155885D02*
Y154409D01*
G01Y164252D02*
Y162775D01*
G01X494816Y173110D02*
X495570Y173848D01*
G01X494565Y174586D02*
X495067Y175324D01*
G01X495570Y173848D02*
X496324Y175078D01*
G01X495067Y175324D02*
X495319Y176555D01*
G01X496324Y175078D02*
X496575Y176555D01*
G01Y184183D02*
Y182952D01*
G01Y188120D02*
Y186889D01*
G01Y176555D02*
X496324Y178031D01*
G01X495319Y176555D02*
X495067Y177785D01*
G01X496324Y178031D02*
X495570Y179261D01*
G01X495067Y177785D02*
X494565Y178523D01*
G01X495570Y179261D02*
X494816Y180000D01*
G01X496575Y195255D02*
Y194025D01*
G01Y192057D02*
Y190826D01*
G01Y199192D02*
Y197962D01*
G01Y203129D02*
Y201899D01*
G01X505315Y426574D02*
Y320275D01*
G01X506496Y1001574D02*
X509252D01*
G01X502559D02*
X505315D01*
G01X498622D02*
X501378D01*
G01X494685D02*
X497441D01*
G01X509252D02*
Y1018110D01*
G01X506496D02*
Y1001574D01*
G01X505315D02*
Y1018110D01*
G01X502559D02*
Y1001574D01*
G01X501378D02*
Y1018110D01*
G01X498622D02*
Y1001574D01*
G01X497441D02*
Y1018110D01*
G01X494685D02*
Y1001574D01*
G01X497441Y1018110D02*
X494685D01*
G01X501378D02*
X498622D01*
G01X505315D02*
X502559D01*
G01X509252D02*
X506496D01*
G01X515302Y-7874D02*
G03Y0I0J3937D01*
G01Y-7874D02*
G03Y0I0J3937D01*
G01X513780Y276771D02*
Y49212D01*
G01X1112146D02*
X513780D01*
G01X526181Y1001574D02*
X528937D01*
G01X522244D02*
X525000D01*
G01X518307D02*
X521063D01*
G01X514370D02*
X517126D01*
G01X510433D02*
X513189D01*
G01X526181Y1018110D02*
Y1001574D01*
G01X525000D02*
Y1018110D01*
G01X522244D02*
Y1001574D01*
G01X521063D02*
Y1018110D01*
G01X518307D02*
Y1001574D01*
G01X517126D02*
Y1018110D01*
G01X514370D02*
Y1001574D01*
G01X513189D02*
Y1018110D01*
G01X510433D02*
Y1001574D01*
G01X513189Y1018110D02*
X510433D01*
G01X517126D02*
X514370D01*
G01X521063D02*
X518307D01*
G01X525000D02*
X522244D01*
G01X528937D02*
X526181D01*
G01X540499Y-7874D02*
X727049D01*
G01X540499Y0D02*
G03Y-7874I0J-3937D01*
G01D02*
X727049D01*
G01X540499Y0D02*
G03Y-7874I0J-3937D01*
G01X539370Y298031D02*
X540945Y299606D01*
G01Y303149D02*
G03I-2953J0D01*
G01X541733Y304910D02*
G03Y301389I-3740J-1761D01*
G01X534252Y300777D02*
G03X541733I3740J2372D01*
G01X540945Y299606D02*
X875985D01*
G01X539370Y298031D02*
X823629D01*
G01X536811Y296161D02*
X541614D01*
G01X540748Y293799D02*
X536811D01*
G01X541142Y292618D02*
X533268D01*
G01X541614Y291830D02*
X536811D01*
G01X875788Y290354D02*
X541142D01*
G01X533268Y288681D02*
X883662D01*
G01X541733Y305522D02*
Y300777D01*
G01X541614Y291830D02*
Y296161D01*
G01X541142Y292618D02*
Y288681D01*
G01X540945Y299606D02*
Y306692D01*
G01X540748Y296161D02*
Y293799D01*
G01X539370Y308267D02*
Y298031D01*
G01X536811Y296161D02*
Y291830D01*
G01X534252Y300777D02*
Y301389D01*
G01X533268Y288681D02*
Y323228D01*
G01X540945Y306692D02*
X539370Y308267D01*
G01X541733Y305522D02*
G03X534252I-3740J-2373D01*
G01X541142Y317637D02*
X533268D01*
G01X883662Y317618D02*
X533268D01*
G01X541142Y315944D02*
X875788D01*
G01X541614Y314468D02*
X536811D01*
G01X533268Y313681D02*
X541142D01*
G01X540748Y312500D02*
X536811D01*
G01X541614Y310137D02*
X536811D01*
G01X823629Y308267D02*
X539370D01*
G01X540945Y306692D02*
X875985D01*
G01X541614Y314468D02*
Y310137D01*
G01X541142Y313681D02*
Y317637D01*
G01X540748Y310137D02*
Y312500D01*
G01X536811Y310137D02*
Y314468D01*
G01X534252Y304910D02*
Y305522D01*
G01X549725Y323228D02*
X533268D01*
G01X541929Y1001574D02*
X544685D01*
G01X537992D02*
X540748D01*
G01X530118D02*
X532874D01*
G01X534055D02*
X536811D01*
G01X541929Y1018110D02*
Y1001574D01*
G01X540748D02*
Y1018110D01*
G01X537992D02*
Y1001574D01*
G01X536811D02*
Y1018110D01*
G01X534055D02*
Y1001574D01*
G01X532874D02*
Y1018110D01*
G01X530118D02*
Y1001574D01*
G01X528937D02*
Y1018110D01*
G01X532874D02*
X530118D01*
G01X536811D02*
X534055D01*
G01X540748D02*
X537992D01*
G01X544685D02*
X541929D01*
G01X556275Y301477D02*
X557505D01*
G01X552338D02*
X553568D01*
G01X548401D02*
X549631D01*
G01X544464D02*
X545694D01*
G01X556287Y301194D02*
X557494D01*
G01X552350D02*
X553557D01*
G01X548413D02*
X549620D01*
G01X544475D02*
X545683D01*
G01X545707Y301107D02*
X544451D01*
G01X553581D02*
X552325D01*
G01X549644D02*
X548388D01*
G01X557518D02*
X556263D01*
G01X556275Y300492D02*
X557505D01*
G01X552338D02*
X553568D01*
G01X548401D02*
X549631D01*
G01X544464D02*
X545694D01*
G01X545685Y300266D02*
X544473D01*
G01X553559D02*
X552347D01*
G01X549622D02*
X548410D01*
G01X557496D02*
X556284D01*
G01X556265Y300197D02*
X557515D01*
G01X552328D02*
X553578D01*
G01X548391D02*
X549641D01*
G01X544454D02*
X545704D01*
G01X548583Y298720D02*
X548461D01*
G01X549572D02*
X548461D01*
G01X557446D02*
X556335D01*
G01X549572D02*
X549449D01*
G01X556335Y297736D02*
X557446D01*
G01X548461D02*
X549572D01*
G01X556316Y297287D02*
X557464D01*
G01X548442D02*
X549590D01*
G01X549581Y297019D02*
X548451D01*
G01X557455D02*
X556325D01*
G01X549595Y295500D02*
X548437D01*
G01X557469D02*
X556311D01*
G01X556320Y295232D02*
X557460D01*
G01X548446D02*
X549586D01*
G01X556301Y294783D02*
X557479D01*
G01X548427D02*
X549605D01*
G01X552364D02*
X553542D01*
G01X544490D02*
X545668D01*
G01Y293799D02*
X544490D01*
G01X549605D02*
X548427D01*
G01X553542D02*
X552364D01*
G01X557479D02*
X556301D01*
G01X545649Y293350D02*
X544509D01*
G01X553523D02*
X552383D01*
G01X552374Y293082D02*
X553532D01*
G01X544500D02*
X545658D01*
G01X552388Y291563D02*
X553518D01*
G01X544514D02*
X545644D01*
G01X545653Y291295D02*
X544505D01*
G01X553527D02*
X552379D01*
G01X545635Y290846D02*
X544524D01*
G01X553509D02*
X552398D01*
G01X545512Y289862D02*
X545635D01*
G01X552398D02*
X553509D01*
G01X544524D02*
X545635D01*
G01X552398D02*
X552520D01*
G01X544524D02*
X544646D01*
G01X557483Y299606D02*
X557496Y300266D01*
G01X557494Y301194D02*
X557463Y299606D01*
G01X553546D02*
X553559Y300266D01*
G01X553557Y301194D02*
X553526Y299606D01*
G01X549609D02*
X549622Y300266D01*
G01X549620Y301194D02*
X549589Y299606D01*
G01X545672D02*
X545685Y300266D01*
G01X545683Y301194D02*
X545652Y299606D01*
G01X556255D02*
X556265Y300197D01*
G01X556263Y301107D02*
X556237Y299606D01*
G01X552318D02*
X552328Y300197D01*
G01X552325Y301107D02*
X552300Y299606D01*
G01X548381D02*
X548391Y300197D01*
G01X548388Y301107D02*
X548363Y299606D01*
G01X544444D02*
X544454Y300197D01*
G01X544451Y301107D02*
X544426Y299606D01*
G01X556325Y297019D02*
X556320Y295232D01*
G01X556311Y295500D02*
X556316Y297287D01*
G01X553532Y293082D02*
X553527Y291295D01*
G01X553518Y291563D02*
X553523Y293350D01*
G01X548451Y297019D02*
X548446Y295232D01*
G01X548437Y295500D02*
X548442Y297287D01*
G01X545658Y293082D02*
X545653Y291295D01*
G01X545644Y291563D02*
X545649Y293350D01*
G01X557479Y294783D02*
Y293799D01*
G01X557323Y298720D02*
Y297736D01*
G01X556457Y298720D02*
Y297736D01*
G01X556301Y293799D02*
Y294783D01*
G01X553542Y293799D02*
Y294783D01*
G01X553386Y290846D02*
Y289862D01*
G01X552520Y290846D02*
Y289862D01*
G01X552364Y294783D02*
Y293799D01*
G01X549605Y294783D02*
Y293799D01*
G01X549449Y298720D02*
Y297736D01*
G01X548583Y298720D02*
Y297736D01*
G01X548427Y293799D02*
Y294783D01*
G01X545668Y293799D02*
Y294783D01*
G01X545512Y290846D02*
Y289862D01*
G01X544646Y290846D02*
Y289862D01*
G01X544490Y294783D02*
Y293799D01*
G01X557464Y297287D02*
X557469Y295500D01*
G01X557460Y295232D02*
X557455Y297019D01*
G01X552383Y293350D02*
X552388Y291563D01*
G01X552379Y291295D02*
X552374Y293082D01*
G01X549590Y297287D02*
X549595Y295500D01*
G01X549586Y295232D02*
X549581Y297019D01*
G01X544509Y293350D02*
X544514Y291563D01*
G01X544505Y291295D02*
X544500Y293082D01*
G01X557543Y299606D02*
X557518Y301107D01*
G01X557515Y300197D02*
X557525Y299606D01*
G01X553606D02*
X553581Y301107D01*
G01X553578Y300197D02*
X553588Y299606D01*
G01X549669D02*
X549644Y301107D01*
G01X549641Y300197D02*
X549651Y299606D01*
G01X545732D02*
X545707Y301107D01*
G01X545704Y300197D02*
X545714Y299606D01*
G01X556317D02*
X556287Y301194D01*
G01X556284Y300266D02*
X556297Y299606D01*
G01X552380D02*
X552350Y301194D01*
G01X552347Y300266D02*
X552360Y299606D01*
G01X548443D02*
X548413Y301194D01*
G01X548410Y300266D02*
X548423Y299606D01*
G01X544506D02*
X544475Y301194D01*
G01X544473Y300266D02*
X544486Y299606D01*
G01X544646Y316437D02*
X544524D01*
G01X545635D02*
X544524D01*
G01X553509D02*
X552398D01*
G01X545635D02*
X545512D01*
G01X545635Y315452D02*
X544524D01*
G01X553509D02*
X552398D01*
G01X552379Y315003D02*
X553527D01*
G01X544505D02*
X545653D01*
G01X545644Y314736D02*
X544514D01*
G01X553518D02*
X552388D01*
G01X545658Y313216D02*
X544500D01*
G01X553532D02*
X552374D01*
G01X552383Y312948D02*
X553523D01*
G01X544509D02*
X545649D01*
G01X545668Y312500D02*
X544490D01*
G01X549605D02*
X548427D01*
G01X553542D02*
X552364D01*
G01X557479D02*
X556301D01*
G01X545668Y311515D02*
X544490D01*
G01X549605D02*
X548427D01*
G01X553542D02*
X552364D01*
G01X557479D02*
X556301D01*
G01X549586Y311066D02*
X548446D01*
G01X557460D02*
X556320D01*
G01X556311Y310799D02*
X557469D01*
G01X548437D02*
X549595D01*
G01X556325Y309279D02*
X557455D01*
G01X548451D02*
X549581D01*
G01X549590Y309011D02*
X548442D01*
G01X557464D02*
X556316D01*
G01X549572Y308563D02*
X548461D01*
G01X557446D02*
X556335D01*
G01X549449Y307578D02*
X549572D01*
G01D02*
X548461D01*
G01X557446D02*
X556335D01*
G01X548461D02*
X548583D01*
G01X545704Y306102D02*
X544454D01*
G01X553578D02*
X552328D01*
G01X549641D02*
X548391D01*
G01X557515D02*
X556265D01*
G01X556284Y306032D02*
X557496D01*
G01X552347D02*
X553559D01*
G01X548410D02*
X549622D01*
G01X544473D02*
X545685D01*
G01X545694Y305806D02*
X544464D01*
G01X553568D02*
X552338D01*
G01X549631D02*
X548401D01*
G01X557505D02*
X556275D01*
G01X556263Y305191D02*
X557518D01*
G01X552325D02*
X553581D01*
G01X548388D02*
X549644D01*
G01X544451D02*
X545707D01*
G01X545683Y305104D02*
X544475D01*
G01X553557D02*
X552350D01*
G01X549620D02*
X548413D01*
G01X557494D02*
X556287D01*
G01X545694Y304822D02*
X544464D01*
G01X553568D02*
X552338D01*
G01X549631D02*
X548401D01*
G01X557505D02*
X556275D01*
G01X556287Y305104D02*
X556317Y306692D01*
G01X556297D02*
X556284Y306032D01*
G01X552350Y305104D02*
X552380Y306692D01*
G01X552360D02*
X552347Y306032D01*
G01X548413Y305104D02*
X548443Y306692D01*
G01X548423D02*
X548410Y306032D01*
G01X544475Y305104D02*
X544506Y306692D01*
G01X544486D02*
X544473Y306032D01*
G01X557518Y305191D02*
X557543Y306692D01*
G01X557525D02*
X557515Y306102D01*
G01X553581Y305191D02*
X553606Y306692D01*
G01X553588D02*
X553578Y306102D01*
G01X549644Y305191D02*
X549669Y306692D01*
G01X549651D02*
X549641Y306102D01*
G01X545707Y305191D02*
X545732Y306692D01*
G01X545714D02*
X545704Y306102D01*
G01X557469Y310799D02*
X557464Y309011D01*
G01X557455Y309279D02*
X557460Y311066D01*
G01X552388Y314736D02*
X552383Y312948D01*
G01X552374Y313216D02*
X552379Y315003D01*
G01X549595Y310799D02*
X549590Y309011D01*
G01X549581Y309279D02*
X549586Y311066D01*
G01X544514Y314736D02*
X544509Y312948D01*
G01X544500Y313216D02*
X544505Y315003D01*
G01X557479Y312500D02*
Y311515D01*
G01X557323Y308563D02*
Y307578D01*
G01X556457D02*
Y308563D01*
G01X556301Y311515D02*
Y312500D01*
G01X554725Y323228D02*
Y317618D01*
G01X553542Y311515D02*
Y312500D01*
G01X553386Y316437D02*
Y315452D01*
G01X552520D02*
Y316437D01*
G01X552364Y312500D02*
Y311515D01*
G01X549725Y323228D02*
Y317618D01*
G01X549605Y312500D02*
Y311515D01*
G01X549449Y308563D02*
Y307578D01*
G01X548583D02*
Y308563D01*
G01X548427Y311515D02*
Y312500D01*
G01X545668Y311515D02*
Y312500D01*
G01X545512Y316437D02*
Y315452D01*
G01X544646D02*
Y316437D01*
G01X544490Y312500D02*
Y311515D01*
G01X556320Y311066D02*
X556325Y309279D01*
G01X556316Y309011D02*
X556311Y310799D01*
G01X553527Y315003D02*
X553532Y313216D01*
G01X553523Y312948D02*
X553518Y314736D01*
G01X548446Y311066D02*
X548451Y309279D01*
G01X548442Y309011D02*
X548437Y310799D01*
G01X545653Y315003D02*
X545658Y313216D01*
G01X545649Y312948D02*
X545644Y314736D01*
G01X556265Y306102D02*
X556255Y306692D01*
G01X556237D02*
X556263Y305191D01*
G01X552328Y306102D02*
X552318Y306692D01*
G01X552300D02*
X552325Y305191D01*
G01X548391Y306102D02*
X548381Y306692D01*
G01X548363D02*
X548388Y305191D01*
G01X544454Y306102D02*
X544444Y306692D01*
G01X544426D02*
X544451Y305191D01*
G01X557496Y306032D02*
X557483Y306692D01*
G01X557463D02*
X557494Y305104D01*
G01X553559Y306032D02*
X553546Y306692D01*
G01X553526D02*
X553557Y305104D01*
G01X549622Y306032D02*
X549609Y306692D01*
G01X549589D02*
X549620Y305104D01*
G01X545685Y306032D02*
X545672Y306692D01*
G01X545652D02*
X545683Y305104D01*
G01X570630Y323228D02*
X554725D01*
G01X545472Y994290D02*
G03X552953I3740J1D01*
G01X545473Y994291D02*
G03X552953I3740J0D01*
G01X545472Y994290D02*
Y1018109D01*
G01X552953D02*
Y994290D01*
G01X556496Y1001574D02*
X553740D01*
G01X560433D02*
X557677D01*
G01D02*
Y1018110D01*
G01X556496D02*
Y1001574D01*
G01X553740D02*
Y1018110D01*
G01X552953Y1021653D02*
Y994291D01*
G01X545473D02*
Y1021653D01*
G01X544685Y1001574D02*
Y1018110D01*
G01X545473Y1021653D02*
X545472Y1018109D01*
G01X544489Y1022637D02*
X545473Y1021653D01*
G01X552953D02*
Y1018109D01*
G01X595079Y1023622D02*
X554922D01*
G01X545473Y1021653D02*
X543505Y1023622D01*
G01X554922D02*
X552953Y1021653D01*
G01X595079Y1023622D02*
X554922D01*
G01X557677Y1018110D02*
X560433D01*
G01X553740D02*
X556496D01*
G01X597048D02*
X552953D01*
G01X545473Y1021653D02*
X543504Y1023622D01*
G01X554922D02*
X552953Y1021653D01*
G01X572023Y301477D02*
X573253D01*
G01X568086D02*
X569316D01*
G01X564149D02*
X565379D01*
G01X560212D02*
X561442D01*
G01X572035Y301194D02*
X573242D01*
G01X568098D02*
X569305D01*
G01X564161D02*
X565368D01*
G01X560224D02*
X561431D01*
G01X561455Y301107D02*
X560200D01*
G01X565392D02*
X564137D01*
G01X569329D02*
X568074D01*
G01X573266D02*
X572011D01*
G01X572023Y300492D02*
X573253D01*
G01X568086D02*
X569316D01*
G01X564149D02*
X565379D01*
G01X560212D02*
X561442D01*
G01X561433Y300266D02*
X560221D01*
G01X565370D02*
X564158D01*
G01X569307D02*
X568095D01*
G01X573244D02*
X572032D01*
G01X572013Y300197D02*
X573263D01*
G01X568076D02*
X569326D01*
G01X564139D02*
X565389D01*
G01X560202D02*
X561452D01*
G01X565320Y298720D02*
X564209D01*
G01X573194D02*
X572083D01*
G01Y297736D02*
X573194D01*
G01X564209D02*
X565320D01*
G01X572064Y297287D02*
X573212D01*
G01X564190D02*
X565338D01*
G01X565329Y297019D02*
X564200D01*
G01X573203D02*
X572074D01*
G01X565343Y295500D02*
X564185D01*
G01X573217D02*
X572059D01*
G01X572068Y295232D02*
X573208D01*
G01X564194D02*
X565334D01*
G01X572050Y294783D02*
X573227D01*
G01X568113D02*
X569290D01*
G01X564175D02*
X565353D01*
G01X560238D02*
X561416D01*
G01Y293799D02*
X560238D01*
G01X565353D02*
X564175D01*
G01X569290D02*
X568113D01*
G01X573227D02*
X572050D01*
G01X561397Y293350D02*
X560257D01*
G01X569271D02*
X568131D01*
G01X568122Y293082D02*
X569280D01*
G01X560248D02*
X561406D01*
G01X568137Y291563D02*
X569266D01*
G01X560263D02*
X561392D01*
G01X561401Y291295D02*
X560253D01*
G01X569275D02*
X568127D01*
G01X561383Y290846D02*
X560272D01*
G01X569257D02*
X568146D01*
G01Y289862D02*
X569257D01*
G01X560272D02*
X561383D01*
G01X573231Y299606D02*
X573244Y300266D01*
G01X573242Y301194D02*
X573211Y299606D01*
G01X569294D02*
X569307Y300266D01*
G01X569305Y301194D02*
X569274Y299606D01*
G01X565357D02*
X565370Y300266D01*
G01X565368Y301194D02*
X565337Y299606D01*
G01X561420D02*
X561433Y300266D01*
G01X561431Y301194D02*
X561400Y299606D01*
G01X575948Y301107D02*
X575922Y299606D01*
G01X572003D02*
X572013Y300197D01*
G01X572011Y301107D02*
X571985Y299606D01*
G01X568066D02*
X568076Y300197D01*
G01X568074Y301107D02*
X568048Y299606D01*
G01X564129D02*
X564139Y300197D01*
G01X564137Y301107D02*
X564111Y299606D01*
G01X560192D02*
X560202Y300197D01*
G01X560200Y301107D02*
X560174Y299606D01*
G01X572074Y297019D02*
X572068Y295232D01*
G01X572059Y295500D02*
X572064Y297287D01*
G01X569280Y293082D02*
X569275Y291295D01*
G01X569266Y291563D02*
X569271Y293350D01*
G01X564200Y297019D02*
X564194Y295232D01*
G01X564185Y295500D02*
X564190Y297287D01*
G01X561406Y293082D02*
X561401Y291295D01*
G01X561392Y291563D02*
X561397Y293350D01*
G01X573227Y294783D02*
Y293799D01*
G01X573071Y298720D02*
Y297736D01*
G01X572205Y298720D02*
Y297736D01*
G01X572050Y293799D02*
Y294783D01*
G01X569290Y293799D02*
Y294783D01*
G01X569134Y290846D02*
Y289862D01*
G01X568268Y290846D02*
Y289862D01*
G01X568113Y294783D02*
Y293799D01*
G01X565353Y294783D02*
Y293799D01*
G01X565197Y298720D02*
Y297736D01*
G01X564331Y298720D02*
Y297736D01*
G01X564175Y293799D02*
Y294783D01*
G01X561416Y293799D02*
Y294783D01*
G01X561260Y290846D02*
Y289862D01*
G01X560394Y290846D02*
Y289862D01*
G01X560238Y294783D02*
Y293799D01*
G01X573212Y297287D02*
X573217Y295500D01*
G01X573208Y295232D02*
X573203Y297019D01*
G01X568131Y293350D02*
X568137Y291563D01*
G01X568127Y291295D02*
X568122Y293082D01*
G01X565338Y297287D02*
X565343Y295500D01*
G01X565334Y295232D02*
X565329Y297019D01*
G01X560257Y293350D02*
X560263Y291563D01*
G01X560253Y291295D02*
X560248Y293082D01*
G01X573291Y299606D02*
X573266Y301107D01*
G01X573263Y300197D02*
X573273Y299606D01*
G01X569354D02*
X569329Y301107D01*
G01X569326Y300197D02*
X569336Y299606D01*
G01X565417D02*
X565392Y301107D01*
G01X565389Y300197D02*
X565399Y299606D01*
G01X561480D02*
X561455Y301107D01*
G01X561452Y300197D02*
X561462Y299606D01*
G01X572065D02*
X572035Y301194D01*
G01X572032Y300266D02*
X572045Y299606D01*
G01X568128D02*
X568098Y301194D01*
G01X568095Y300266D02*
X568108Y299606D01*
G01X564191D02*
X564161Y301194D01*
G01X564158Y300266D02*
X564171Y299606D01*
G01X560254D02*
X560224Y301194D01*
G01X560221Y300266D02*
X560234Y299606D01*
G01X561383Y316437D02*
X560272D01*
G01X569257D02*
X568146D01*
G01X561383Y315452D02*
X560272D01*
G01X569257D02*
X568146D01*
G01X568127Y315003D02*
X569275D01*
G01X560253D02*
X561401D01*
G01X561392Y314736D02*
X560263D01*
G01X569266D02*
X568137D01*
G01X561406Y313216D02*
X560248D01*
G01X569280D02*
X568122D01*
G01X568131Y312948D02*
X569271D01*
G01X560257D02*
X561397D01*
G01X561416Y312500D02*
X560238D01*
G01X565353D02*
X564175D01*
G01X569290D02*
X568113D01*
G01X573227D02*
X572050D01*
G01X561416Y311515D02*
X560238D01*
G01X565353D02*
X564175D01*
G01X569290D02*
X568113D01*
G01X573227D02*
X572050D01*
G01X565334Y311066D02*
X564194D01*
G01X573208D02*
X572068D01*
G01X572059Y310799D02*
X573217D01*
G01X564185D02*
X565343D01*
G01X572074Y309279D02*
X573203D01*
G01X564200D02*
X565329D01*
G01X565338Y309011D02*
X564190D01*
G01X573212D02*
X572064D01*
G01X565320Y308563D02*
X564209D01*
G01X573194D02*
X572083D01*
G01X565320Y307578D02*
X564209D01*
G01X573194D02*
X572083D01*
G01X561452Y306102D02*
X560202D01*
G01X565389D02*
X564139D01*
G01X569326D02*
X568076D01*
G01X573263D02*
X572013D01*
G01X572032Y306032D02*
X573244D01*
G01X568095D02*
X569307D01*
G01X564158D02*
X565370D01*
G01X560221D02*
X561433D01*
G01X561442Y305806D02*
X560212D01*
G01X565379D02*
X564149D01*
G01X569316D02*
X568086D01*
G01X573253D02*
X572023D01*
G01X572011Y305191D02*
X573266D01*
G01X568074D02*
X569329D01*
G01X564137D02*
X565392D01*
G01X560200D02*
X561455D01*
G01X561431Y305104D02*
X560224D01*
G01X565368D02*
X564161D01*
G01X569305D02*
X568098D01*
G01X573242D02*
X572035D01*
G01X561442Y304822D02*
X560212D01*
G01X565379D02*
X564149D01*
G01X569316D02*
X568086D01*
G01X573253D02*
X572023D01*
G01X572035Y305104D02*
X572065Y306692D01*
G01X572045D02*
X572032Y306032D01*
G01X568098Y305104D02*
X568128Y306692D01*
G01X568108D02*
X568095Y306032D01*
G01X564161Y305104D02*
X564191Y306692D01*
G01X564171D02*
X564158Y306032D01*
G01X560224Y305104D02*
X560254Y306692D01*
G01X560234D02*
X560221Y306032D01*
G01X573266Y305191D02*
X573291Y306692D01*
G01X573273D02*
X573263Y306102D01*
G01X569329Y305191D02*
X569354Y306692D01*
G01X569336D02*
X569326Y306102D01*
G01X565392Y305191D02*
X565417Y306692D01*
G01X565399D02*
X565389Y306102D01*
G01X561455Y305191D02*
X561480Y306692D01*
G01X561462D02*
X561452Y306102D01*
G01X573217Y310799D02*
X573212Y309011D01*
G01X573203Y309279D02*
X573208Y311066D01*
G01X568137Y314736D02*
X568131Y312948D01*
G01X568122Y313216D02*
X568127Y315003D01*
G01X565343Y310799D02*
X565338Y309011D01*
G01X565329Y309279D02*
X565334Y311066D01*
G01X560263Y314736D02*
X560257Y312948D01*
G01X560248Y313216D02*
X560253Y315003D01*
G01X575630Y323228D02*
Y317618D01*
G01X573227Y312500D02*
Y311515D01*
G01X573071Y308563D02*
Y307578D01*
G01X572205D02*
Y308563D01*
G01X572050Y311515D02*
Y312500D01*
G01X570630Y323228D02*
Y317618D01*
G01X569290Y311515D02*
Y312500D01*
G01X569134Y316437D02*
Y315452D01*
G01X568268D02*
Y316437D01*
G01X568113Y312500D02*
Y311515D01*
G01X565353Y312500D02*
Y311515D01*
G01X565197Y308563D02*
Y307578D01*
G01X564331D02*
Y308563D01*
G01X564175Y311515D02*
Y312500D01*
G01X561416Y311515D02*
Y312500D01*
G01X561260Y316437D02*
Y315452D01*
G01X560394D02*
Y316437D01*
G01X560238Y312500D02*
Y311515D01*
G01X572068Y311066D02*
X572074Y309279D01*
G01X572064Y309011D02*
X572059Y310799D01*
G01X569275Y315003D02*
X569280Y313216D01*
G01X569271Y312948D02*
X569266Y314736D01*
G01X564194Y311066D02*
X564200Y309279D01*
G01X564190Y309011D02*
X564185Y310799D01*
G01X561401Y315003D02*
X561406Y313216D01*
G01X561397Y312948D02*
X561392Y314736D01*
G01X575922Y306692D02*
X575948Y305191D01*
G01X572013Y306102D02*
X572003Y306692D01*
G01X571985D02*
X572011Y305191D01*
G01X568076Y306102D02*
X568066Y306692D01*
G01X568048D02*
X568074Y305191D01*
G01X564139Y306102D02*
X564129Y306692D01*
G01X564111D02*
X564137Y305191D01*
G01X560202Y306102D02*
X560192Y306692D01*
G01X560174D02*
X560200Y305191D01*
G01X573244Y306032D02*
X573231Y306692D01*
G01X573211D02*
X573242Y305104D01*
G01X569307Y306032D02*
X569294Y306692D01*
G01X569274D02*
X569305Y305104D01*
G01X565370Y306032D02*
X565357Y306692D01*
G01X565337D02*
X565368Y305104D01*
G01X561433Y306032D02*
X561420Y306692D01*
G01X561400D02*
X561431Y305104D01*
G01X579134Y337992D02*
G03I-6890J0D01*
G01D02*
G03I-6890J0D01*
G01X572244Y324212D02*
G03Y351771I0J13780D01*
G01X591536Y323228D02*
X575630D01*
G01X560433Y422637D02*
Y324212D01*
G01X560464Y360343D02*
G03X568307Y351771I7843J-698D01*
G01X572244D02*
X568307D01*
G01X560464Y360343D02*
X560433Y422637D01*
G01X564370Y1001574D02*
X561614D01*
G01X568307D02*
X565551D01*
G01X572244D02*
X569488D01*
G01X576181D02*
X573425D01*
G01D02*
Y1018110D01*
G01X572244D02*
Y1001574D01*
G01X569488D02*
Y1018110D01*
G01X568307D02*
Y1001574D01*
G01X565551D02*
Y1018110D01*
G01X564370D02*
Y1001574D01*
G01X561614D02*
Y1018110D01*
G01X560433D02*
Y1001574D01*
G01X573425Y1018110D02*
X576181D01*
G01X569488D02*
X572244D01*
G01X565551D02*
X568307D01*
G01X561614D02*
X564370D01*
G01X586772Y-5512D02*
G03X587559Y-6300I788J0D01*
G01X585985D02*
G03X586784Y-7087I787J0D01*
G01X590315Y-4331D02*
G03X591103Y-3544I1J787D01*
G01X586772Y-6949D02*
G03X587559Y-7737I788J0D01*
G01X592087D02*
G03X592874Y-6949I0J787D01*
G01X585197Y-6300D02*
G03X586772Y-7874I1575J1D01*
G01X589065Y7322D02*
X588081Y6338D01*
G01X591427Y39874D02*
Y-4095D01*
G01X591103Y-2227D02*
Y-3544D01*
G01X588081Y6338D02*
Y25629D01*
G01X587215Y3713D02*
Y-2227D01*
G01X587166Y-7048D02*
Y87176D01*
G01X586772Y85236D02*
Y-6949D01*
G01X586378Y86614D02*
Y-6260D01*
G01X585985Y-6300D02*
Y85602D01*
G01X585197Y-6300D02*
Y85602D01*
G01X592609Y6338D02*
X591624Y7322D01*
G01X586378Y-6260D02*
X587166Y-7048D01*
G01X592609Y6338D02*
X588081D01*
G01X585985Y5118D02*
X585197D01*
G01X585985Y4330D02*
X585197D01*
G01X593170Y3713D02*
X587215D01*
G01X585197Y3543D02*
X587215D01*
G01X593170Y-2227D02*
X587215D01*
G01X648455Y-4095D02*
X591427D01*
G01X585197Y-4331D02*
X590315D01*
G01X585985Y-5119D02*
X585197D01*
G01Y-5512D02*
X585985D01*
G01X585197Y-5906D02*
X585985D01*
G01X587559Y-6300D02*
X610204D01*
G01X585985D02*
X585197D01*
G01X592874Y-6949D02*
X586772D01*
G01X652717Y-7048D02*
X587166D01*
G01X585408Y-7087D02*
X654474D01*
G01X592481Y-7470D02*
X586969D01*
G01X592087Y-7737D02*
X587559D01*
G01X586772Y-7874D02*
X653111D01*
G01X592313Y19271D02*
G03I-1968J0D01*
G01Y9271D02*
G03I-1968J0D01*
G01X592609Y12637D02*
X591624Y11653D01*
G01Y30944D02*
Y7322D01*
G01X591231Y16181D02*
Y8149D01*
G01Y20118D02*
Y18149D01*
G01Y30118D02*
Y22086D01*
G01X589459Y8149D02*
Y16181D01*
G01Y20118D02*
Y18149D01*
G01Y30118D02*
Y22086D01*
G01X589262Y7854D02*
Y11397D01*
G01Y20413D02*
Y17854D01*
G01X589065Y30944D02*
Y7322D01*
G01X586605Y12933D02*
Y25334D01*
G01X589065Y11653D02*
X588081Y12637D01*
G01X591231Y22086D02*
X589459D01*
G01X591427Y20413D02*
X589262D01*
G01X591231Y20118D02*
X589459D01*
G01X591231Y18149D02*
X589459D01*
G01X591427Y17854D02*
X589262D01*
G01X586772Y16181D02*
X592874D01*
G01X589459Y14294D02*
X591231D01*
G01Y14212D02*
X589459D01*
G01Y13228D02*
X591231D01*
G01X594085Y12933D02*
X586605D01*
G01X588081Y12637D02*
X586378D01*
G01X589262Y11397D02*
X591427D01*
G01X591231Y11341D02*
X589459D01*
G01X591427Y10413D02*
X589262D01*
G01X591231Y10118D02*
X589459D01*
G01Y9133D02*
X591231D01*
G01Y8149D02*
X589459D01*
G01X591427Y7854D02*
X589262D01*
G01X591624Y7322D02*
X589065D01*
G01X588081Y25629D02*
X589065Y26614D01*
G01X591624Y30944D02*
X592609Y31929D01*
G01X591260Y45321D02*
Y39874D01*
G01X589823Y39409D02*
Y85472D01*
G01X589262Y26870D02*
Y30413D01*
G01X588081Y31929D02*
Y26614D01*
G01Y31929D02*
X589065Y30944D01*
G01X591624Y26614D02*
X592609Y25629D01*
G01X591260Y39874D02*
X596706D01*
G01X585197Y39765D02*
X585985D01*
G01Y39691D02*
X585197D01*
G01Y39566D02*
X585985D01*
G01X650059Y39409D02*
X589823D01*
G01X585197Y38958D02*
X585985D01*
G01X585197Y35261D02*
X585985D01*
G01X585197Y34035D02*
X585985D01*
G01Y33302D02*
X585197D01*
G01X588081Y31929D02*
X592609D01*
G01X591624Y30944D02*
X589065D01*
G01X591427Y30413D02*
X589262D01*
G01X591231Y30118D02*
X589459D01*
G01X591231Y29133D02*
X589459D01*
G01Y28149D02*
X591231D01*
G01X591427Y27854D02*
X589262D01*
G01X591231Y26926D02*
X589459D01*
G01X591427Y26870D02*
X589262D01*
G01X589065Y26614D02*
X586378D01*
G01X593170D02*
X591624D01*
G01X588081Y25629D02*
X586378D01*
G01X592874Y25433D02*
X586772D01*
G01X594085Y25334D02*
X586605D01*
G01X591231Y25039D02*
X589459D01*
G01X591231Y24055D02*
X589459D01*
G01X591231Y23973D02*
X589459D01*
G01X590315Y51377D02*
G03X591103Y52165I0J788D01*
G01X588406Y44133D02*
G03I-3091J0D01*
G01X591427Y60078D02*
Y45321D01*
G01X591103Y58464D02*
Y52165D01*
G01X590020Y48070D02*
Y40196D01*
G01X585197Y51377D02*
X590315D01*
G01X585985Y50590D02*
X585197D01*
G01Y49803D02*
X585985D01*
G01Y48622D02*
X585197D01*
G01X590020Y48070D02*
X649863D01*
G01X585197Y47834D02*
X585985D01*
G01Y46259D02*
X585197D01*
G01X590020Y46102D02*
X649863D01*
G01X585985Y45335D02*
X585197D01*
G01X596706Y45321D02*
X591260D01*
G01X585197Y42853D02*
X585985D01*
G01X585197Y41929D02*
X585985D01*
G01X591260Y40984D02*
X590020D01*
G01X585985Y40498D02*
X585197D01*
G01X585985Y40354D02*
X585197D01*
G01X591260Y40196D02*
X590020D01*
G01X585985Y72792D02*
G03X586378Y73474I-394J682D01*
G01Y72110D02*
G03X585985Y71428I394J-681D01*
G01X586378Y72110D02*
G03X587166Y73474I-787J1364D01*
G01X585985Y72792D02*
G03X585197Y71428I787J-1364D01*
G01X591103Y58464D02*
G03X590315Y59252I-788J0D01*
G01X587166Y69724D02*
X586378Y68937D01*
G01X590020Y84685D02*
Y67362D01*
G01X587559Y85472D02*
Y56929D01*
G01X587116Y68700D02*
Y68503D01*
G01X585197Y72699D02*
X585985D01*
G01X587559Y69724D02*
X587166D01*
G01X586378Y68700D02*
X587166D01*
G01X585197D02*
X585985D01*
G01X587116Y68503D02*
X585197D01*
G01X649863Y67362D02*
X590020D01*
G01X587166Y61023D02*
X585197D01*
G01X585985Y60826D02*
X585197D01*
G01X591427Y60078D02*
X586378D01*
G01X585985Y60039D02*
X585197D01*
G01Y59252D02*
X590315D01*
G01X587559Y56929D02*
X586378D01*
G01X586772Y86389D02*
G03X585985Y85602I0J-787D01*
G01X586772Y87176D02*
G03X585197Y85602I0J-1575D01*
G01X587166Y85472D02*
X586378Y84685D01*
G01X585985Y79133D02*
X587166Y82677D01*
G01X586378D02*
X585197Y79133D01*
G01X586772Y85078D02*
X587166Y84685D01*
G01X585563Y86610D02*
X586167Y86106D01*
G01X587087Y82440D02*
X586378Y82677D01*
G01X653111Y87176D02*
X586772D01*
G01X587166Y86614D02*
X586378D01*
G01X586772Y86389D02*
X653111D01*
G01X593344Y85995D02*
X587166D01*
G01X586378Y85826D02*
X587166D01*
G01X585197Y85602D02*
X585985D01*
G01X587166Y85472D02*
X652717D01*
G01X587166Y85236D02*
X585563D01*
G01X585985Y84744D02*
X585197D01*
G01X652717Y84685D02*
X587166D01*
G01X586378Y82677D02*
X587166D01*
G01X585985Y82452D02*
X585197D01*
G01X585985Y81861D02*
X585197D01*
G01X585985Y79133D02*
X585197D01*
G01X587166Y78740D02*
X586378D01*
G01X585985Y78318D02*
X585197D01*
G01X585985Y77727D02*
X585197D01*
G01Y73831D02*
X585985D01*
G01Y73594D02*
X585197D01*
G01X585985Y73263D02*
X585197D01*
G01X588979Y299606D02*
X588992Y300266D01*
G01X588990Y301194D02*
X588959Y299606D01*
G01X585042D02*
X585055Y300266D01*
G01X585053Y301194D02*
X585022Y299606D01*
G01X591688D02*
X591698Y300197D01*
G01X591696Y301107D02*
X591670Y299606D01*
G01X587751D02*
X587761Y300197D01*
G01X587759Y301107D02*
X587733Y299606D01*
G01X583814D02*
X583824Y300197D01*
G01X583822Y301107D02*
X583796Y299606D01*
G01X587822Y297019D02*
X587816Y295232D01*
G01X587807Y295500D02*
X587812Y297287D01*
G01X585028Y293082D02*
X585023Y291295D01*
G01X585014Y291563D02*
X585019Y293350D01*
G01X591890Y290846D02*
Y289862D01*
G01X591735Y294783D02*
Y293799D01*
G01X588975Y294783D02*
Y293799D01*
G01X588819Y298720D02*
Y297736D01*
G01X587953Y298720D02*
Y297736D01*
G01X587798Y293799D02*
Y294783D01*
G01X585038Y293799D02*
Y294783D01*
G01X584882Y290846D02*
Y289862D01*
G01X591753Y293350D02*
X591759Y291563D01*
G01X591749Y291295D02*
X591744Y293082D01*
G01X588960Y297287D02*
X588965Y295500D01*
G01X588956Y295232D02*
X588951Y297019D01*
G01X589039Y299606D02*
X589014Y301107D01*
G01X589011Y300197D02*
X589021Y299606D01*
G01X591750D02*
X591720Y301194D01*
G01X591717Y300266D02*
X591730Y299606D01*
G01X587813D02*
X587783Y301194D01*
G01X587780Y300266D02*
X587793Y299606D01*
G01X591708Y301477D02*
X592938D01*
G01X587771D02*
X589001D01*
G01X583834D02*
X585064D01*
G01X579897D02*
X581127D01*
G01X575960D02*
X577190D01*
G01X591720Y301194D02*
X592927D01*
G01X587783D02*
X588990D01*
G01X583846D02*
X585053D01*
G01X579909D02*
X581116D01*
G01X575972D02*
X577179D01*
G01X577203Y301107D02*
X575948D01*
G01X581140D02*
X579885D01*
G01X585077D02*
X583822D01*
G01X589014D02*
X587759D01*
G01X592951D02*
X591696D01*
G01X591708Y300492D02*
X592938D01*
G01X587771D02*
X589001D01*
G01X583834D02*
X585064D01*
G01X579897D02*
X581127D01*
G01X575960D02*
X577190D01*
G01X577181Y300266D02*
X575969D01*
G01X581118D02*
X579906D01*
G01X585055D02*
X583843D01*
G01X588992D02*
X587780D01*
G01X592929D02*
X591717D01*
G01X591698Y300197D02*
X592948D01*
G01X587761D02*
X589011D01*
G01X583824D02*
X585074D01*
G01X579887D02*
X581137D01*
G01X575950D02*
X577200D01*
G01X581068Y298720D02*
X579957D01*
G01X588942D02*
X587831D01*
G01Y297736D02*
X588942D01*
G01X579957D02*
X581068D01*
G01X587812Y297287D02*
X588960D01*
G01X579938D02*
X581086D01*
G01X581077Y297019D02*
X579948D01*
G01X588951D02*
X587822D01*
G01X581091Y295500D02*
X579933D01*
G01X588965D02*
X587807D01*
G01X587816Y295232D02*
X588956D01*
G01X579942D02*
X581082D01*
G01X591735Y294783D02*
X592912D01*
G01X587798D02*
X588975D01*
G01X583861D02*
X585038D01*
G01X579924D02*
X581101D01*
G01X575987D02*
X577164D01*
G01Y293799D02*
X575987D01*
G01X581101D02*
X579924D01*
G01X585038D02*
X583861D01*
G01X588975D02*
X587798D01*
G01X592912D02*
X591735D01*
G01X577145Y293350D02*
X576005D01*
G01X585019D02*
X583879D01*
G01X592893D02*
X591753D01*
G01X591744Y293082D02*
X592902D01*
G01X583870D02*
X585028D01*
G01X575996D02*
X577154D01*
G01X591759Y291563D02*
X592888D01*
G01X583885D02*
X585014D01*
G01X576011D02*
X577140D01*
G01X577149Y291295D02*
X576001D01*
G01X585023D02*
X583875D01*
G01X592897D02*
X591749D01*
G01X577131Y290846D02*
X576020D01*
G01X585005D02*
X583894D01*
G01X592879D02*
X591768D01*
G01Y289862D02*
X592879D01*
G01X583894D02*
X585005D01*
G01X576020D02*
X577131D01*
G01X581105Y299606D02*
X581118Y300266D01*
G01X581116Y301194D02*
X581085Y299606D01*
G01X577168D02*
X577181Y300266D01*
G01X577179Y301194D02*
X577148Y299606D01*
G01X579877D02*
X579887Y300197D01*
G01X579885Y301107D02*
X579859Y299606D01*
G01X575940D02*
X575950Y300197D01*
G01X579948Y297019D02*
X579942Y295232D01*
G01X579933Y295500D02*
X579938Y297287D01*
G01X577154Y293082D02*
X577149Y291295D01*
G01X577140Y291563D02*
X577145Y293350D01*
G01X584016Y290846D02*
Y289862D01*
G01X583861Y294783D02*
Y293799D01*
G01X581101Y294783D02*
Y293799D01*
G01X580945Y298720D02*
Y297736D01*
G01X580079Y298720D02*
Y297736D01*
G01X579924Y293799D02*
Y294783D01*
G01X577164Y293799D02*
Y294783D01*
G01X577008Y290846D02*
Y289862D01*
G01X576142Y290846D02*
Y289862D01*
G01X575987Y294783D02*
Y293799D01*
G01X583879Y293350D02*
X583885Y291563D01*
G01X583875Y291295D02*
X583870Y293082D01*
G01X581086Y297287D02*
X581091Y295500D01*
G01X581082Y295232D02*
X581077Y297019D01*
G01X576005Y293350D02*
X576011Y291563D01*
G01X576001Y291295D02*
X575996Y293082D01*
G01X585102Y299606D02*
X585077Y301107D01*
G01X585074Y300197D02*
X585084Y299606D01*
G01X581165D02*
X581140Y301107D01*
G01X581137Y300197D02*
X581147Y299606D01*
G01X577228D02*
X577203Y301107D01*
G01X577200Y300197D02*
X577210Y299606D01*
G01X583876D02*
X583846Y301194D01*
G01X583843Y300266D02*
X583856Y299606D01*
G01X579939D02*
X579909Y301194D01*
G01X579906Y300266D02*
X579919Y299606D01*
G01X576002D02*
X575972Y301194D01*
G01X575969Y300266D02*
X575982Y299606D01*
G01X577131Y316437D02*
X576020D01*
G01X585005D02*
X583894D01*
G01X592879D02*
X591768D01*
G01X577131Y315452D02*
X576020D01*
G01X585005D02*
X583894D01*
G01X592879D02*
X591768D01*
G01X591749Y315003D02*
X592897D01*
G01X583875D02*
X585023D01*
G01X576001D02*
X577149D01*
G01X577140Y314736D02*
X576011D01*
G01X585014D02*
X583885D01*
G01X592888D02*
X591759D01*
G01X577154Y313216D02*
X575996D01*
G01X585028D02*
X583870D01*
G01X592902D02*
X591744D01*
G01X591753Y312948D02*
X592893D01*
G01X583879D02*
X585019D01*
G01X576005D02*
X577145D01*
G01X577164Y312500D02*
X575987D01*
G01X581101D02*
X579924D01*
G01X585038D02*
X583861D01*
G01X588975D02*
X587798D01*
G01X592912D02*
X591735D01*
G01X577164Y311515D02*
X575987D01*
G01X581101D02*
X579924D01*
G01X585038D02*
X583861D01*
G01X588975D02*
X587798D01*
G01X592912D02*
X591735D01*
G01X581082Y311066D02*
X579942D01*
G01X588956D02*
X587816D01*
G01X587807Y310799D02*
X588965D01*
G01X579933D02*
X581091D01*
G01X591720Y305104D02*
X591750Y306692D01*
G01X591730D02*
X591717Y306032D01*
G01X587783Y305104D02*
X587813Y306692D01*
G01X587793D02*
X587780Y306032D01*
G01X583846Y305104D02*
X583876Y306692D01*
G01X583856D02*
X583843Y306032D01*
G01X589014Y305191D02*
X589039Y306692D01*
G01X589021D02*
X589011Y306102D01*
G01X585077Y305191D02*
X585102Y306692D01*
G01X585084D02*
X585074Y306102D01*
G01X591759Y314736D02*
X591753Y312948D01*
G01X591744Y313216D02*
X591749Y315003D01*
G01X588965Y310799D02*
X588960Y309011D01*
G01X588951Y309279D02*
X588956Y311066D01*
G01X591890Y315452D02*
Y316437D01*
G01X591735Y312500D02*
Y311515D01*
G01X591536Y323228D02*
Y317618D01*
G01X588975Y312500D02*
Y311515D01*
G01X588819Y308563D02*
Y307578D01*
G01X587953D02*
Y308563D01*
G01X587798Y311515D02*
Y312500D01*
G01X585038Y311515D02*
Y312500D01*
G01X584882Y316437D02*
Y315452D01*
G01X587816Y311066D02*
X587822Y309279D01*
G01X587812Y309011D02*
X587807Y310799D01*
G01X591698Y306102D02*
X591688Y306692D01*
G01X591670D02*
X591696Y305191D01*
G01X587761Y306102D02*
X587751Y306692D01*
G01X587733D02*
X587759Y305191D01*
G01X588992Y306032D02*
X588979Y306692D01*
G01X588959D02*
X588990Y305104D01*
G01X587822Y309279D02*
X588951D01*
G01X579948D02*
X581077D01*
G01X581086Y309011D02*
X579938D01*
G01X588960D02*
X587812D01*
G01X581068Y308563D02*
X579957D01*
G01X588942D02*
X587831D01*
G01X581068Y307578D02*
X579957D01*
G01X588942D02*
X587831D01*
G01X577200Y306102D02*
X575950D01*
G01X581137D02*
X579887D01*
G01X585074D02*
X583824D01*
G01X589011D02*
X587761D01*
G01X592948D02*
X591698D01*
G01X591717Y306032D02*
X592929D01*
G01X587780D02*
X588992D01*
G01X583843D02*
X585055D01*
G01X579906D02*
X581118D01*
G01X575969D02*
X577181D01*
G01X577190Y305806D02*
X575960D01*
G01X581127D02*
X579897D01*
G01X585064D02*
X583834D01*
G01X589001D02*
X587771D01*
G01X592938D02*
X591708D01*
G01X591696Y305191D02*
X592951D01*
G01X587759D02*
X589014D01*
G01X583822D02*
X585077D01*
G01X579885D02*
X581140D01*
G01X575948D02*
X577203D01*
G01X577179Y305104D02*
X575972D01*
G01X581116D02*
X579909D01*
G01X585053D02*
X583846D01*
G01X588990D02*
X587783D01*
G01X592927D02*
X591720D01*
G01X577190Y304822D02*
X575960D01*
G01X581127D02*
X579897D01*
G01X585064D02*
X583834D01*
G01X589001D02*
X587771D01*
G01X592938D02*
X591708D01*
G01X579909Y305104D02*
X579939Y306692D01*
G01X579919D02*
X579906Y306032D01*
G01X575972Y305104D02*
X576002Y306692D01*
G01X575982D02*
X575969Y306032D01*
G01X581140Y305191D02*
X581165Y306692D01*
G01X581147D02*
X581137Y306102D01*
G01X577203Y305191D02*
X577228Y306692D01*
G01X577210D02*
X577200Y306102D01*
G01X583885Y314736D02*
X583879Y312948D01*
G01X583870Y313216D02*
X583875Y315003D01*
G01X581091Y310799D02*
X581086Y309011D01*
G01X581077Y309279D02*
X581082Y311066D01*
G01X576011Y314736D02*
X576005Y312948D01*
G01X575996Y313216D02*
X576001Y315003D01*
G01X584016Y315452D02*
Y316437D01*
G01X583861Y312500D02*
Y311515D01*
G01X581101Y312500D02*
Y311515D01*
G01X580945Y308563D02*
Y307578D01*
G01X580079D02*
Y308563D01*
G01X579924Y311515D02*
Y312500D01*
G01X577164Y311515D02*
Y312500D01*
G01X577008Y316437D02*
Y315452D01*
G01X576142D02*
Y316437D01*
G01X575987Y312500D02*
Y311515D01*
G01X585023Y315003D02*
X585028Y313216D01*
G01X585019Y312948D02*
X585014Y314736D01*
G01X579942Y311066D02*
X579948Y309279D01*
G01X579938Y309011D02*
X579933Y310799D01*
G01X577149Y315003D02*
X577154Y313216D01*
G01X577145Y312948D02*
X577140Y314736D01*
G01X583824Y306102D02*
X583814Y306692D01*
G01X583796D02*
X583822Y305191D01*
G01X579887Y306102D02*
X579877Y306692D01*
G01X579859D02*
X579885Y305191D01*
G01X575950Y306102D02*
X575940Y306692D01*
G01X585055Y306032D02*
X585042Y306692D01*
G01X585022D02*
X585053Y305104D01*
G01X581118Y306032D02*
X581105Y306692D01*
G01X581085D02*
X581116Y305104D01*
G01X577181Y306032D02*
X577168Y306692D01*
G01X577148D02*
X577179Y305104D01*
G01X591201Y365315D02*
X589725D01*
G01X591201Y370843D02*
Y365315D01*
G01X589725D02*
Y377126D01*
G01D02*
X591201D01*
G01Y372351D02*
X598091D01*
G01Y370843D02*
X591201D01*
G01Y377126D02*
Y372351D01*
G01X580118Y1001574D02*
X577363D01*
G01X584055D02*
X581300D01*
G01X587992D02*
X585237D01*
G01X591929D02*
X589174D01*
G01X591929Y1018110D02*
Y1001574D01*
G01X589174D02*
Y1018110D01*
G01X587992D02*
Y1001574D01*
G01X585237D02*
Y1018110D01*
G01X584055D02*
Y1001574D01*
G01X581300D02*
Y1018110D01*
G01X580118D02*
Y1001574D01*
G01X577363D02*
Y1018110D01*
G01X576181D02*
Y1001574D01*
G01X589174Y1018110D02*
X591929D01*
G01X581300D02*
X584055D01*
G01X585237D02*
X587992D01*
G01X577363D02*
X580118D01*
G01X591496Y1031063D02*
X593898D01*
G01X593998Y1030450D02*
X592097D01*
G01Y1029019D02*
X593998D01*
G01X592097Y1028405D02*
X593998D01*
G01Y1026872D02*
X592097D01*
G01X593898Y1026259D02*
X591496D01*
G01X592097Y1026872D02*
Y1028405D01*
G01Y1030450D02*
Y1029019D01*
G01X591496Y1026259D02*
Y1031063D01*
G01X606704Y2543D02*
X606713Y2403D01*
G01X605138D02*
X605129Y2543D01*
G01X606713Y2478D02*
X606704Y2543D01*
G01X605129D02*
X605138Y2478D01*
G01X596506Y-3504D02*
Y-3573D01*
G01X602805Y2401D02*
G03Y826I0J-788D01*
G01X595650Y-4095D02*
G03X595335Y-4725I472J-630D01*
G01X593268Y-7087D02*
G03X592481Y-6300I-787J0D01*
G01X593875Y-7087D02*
G03X594650Y-6436I0J787D01*
G01X602215Y-748D02*
G03X599065I-1575J0D01*
G01X593875Y-7874D02*
G03X595425Y-6573I-1J1574D01*
G01X596255Y2665D02*
G03X596077Y4694I-3877J682D01*
G01X597030Y2527D02*
G03X596817Y4964I-4652J821D01*
G01X596128Y6858D02*
X595388Y6589D01*
G01X607540Y-5670D02*
X606162Y-7048D01*
G01X598731Y-6654D02*
X598337Y-7048D01*
G01X596506Y-6654D02*
X596113Y-7048D01*
G01X596319Y-6260D02*
X595532Y-7048D01*
G01X594449Y-6260D02*
X593662Y-7048D01*
G01X595425Y-6573D02*
X597030Y2527D01*
G01X596255Y2665D02*
X594650Y-6436D01*
G01X608721Y-2520D02*
Y17559D01*
G01X607540Y36653D02*
Y-5670D01*
G01X607067Y-2520D02*
Y17559D01*
G01X606949Y-7087D02*
Y-7874D01*
G01X606713Y-16D02*
Y28485D01*
G01X606162Y-7087D02*
Y-7874D01*
G01X605374Y-7087D02*
Y-7874D01*
G01X605138Y-16D02*
Y28485D01*
G01X604705Y-2520D02*
Y17559D01*
G01X603898Y-7048D02*
Y14606D01*
G01X603790Y6170D02*
Y9213D01*
G01Y-6733D02*
Y-7048D01*
G01X603711Y16574D02*
Y-6654D01*
G01X602215Y-748D02*
Y-7048D01*
G01X601821Y15787D02*
Y6141D01*
G01X601487Y-355D02*
Y-6654D01*
G01X599065Y-5934D02*
Y6564D01*
G01X598731Y-6654D02*
Y14606D01*
G01X596506Y-6654D02*
Y16574D01*
G01X596319Y-6260D02*
Y36653D01*
G01X596122Y-7087D02*
Y-7874D01*
G01X595335D02*
Y-4095D01*
G01X594548Y-7087D02*
Y-7874D01*
G01X594449Y10511D02*
Y-6260D01*
G01X593875Y-7087D02*
Y-7874D01*
G01X593481Y-7087D02*
Y-7874D01*
G01X593268Y-7087D02*
Y-7874D01*
G01X593170Y-2227D02*
Y-7048D01*
G01Y12637D02*
Y3713D01*
G01X592874D02*
Y25433D01*
G01Y-2227D02*
Y-6949D01*
G01X592609Y6338D02*
Y25629D01*
G01X592481Y-7470D02*
Y-7874D01*
G01X606220Y8155D02*
X606704Y2543D01*
G01X604705Y7466D02*
X605129Y2543D01*
G01X596817Y4964D02*
X595859Y7598D01*
G01X595118Y7329D02*
X596077Y4694D01*
G01X604105Y-7048D02*
X603711Y-6654D01*
G01X601487D02*
X601880Y-7048D01*
G01X603790Y6564D02*
X599065D01*
G01Y6170D02*
X603790D01*
G01X603711Y6141D02*
X601821D01*
G01X606713Y4983D02*
X605138D01*
G01X606713Y4489D02*
X605138D01*
G01Y4277D02*
X606713D01*
G01X605129Y2543D02*
X606713D01*
G01X603711Y2401D02*
X602805D01*
G01X605138Y2338D02*
X606713D01*
G01X605138Y1362D02*
X606713D01*
G01X603711Y826D02*
X602805D01*
G01X611969Y39D02*
X607540D01*
G01X605138Y-16D02*
X606713D01*
G01X604705Y-158D02*
X607067D01*
G01X608721D02*
X611083D01*
G01X601487Y-355D02*
X598731D01*
G01X601487Y-748D02*
X598731D01*
G01X607067Y-2520D02*
X604705D01*
G01X611083D02*
X608721D01*
G01X598731Y-3504D02*
X596506D01*
G01Y-3577D02*
X598731D01*
G01X596506Y-4162D02*
X599065D01*
G01X596506Y-4489D02*
X598731D01*
G01X599065Y-4654D02*
X596506D01*
G01Y-4685D02*
X598731D01*
G01X599065Y-5048D02*
X596506D01*
G01X599065Y-5146D02*
X596506D01*
G01X603898Y-5670D02*
X611969D01*
G01X599065Y-5934D02*
X596506D01*
G01X593170Y-6260D02*
X646713D01*
G01X596506Y-6654D02*
X603711D01*
G01X644548Y-6693D02*
X595335D01*
G01X608764Y8946D02*
X608791Y8361D01*
G01X606207D02*
X606220Y8155D01*
G01X605729Y13620D02*
G03X605779Y12829I246316J15173D01*
G01X604154Y13620D02*
G03X604205Y12829I250787J15772D01*
G01X608448Y13620D02*
G03X608484Y12829I348828J15480D01*
G01X605729Y13620D02*
G03X605779Y13255I48043J6395D01*
G01X597294Y16574D02*
G03X596506Y15787I-1J-787D01*
G01X601821D02*
G03X601034Y16574I-787J0D01*
G01X606220Y8155D02*
G03X606170Y8520I-51413J-6857D01*
G01X608800Y8155D02*
G03X608764Y8520I-77768J-7486D01*
G01X606207Y8361D02*
G03X606170Y8946I-260575J-16187D01*
G01X595859Y7598D02*
X595118Y7329D01*
G01X608764Y8946D02*
Y8520D01*
G01X608484Y13236D02*
Y12829D01*
G01X606170Y8520D02*
Y8946D01*
G01X605779Y12829D02*
Y13255D01*
G01X604205Y13236D02*
Y12829D01*
G01X595040Y12637D02*
Y25629D01*
G01X594252D02*
Y12637D01*
G01X594085Y25334D02*
Y12933D01*
G01X594055Y39874D02*
Y11850D01*
G01X593760Y39409D02*
Y11259D01*
G01X608600D02*
X608484Y13236D01*
G01X608164Y11850D02*
X606403Y40984D01*
G01X606009D02*
X607770Y11850D01*
G01X606664Y42460D02*
X608448Y13620D01*
G01X608721Y9614D02*
X608764Y8946D01*
G01X608721Y9188D02*
X608764Y8520D01*
G01X608484Y12829D02*
X608586Y11259D01*
G01X604366D02*
X604205Y13236D01*
G01X606683Y11850D02*
X604217Y40984D01*
G01X603822D02*
X606288Y11850D01*
G01X601460Y40984D02*
X603925Y11850D01*
G01X603530D02*
X601065Y40984D01*
G01X603244Y42460D02*
X605729Y13620D01*
G01X601669Y42460D02*
X604154Y13620D01*
G01X606170Y8946D02*
X605779Y13255D01*
G01X606170Y8520D02*
X605779Y12829D01*
G01X604205D02*
X604347Y11259D01*
G01X607067Y17559D02*
X604705D01*
G01X611083D02*
X608721D01*
G01X603711Y16574D02*
X596506D01*
G01X603898Y14606D02*
X596319D01*
G01X608448Y13620D02*
X610023D01*
G01X604154D02*
X605729D01*
G01X610059Y13255D02*
X608721D01*
G01X605779D02*
X604705D01*
G01X605779Y12829D02*
X604205D01*
G01X610059D02*
X608484D01*
G01X592609Y12637D02*
X595040D01*
G01X632343Y12047D02*
X607540D01*
G01X645827Y11850D02*
X594055D01*
G01X604705Y11259D02*
X593760D01*
G01X608721D02*
X607067D01*
G01X596319Y10511D02*
X594449D01*
G01X603790Y9213D02*
X596506D01*
G01X610339Y8946D02*
X608764D01*
G01X606170D02*
X604705D01*
G01X596506Y8819D02*
X603790D01*
G01X610339Y8520D02*
X608764D01*
G01X606170D02*
X604705D01*
G01Y8361D02*
X606207D01*
G01X604705Y8155D02*
X606220D01*
G01X598495Y40048D02*
G03X603395I2450J4085D01*
G01X607323Y44133D02*
G03I-6378J0D01*
G01X607481D02*
X600945Y37598D01*
G01X605335Y28359D02*
X605138Y27991D01*
G01X605335Y28853D02*
X605138Y28485D01*
G01X605532Y36261D02*
X605335Y35526D01*
G01X605532Y36755D02*
X605335Y36020D01*
G01X608721Y39409D02*
Y32716D01*
G01X608622Y39409D02*
Y45979D01*
G01X607067Y39409D02*
Y32716D01*
G01X606516Y28359D02*
Y36020D01*
G01X606319Y36755D02*
Y36261D01*
G01X605532Y36755D02*
Y36261D01*
G01X605335Y36020D02*
Y28359D01*
G01X604705Y39409D02*
Y32716D01*
G01X603622Y39409D02*
Y44921D01*
G01X602225Y28779D02*
Y32716D01*
G01X596706Y39874D02*
Y45321D01*
G01X593170Y26614D02*
Y25629D01*
G01X592609Y26614D02*
Y31929D01*
G01X592481Y39409D02*
Y39874D01*
G01X608239Y42460D02*
X610023Y13620D01*
G01X606516Y36020D02*
X606319Y36755D01*
G01X606516Y35526D02*
X606319Y36261D01*
G01X606713Y28485D02*
X606516Y28853D01*
G01X606713Y27991D02*
X606516Y28359D01*
G01X594410Y44133D02*
X600945Y37598D01*
G01X605532Y36755D02*
X606319D01*
G01X596319Y36653D02*
X643563D01*
G01X606319Y36261D02*
X605532D01*
G01X604705Y35984D02*
X593760D01*
G01X608721D02*
X607067D01*
G01X643563Y32716D02*
X596319D01*
G01X602225Y31732D02*
X596319D01*
G01X602225Y28779D02*
X596319D01*
G01X607540Y26811D02*
X596319D01*
G01X592609Y25629D02*
X647274D01*
G01X606654Y42703D02*
X606664Y42460D01*
G01X608239D02*
X608229Y42703D01*
G01X606654Y42561D02*
X606664Y42460D01*
G01X608239D02*
X608229Y42561D01*
G01X601654D02*
X601669Y42460D01*
G01X603244D02*
X603229Y42561D01*
G01X601654Y42703D02*
X601669Y42460D01*
G01X603244D02*
X603229Y42703D01*
G01X596860Y46583D02*
G03Y41683I4085J-2450D01*
G01X603395Y48219D02*
G03X598495I-2450J-4086D01*
G01X605031Y41683D02*
G03Y46583I-4086J2450D01*
G01X600945Y50669D02*
X594410Y44133D01*
G01X603780Y44921D02*
X604409Y45708D01*
G01X608675Y44601D02*
Y45979D01*
G01X608648D02*
Y44601D01*
G01X608229Y44822D02*
Y42561D01*
G01X607835Y43444D02*
Y44822D01*
G01X607638Y45979D02*
Y44601D01*
G01X607613D02*
Y45979D01*
G01X607585D02*
Y44601D01*
G01X607441Y44822D02*
Y56397D01*
G01X607369Y44601D02*
Y45979D01*
G01X607343D02*
Y44601D01*
G01X607297Y45979D02*
Y44601D01*
G01X607244Y45979D02*
Y44601D01*
G01X607048Y44822D02*
Y43444D01*
G01X606654Y45979D02*
Y42561D01*
G01X606260Y44921D02*
Y40984D01*
G01X606103Y44921D02*
Y43346D01*
G01X605474D02*
Y45708D01*
G01X605473Y42165D02*
Y43346D01*
G01X604882Y44822D02*
Y45979D01*
G01X604410Y43346D02*
Y42165D01*
G01X604409Y45708D02*
Y43346D01*
G01X604292Y45979D02*
Y44601D01*
G01X604239D02*
Y45979D01*
G01X604193D02*
Y44601D01*
G01X604168Y45979D02*
Y44601D01*
G01X604095Y44822D02*
Y56397D01*
G01X603951Y44601D02*
Y45979D01*
G01X603924D02*
Y44601D01*
G01X603898Y45979D02*
Y44601D01*
G01X603780Y43346D02*
Y44921D01*
G01X603229Y44822D02*
Y42561D01*
G01X602914Y45979D02*
Y44601D01*
G01X602888D02*
Y45979D01*
G01X602861D02*
Y44601D01*
G01X602835Y43444D02*
Y44822D01*
G01X602717D02*
Y56397D01*
G01X602644Y44601D02*
Y45979D01*
G01X602618D02*
Y44601D01*
G01X602573Y45979D02*
Y44601D01*
G01X602520Y45979D02*
Y44601D01*
G01X602048Y44822D02*
Y43444D01*
G01X601929Y45979D02*
Y44822D01*
G01X601654D02*
Y42561D01*
G01X601260Y44921D02*
Y40984D01*
G01X601103Y44921D02*
Y43346D01*
G01X600474D02*
Y45708D01*
G01X600473Y42165D02*
Y43346D01*
G01X600453Y40984D02*
Y42165D01*
G01X600158Y44822D02*
Y45979D01*
G01X599981Y44822D02*
Y43444D01*
G01X599567Y45979D02*
Y44601D01*
G01X599514D02*
Y45979D01*
G01X599469Y46102D02*
Y42165D01*
G01X599443Y45979D02*
Y44601D01*
G01X599370D02*
Y56397D01*
G01X599226Y44601D02*
Y45979D01*
G01X599200D02*
Y44601D01*
G01X599174Y45979D02*
Y44601D01*
G01X598189Y45979D02*
Y44601D01*
G01X598164D02*
Y45979D01*
G01X598137D02*
Y44601D01*
G01X597992D02*
Y56397D01*
G01X597920Y44601D02*
Y45979D01*
G01X597894D02*
Y44601D01*
G01X597848Y45979D02*
Y44601D01*
G01X597796Y45979D02*
Y44601D01*
G01X597205Y45979D02*
Y44601D01*
G01X595433Y45321D02*
Y45979D01*
G01X594843D02*
Y45321D01*
G01X594790D02*
Y45979D01*
G01X594744D02*
Y45321D01*
G01X594719Y45979D02*
Y45321D01*
G01X594646D02*
Y56397D01*
G01X594502Y45321D02*
Y45979D01*
G01X594475D02*
Y45321D01*
G01X594449Y45979D02*
Y45321D01*
G01X593465Y45979D02*
Y45321D01*
G01X593439D02*
Y45979D01*
G01X593412D02*
Y45321D01*
G01X593268D02*
Y56397D01*
G01X593196Y45321D02*
Y45979D01*
G01X593170D02*
Y45321D01*
G01X593124Y45979D02*
Y45321D01*
G01X593071Y45979D02*
Y45321D01*
G01X592776Y48070D02*
Y45321D01*
G01X592481D02*
Y85472D01*
G01X608765Y40984D02*
X610526Y11850D01*
G01X605474Y45708D02*
X606103Y44921D01*
G01X600474Y45708D02*
X601103Y44921D01*
G01X600945Y50669D02*
X607481Y44133D01*
G01X594646Y56397D02*
X593268D01*
G01X599370D02*
X597992D01*
G01X604095D02*
X602717D01*
G01X608819D02*
X607441D01*
G01X594646Y55019D02*
X593268D01*
G01X599370D02*
X597992D01*
G01X604095D02*
X602717D01*
G01X608819D02*
X607441D01*
G01X594646Y54035D02*
X593268D01*
G01X599370D02*
X597992D01*
G01X604095D02*
X602717D01*
G01X608819D02*
X607441D01*
G01X594646Y46963D02*
X593268D01*
G01X599370D02*
X597992D01*
G01X604095D02*
X602717D01*
G01X608819D02*
X607441D01*
G01X595433Y45979D02*
X592481D01*
G01X600158D02*
X597205D01*
G01X604882D02*
X601929D01*
G01X609607D02*
X606654D01*
G01X605474Y45708D02*
X609409D01*
G01X600474D02*
X604409D01*
G01X606103Y44921D02*
X608780D01*
G01X601103D02*
X603780D01*
G01X639981Y44822D02*
X599981D01*
G01X597205Y44601D02*
X599981D01*
G01X604292D02*
X602520D01*
G01X609016D02*
X607244D01*
G01X639981Y43444D02*
X599981D01*
G01X604404Y43346D02*
X600479D01*
G01X609404D02*
X605479D01*
G01X606664Y42460D02*
X608239D01*
G01X601669D02*
X603244D01*
G01X640414Y42165D02*
X599469D01*
G01X606403Y40984D02*
X603822D01*
G01X601460D02*
X600453D01*
G01X611346D02*
X608765D01*
G01X643563Y40196D02*
X596706D01*
G01X609134Y70118D02*
G03I-1181J0D01*
G01X601142D02*
G03I-1181J0D01*
G01X610106D02*
G03I-2153J0D01*
G01X602114D02*
G03I-2153J0D01*
G01X607048Y69429D02*
Y78803D01*
G01X600827D02*
Y69429D01*
G01X599055D02*
Y78803D01*
G01X594351Y78693D02*
Y67362D01*
G01X592776Y84685D02*
Y67362D01*
G01X607048Y71791D02*
X608819D01*
G01X599055D02*
X600827D01*
G01Y70807D02*
X599055D01*
G01X608819D02*
X607048D01*
G01X600827Y69429D02*
X599055D01*
G01X608819D02*
X607048D01*
G01X647402Y67165D02*
X592481D01*
G01X593344Y85995D02*
G03X594351Y85433I1006J619D01*
G01X605138Y80118D02*
G03I-1181J0D01*
G01X597146D02*
G03I-1181J0D01*
G01X606110D02*
G03I-2153J0D01*
G01X594351Y78693D02*
G03Y81542I1614J1424D01*
G01X604710Y81086D02*
X604484Y80898D01*
G01X604710Y82215D02*
X604484Y82027D01*
G01X596718Y81086D02*
X596492Y80898D01*
G01X596718Y82215D02*
X596492Y82027D01*
G01X608721Y78803D02*
Y77426D01*
G01X608425Y78803D02*
Y77426D01*
G01X607441Y78803D02*
Y77426D01*
G01X607146D02*
Y78803D01*
G01X606752Y77426D02*
Y78803D01*
G01X606260Y77426D02*
Y78803D01*
G01X605630Y79429D02*
Y80807D01*
G01X605138D02*
Y79429D01*
G01X604843Y80807D02*
Y79429D01*
G01X604744Y82346D02*
Y81150D01*
G01X604710Y82215D02*
Y81086D01*
G01X604646Y79429D02*
Y80807D01*
G01X604548Y81331D02*
Y82459D01*
G01X604484Y82027D02*
Y80898D01*
G01X604449Y81963D02*
Y79429D01*
G01X603465D02*
Y81963D01*
G01X603430Y80898D02*
Y82027D01*
G01X603366Y82459D02*
Y81331D01*
G01X603268Y80807D02*
Y79429D01*
G01X603204Y81086D02*
Y82215D01*
G01X603170Y82346D02*
Y81150D01*
G01X603071Y80807D02*
Y79429D01*
G01X602776Y80807D02*
Y79429D01*
G01X602284Y80807D02*
Y79429D01*
G01X601614Y78803D02*
Y77426D01*
G01X601122Y78803D02*
Y77426D01*
G01X600729Y78803D02*
Y77426D01*
G01X600433Y78803D02*
Y77426D01*
G01X599449Y78803D02*
Y77426D01*
G01X599154D02*
Y78803D01*
G01X598760Y77426D02*
Y78803D01*
G01X598268Y77426D02*
Y78803D01*
G01X597638Y79429D02*
Y80807D01*
G01X597146D02*
Y79429D01*
G01X596851Y80807D02*
Y79429D01*
G01X596752Y82346D02*
Y81150D01*
G01X596718Y82215D02*
Y81086D01*
G01X596654Y79429D02*
Y80807D01*
G01X596555Y81331D02*
Y82459D01*
G01X596492Y82027D02*
Y80898D01*
G01X596457Y81963D02*
Y79429D01*
G01X595473D02*
Y81963D01*
G01X595438Y80898D02*
Y82027D01*
G01X595374Y82459D02*
Y81331D01*
G01X595276Y80807D02*
Y79429D01*
G01X595212Y81086D02*
Y82215D01*
G01X595177Y82346D02*
Y81150D01*
G01X595079Y80807D02*
Y79429D01*
G01X594784Y80807D02*
Y79429D01*
G01X594351Y86389D02*
Y87176D01*
G01Y84685D02*
Y81542D01*
G01X594292Y80807D02*
Y79429D01*
G01X593344Y86389D02*
Y87176D01*
G01X593218Y86831D02*
Y86274D01*
G01X603430Y82027D02*
X603204Y82215D01*
G01X603430Y80898D02*
X603204Y81086D01*
G01X595438Y82027D02*
X595212Y82215D01*
G01X595438Y80898D02*
X595212Y81086D01*
G01X614823Y85433D02*
X594351D01*
G01X603366Y82459D02*
X604548D01*
G01X595374D02*
X596555D01*
G01Y81331D02*
X595374D01*
G01X604548D02*
X603366D01*
G01X602284Y80807D02*
X605630D01*
G01X594292D02*
X597638D01*
G01X603465Y79678D02*
X604449D01*
G01X595473D02*
X596457D01*
G01X602284Y79429D02*
X605630D01*
G01X594292D02*
X597638D01*
G01X601614Y78803D02*
X598268D01*
G01X609607D02*
X606260D01*
G01X601614Y77426D02*
X598268D01*
G01X609607D02*
X606260D01*
G01X607048Y76441D02*
X608819D01*
G01X599055D02*
X600827D01*
G01X608664Y299606D02*
X608677Y300266D01*
G01X608675Y301194D02*
X608644Y299606D01*
G01X604727D02*
X604740Y300266D01*
G01X604738Y301194D02*
X604707Y299606D01*
G01X600790D02*
X600803Y300266D01*
G01X600801Y301194D02*
X600770Y299606D01*
G01X596853D02*
X596866Y300266D01*
G01X596864Y301194D02*
X596833Y299606D01*
G01X592916D02*
X592929Y300266D01*
G01X592927Y301194D02*
X592896Y299606D01*
G01X607436D02*
X607446Y300197D01*
G01X607444Y301107D02*
X607418Y299606D01*
G01X603499D02*
X603509Y300197D01*
G01X603507Y301107D02*
X603481Y299606D01*
G01X599562D02*
X599572Y300197D01*
G01X599570Y301107D02*
X599544Y299606D01*
G01X595625D02*
X595635Y300197D01*
G01X595633Y301107D02*
X595607Y299606D01*
G01X608650Y293082D02*
X608645Y291295D01*
G01X608636Y291563D02*
X608641Y293350D01*
G01X603570Y297019D02*
X603564Y295232D01*
G01X603555Y295500D02*
X603560Y297287D01*
G01X600776Y293082D02*
X600771Y291295D01*
G01X600762Y291563D02*
X600767Y293350D01*
G01X595696Y297019D02*
X595690Y295232D01*
G01X595681Y295500D02*
X595686Y297287D01*
G01X592902Y293082D02*
X592897Y291295D01*
G01X592888Y291563D02*
X592893Y293350D01*
G01X608660Y293799D02*
Y294783D01*
G01X608504Y290846D02*
Y289862D01*
G01X607638Y290846D02*
Y289862D01*
G01X607483Y294783D02*
Y293799D01*
G01X604723Y294783D02*
Y293799D01*
G01X604567Y298720D02*
Y297736D01*
G01X603701Y298720D02*
Y297736D01*
G01X603546Y293799D02*
Y294783D01*
G01X600786Y293799D02*
Y294783D01*
G01X600630Y290846D02*
Y289862D01*
G01X599764Y290846D02*
Y289862D01*
G01X599609Y294783D02*
Y293799D01*
G01X596849Y294783D02*
Y293799D01*
G01X596693Y298720D02*
Y297736D01*
G01X595827Y298720D02*
Y297736D01*
G01X595672Y293799D02*
Y294783D01*
G01X592912Y293799D02*
Y294783D01*
G01X592756Y290846D02*
Y289862D01*
G01X607501Y293350D02*
X607507Y291563D01*
G01X607497Y291295D02*
X607492Y293082D01*
G01X604708Y297287D02*
X604713Y295500D01*
G01X604704Y295232D02*
X604699Y297019D01*
G01X599627Y293350D02*
X599633Y291563D01*
G01X599623Y291295D02*
X599618Y293082D01*
G01X596834Y297287D02*
X596839Y295500D01*
G01X596830Y295232D02*
X596825Y297019D01*
G01X608724Y299606D02*
X608699Y301107D01*
G01X608696Y300197D02*
X608706Y299606D01*
G01X604787D02*
X604762Y301107D01*
G01X604759Y300197D02*
X604769Y299606D01*
G01X600850D02*
X600825Y301107D01*
G01X600822Y300197D02*
X600832Y299606D01*
G01X596913D02*
X596888Y301107D01*
G01X596885Y300197D02*
X596895Y299606D01*
G01X592976D02*
X592951Y301107D01*
G01X592948Y300197D02*
X592958Y299606D01*
G01X607498D02*
X607468Y301194D01*
G01X607465Y300266D02*
X607478Y299606D01*
G01X603561D02*
X603531Y301194D01*
G01X603528Y300266D02*
X603541Y299606D01*
G01X599624D02*
X599594Y301194D01*
G01X599591Y300266D02*
X599604Y299606D01*
G01X595687D02*
X595657Y301194D01*
G01X595654Y300266D02*
X595667Y299606D01*
G01X607456Y301477D02*
X608686D01*
G01X603519D02*
X604749D01*
G01X599582D02*
X600812D01*
G01X595645D02*
X596875D01*
G01X607468Y301194D02*
X608675D01*
G01X603531D02*
X604738D01*
G01X599594D02*
X600801D01*
G01X595657D02*
X596864D01*
G01X600825Y301107D02*
X599570D01*
G01X596888D02*
X595633D01*
G01X604762D02*
X603507D01*
G01X608699D02*
X607444D01*
G01X607456Y300492D02*
X608686D01*
G01X603519D02*
X604749D01*
G01X599582D02*
X600812D01*
G01X595645D02*
X596875D01*
G01X600803Y300266D02*
X599591D01*
G01X596866D02*
X595654D01*
G01X604740D02*
X603528D01*
G01X608677D02*
X607465D01*
G01X607446Y300197D02*
X608696D01*
G01X603509D02*
X604759D01*
G01X599572D02*
X600822D01*
G01X595635D02*
X596885D01*
G01X596816Y298720D02*
X595705D01*
G01X604690D02*
X603579D01*
G01Y297736D02*
X604690D01*
G01X595705D02*
X596816D01*
G01X603560Y297287D02*
X604708D01*
G01X595686D02*
X596834D01*
G01X596825Y297019D02*
X595696D01*
G01X604699D02*
X603570D01*
G01X596839Y295500D02*
X595681D01*
G01X604713D02*
X603555D01*
G01X603564Y295232D02*
X604704D01*
G01X595690D02*
X596830D01*
G01X607483Y294783D02*
X608660D01*
G01X603546D02*
X604723D01*
G01X599609D02*
X600786D01*
G01X595672D02*
X596849D01*
G01X600786Y293799D02*
X599609D01*
G01X596849D02*
X595672D01*
G01X604723D02*
X603546D01*
G01X608660D02*
X607483D01*
G01X600767Y293350D02*
X599627D01*
G01X608641D02*
X607501D01*
G01X607492Y293082D02*
X608650D01*
G01X599618D02*
X600776D01*
G01X607507Y291563D02*
X608636D01*
G01X599633D02*
X600762D01*
G01X600771Y291295D02*
X599623D01*
G01X608645D02*
X607497D01*
G01X600753Y290846D02*
X599642D01*
G01X608627D02*
X607516D01*
G01Y289862D02*
X608627D01*
G01X599642D02*
X600753D01*
G01Y316437D02*
X599642D01*
G01X608627D02*
X607516D01*
G01X600753Y315452D02*
X599642D01*
G01X608627D02*
X607516D01*
G01X607497Y315003D02*
X608645D01*
G01X599623D02*
X600771D01*
G01X600762Y314736D02*
X599633D01*
G01X608636D02*
X607507D01*
G01X600776Y313216D02*
X599618D01*
G01X608650D02*
X607492D01*
G01X607501Y312948D02*
X608641D01*
G01X599627D02*
X600767D01*
G01X600786Y312500D02*
X599609D01*
G01X596849D02*
X595672D01*
G01X604723D02*
X603546D01*
G01X608660D02*
X607483D01*
G01X600786Y311515D02*
X599609D01*
G01X596849D02*
X595672D01*
G01X604723D02*
X603546D01*
G01X608660D02*
X607483D01*
G01X596830Y311066D02*
X595690D01*
G01X604704D02*
X603564D01*
G01X603555Y310799D02*
X604713D01*
G01X595681D02*
X596839D01*
G01X607468Y305104D02*
X607498Y306692D01*
G01X607478D02*
X607465Y306032D01*
G01X603531Y305104D02*
X603561Y306692D01*
G01X603541D02*
X603528Y306032D01*
G01X599594Y305104D02*
X599624Y306692D01*
G01X599604D02*
X599591Y306032D01*
G01X595657Y305104D02*
X595687Y306692D01*
G01X595667D02*
X595654Y306032D01*
G01X608699Y305191D02*
X608724Y306692D01*
G01X608706D02*
X608696Y306102D01*
G01X604762Y305191D02*
X604787Y306692D01*
G01X604769D02*
X604759Y306102D01*
G01X600825Y305191D02*
X600850Y306692D01*
G01X600832D02*
X600822Y306102D01*
G01X596888Y305191D02*
X596913Y306692D01*
G01X596895D02*
X596885Y306102D01*
G01X592951Y305191D02*
X592976Y306692D01*
G01X592958D02*
X592948Y306102D01*
G01X607507Y314736D02*
X607501Y312948D01*
G01X607492Y313216D02*
X607497Y315003D01*
G01X604713Y310799D02*
X604708Y309011D01*
G01X604699Y309279D02*
X604704Y311066D01*
G01X599633Y314736D02*
X599627Y312948D01*
G01X599618Y313216D02*
X599623Y315003D01*
G01X596839Y310799D02*
X596834Y309011D01*
G01X596825Y309279D02*
X596830Y311066D01*
G01X608660Y311515D02*
Y312500D01*
G01X608504Y316437D02*
Y315452D01*
G01X607638D02*
Y316437D01*
G01X607483Y312500D02*
Y311515D01*
G01X604723Y312500D02*
Y311515D01*
G01X604567Y308563D02*
Y307578D01*
G01X603701D02*
Y308563D01*
G01X603546Y311515D02*
Y312500D01*
G01X600786Y311515D02*
Y312500D01*
G01X600630Y316437D02*
Y315452D01*
G01X599764D02*
Y316437D01*
G01X599609Y312500D02*
Y311515D01*
G01X596849D02*
Y312500D01*
G01X596693Y308563D02*
Y307578D01*
G01X596536Y323228D02*
Y317618D01*
G01X595827Y307578D02*
Y308563D01*
G01X595672Y312500D02*
Y311515D01*
G01X592912D02*
Y312500D01*
G01X592756Y316437D02*
Y315452D01*
G01X608645Y315003D02*
X608650Y313216D01*
G01X608641Y312948D02*
X608636Y314736D01*
G01X603564Y311066D02*
X603570Y309279D01*
G01X603560Y309011D02*
X603555Y310799D01*
G01X600771Y315003D02*
X600776Y313216D01*
G01X600767Y312948D02*
X600762Y314736D01*
G01X595690Y311066D02*
X595696Y309279D01*
G01X595686Y309011D02*
X595681Y310799D01*
G01X592897Y315003D02*
X592902Y313216D01*
G01X592893Y312948D02*
X592888Y314736D01*
G01X607446Y306102D02*
X607436Y306692D01*
G01X607418D02*
X607444Y305191D01*
G01X603509Y306102D02*
X603499Y306692D01*
G01X603481D02*
X603507Y305191D01*
G01X599572Y306102D02*
X599562Y306692D01*
G01X599544D02*
X599570Y305191D01*
G01X595635Y306102D02*
X595625Y306692D01*
G01X595607D02*
X595633Y305191D01*
G01X608677Y306032D02*
X608664Y306692D01*
G01X608644D02*
X608675Y305104D01*
G01X604740Y306032D02*
X604727Y306692D01*
G01X604707D02*
X604738Y305104D01*
G01X600803Y306032D02*
X600790Y306692D01*
G01X600770D02*
X600801Y305104D01*
G01X596866Y306032D02*
X596853Y306692D01*
G01X596833D02*
X596864Y305104D01*
G01X592929Y306032D02*
X592916Y306692D01*
G01X592896D02*
X592927Y305104D01*
G01X603570Y309279D02*
X604699D01*
G01X595696D02*
X596825D01*
G01X596834Y309011D02*
X595686D01*
G01X604708D02*
X603560D01*
G01X596816Y308563D02*
X595705D01*
G01X604690D02*
X603579D01*
G01X596816Y307578D02*
X595705D01*
G01X604690D02*
X603579D01*
G01X600822Y306102D02*
X599572D01*
G01X596885D02*
X595635D01*
G01X604759D02*
X603509D01*
G01X608696D02*
X607446D01*
G01X607465Y306032D02*
X608677D01*
G01X603528D02*
X604740D01*
G01X599591D02*
X600803D01*
G01X595654D02*
X596866D01*
G01X600812Y305806D02*
X599582D01*
G01X596875D02*
X595645D01*
G01X604749D02*
X603519D01*
G01X608686D02*
X607456D01*
G01X607444Y305191D02*
X608699D01*
G01X603507D02*
X604762D01*
G01X599570D02*
X600825D01*
G01X595633D02*
X596888D01*
G01X600801Y305104D02*
X599594D01*
G01X596864D02*
X595657D01*
G01X604738D02*
X603531D01*
G01X608675D02*
X607468D01*
G01X600812Y304822D02*
X599582D01*
G01X596875D02*
X595645D01*
G01X604749D02*
X603519D01*
G01X608686D02*
X607456D01*
G01X612441Y323228D02*
X596536D01*
G01X599567Y365315D02*
X598091D01*
G01X599567Y377126D02*
Y365315D01*
G01X598091D02*
Y370843D01*
G01Y377126D02*
X599567D01*
G01X601536Y373356D02*
X605473D01*
G01Y372351D02*
X601536D01*
G01X608918Y375115D02*
X607441Y373356D01*
G01Y375366D02*
X608918Y377126D01*
G01X601536Y370340D02*
X605473D01*
G01Y369335D02*
X601536D01*
G01X607441Y373356D02*
Y375366D01*
G01X605473Y370340D02*
Y369335D01*
G01Y373356D02*
Y372351D01*
G01X601536Y369335D02*
Y370340D01*
G01Y372351D02*
Y373356D01*
G01X598091Y372351D02*
Y377126D01*
G01X597047Y992126D02*
Y1018109D01*
G01X597048Y992126D02*
G03X600984Y988189I3937J0D01*
G01X713189D02*
X600984D01*
G01X597048Y992126D02*
G03X600985Y988189I3937J0D01*
G01X713189D02*
X600985D01*
G01X597048Y992126D02*
Y1021653D01*
G01X641198Y996063D02*
X604922D01*
G01D02*
Y1023622D01*
G01X641198Y996063D02*
X604922D01*
G01D02*
Y1023622D01*
G01X595866Y1001574D02*
X593111D01*
G01X595866Y1018110D02*
Y1001574D01*
G01X593111D02*
Y1018110D01*
G01X604922Y1023622D02*
X709253D01*
G01X604922D02*
X709253D01*
G01X597048Y1021653D02*
X597047Y1018109D01*
G01X597048Y1021653D02*
X595079Y1023622D01*
G01X593111Y1018110D02*
X595866D01*
G01X597048Y1021653D02*
X595079Y1023622D01*
G01X593898Y1031063D02*
X594398Y1030960D01*
G01X596600Y1031063D02*
X597200D01*
G01Y1026259D02*
X596600D01*
G01X594398Y1026362D02*
X593898Y1026259D01*
G01X594298Y1030347D02*
X593998Y1030450D01*
G01Y1028405D02*
X594298Y1028303D01*
G01X594598Y1028712D02*
X594799Y1028610D01*
G01X594398Y1030960D02*
X594799Y1030654D01*
G01X594498Y1030143D02*
X594298Y1030347D01*
G01Y1028303D02*
X594498Y1028099D01*
G01X594799Y1030654D02*
X595099Y1030245D01*
G01X594799Y1028610D02*
X595099Y1028201D01*
G01Y1030245D02*
X595199Y1029939D01*
G01X594598Y1029836D02*
X594498Y1030143D01*
G01X595099Y1028201D02*
X595199Y1027894D01*
G01X594498Y1028099D02*
X594598Y1027792D01*
G01X597200Y1031063D02*
Y1026259D01*
G01X596600D02*
Y1030245D01*
G01X596000Y1029529D02*
Y1030347D01*
G01X595199Y1027894D02*
Y1027383D01*
G01Y1029939D02*
Y1029529D01*
G01X594598Y1029632D02*
Y1029836D01*
G01Y1027792D02*
Y1027486D01*
G01X595199Y1027383D02*
X595099Y1027077D01*
G01X594598Y1027486D02*
X594498Y1027179D01*
G01X595199Y1029529D02*
X595099Y1029223D01*
G01X594498Y1029325D02*
X594598Y1029632D01*
G01X596600Y1030245D02*
X596000Y1029529D01*
G01Y1030347D02*
X596600Y1031063D01*
G01X595099Y1027077D02*
X594799Y1026668D01*
G01X595099Y1029223D02*
X594799Y1028814D01*
G01Y1026668D02*
X594398Y1026362D01*
G01X594498Y1027179D02*
X594298Y1026975D01*
G01Y1029121D02*
X594498Y1029325D01*
G01X594298Y1026975D02*
X593998Y1026872D01*
G01Y1029019D02*
X594298Y1029121D01*
G01X594799Y1028814D02*
X594598Y1028712D01*
G01X621201Y2403D02*
X621202Y2543D01*
G01X622776Y2478D02*
X622777Y2543D01*
G01X621202D02*
X621201Y2478D01*
G01X622777Y2543D02*
X622776Y2403D01*
G01X617185D02*
X617184Y2543D01*
G01X618760Y2478D02*
X618759Y2543D01*
G01X617184D02*
X617185Y2478D01*
G01X618759Y2543D02*
X618760Y2403D01*
G01X613170D02*
X613166Y2543D01*
G01X614744Y2478D02*
X614740Y2543D01*
G01X613166D02*
X613170Y2478D01*
G01X614740Y2543D02*
X614744Y2403D01*
G01X609154D02*
X609148Y2543D01*
G01X610729Y2478D02*
X610722Y2543D01*
G01X609148D02*
X609154Y2478D01*
G01X610722Y2543D02*
X610729Y2403D01*
G01X610886Y-5906D02*
G03X610099Y-6693I0J-787D01*
G01X622840Y8155D02*
X622777Y2543D01*
G01X621265Y8155D02*
X621202Y2543D01*
G01X610475Y5394D02*
Y6667D01*
G01X624784Y-2520D02*
Y17559D01*
G01X623130Y-2520D02*
Y17559D01*
G01X622776Y28485D02*
Y-16D01*
G01X621201D02*
Y28485D01*
G01X620768Y-2520D02*
Y17559D01*
G01X619114Y-2520D02*
Y17559D01*
G01X618760Y28485D02*
Y-16D01*
G01X617185D02*
Y28485D01*
G01X616752Y-2520D02*
Y17559D01*
G01X615099Y-2520D02*
Y17559D01*
G01X614744Y28485D02*
Y-16D01*
G01X613170D02*
Y28485D01*
G01X612737Y-2520D02*
Y17559D01*
G01X611969Y-7048D02*
Y39D01*
G01X611083Y-2520D02*
Y17559D01*
G01X610729Y-16D02*
Y28485D01*
G01X610099Y-6693D02*
Y-7874D01*
G01X609311Y-7087D02*
Y-7874D01*
G01X609154Y-16D02*
Y28485D01*
G01X618685Y8155D02*
X618759Y2543D01*
G01X617110Y8155D02*
X617184Y2543D01*
G01X614530Y8155D02*
X614740Y2543D01*
G01X612955Y8155D02*
X613166Y2543D01*
G01X610375Y8155D02*
X610722Y2543D01*
G01X608801Y8155D02*
X609148Y2543D01*
G01X614744Y4983D02*
X613170D01*
G01X610729D02*
X609154D01*
G01X618760D02*
X617185D01*
G01X622776D02*
X621201D01*
G01X614744Y4489D02*
X613170D01*
G01X610729D02*
X609154D01*
G01X618760D02*
X617185D01*
G01X622776D02*
X621201D01*
G01Y4277D02*
X622776D01*
G01X617185D02*
X618760D01*
G01X613170D02*
X614744D01*
G01X609154D02*
X610729D01*
G01X621201Y2543D02*
X622777D01*
G01X617184D02*
X618760D01*
G01X613166D02*
X614744D01*
G01X609148D02*
X610729D01*
G01X621201Y2338D02*
X622776D01*
G01X617185D02*
X618760D01*
G01X613170D02*
X614744D01*
G01X609154D02*
X610729D01*
G01X621201Y1362D02*
X622776D01*
G01X617185D02*
X618760D01*
G01X613170D02*
X614744D01*
G01X609154D02*
X610729D01*
G01X621201Y-16D02*
X622776D01*
G01X617185D02*
X618760D01*
G01X613170D02*
X614744D01*
G01X609154D02*
X610729D01*
G01X624784Y-158D02*
X627146D01*
G01X620768D02*
X623130D01*
G01X616752D02*
X619114D01*
G01X612737D02*
X615099D01*
G01Y-2520D02*
X612737D01*
G01X619114D02*
X616752D01*
G01X623130D02*
X620768D01*
G01X627146D02*
X624784D01*
G01X628996Y-5906D02*
X610886D01*
G01X621265Y8155D02*
X621267Y8361D01*
G01X621272Y8946D02*
X621267Y8361D01*
G01X622842D02*
X622846Y8946D01*
G01X622904Y13620D02*
X622897Y13255D01*
G01X621322D02*
X621329Y13620D01*
G01X621322Y12829D02*
X621329Y13620D01*
G01X622904D02*
X622897Y12829D01*
G01X621272Y8520D02*
X621265Y8155D01*
G01X622840D02*
X622846Y8520D01*
G01X622842Y8361D02*
X622840Y8155D01*
G01X617110D02*
X617108Y8361D01*
G01X617103Y8946D02*
X617108Y8361D01*
G01X618683D02*
X618677Y8946D01*
G01X618610Y13620D02*
X618618Y13255D01*
G01X617043D02*
X617035Y13620D01*
G01X617043Y12829D02*
X617035Y13620D01*
G01X618610D02*
X618618Y12829D01*
G01X617103Y8520D02*
X617110Y8155D01*
G01X618685D02*
X618677Y8520D01*
G01X618683Y8361D02*
X618685Y8155D01*
G01X612955D02*
X612950Y8361D01*
G01X612933Y8946D02*
X612950Y8361D01*
G01X614525D02*
X614508Y8946D01*
G01X612764Y12829D02*
X612742Y13620D01*
G01X614316D02*
X614338Y12829D01*
G01X614525Y8361D02*
X614530Y8155D01*
G01X608801D02*
X608791Y8361D01*
G01X610366D02*
X610339Y8946D01*
G01X610366Y8361D02*
X610375Y8155D01*
G01X614316Y13620D02*
G03X614338Y13255I108661J6366D01*
G01X612742Y13620D02*
G03X612763Y13255I137902J7751D01*
G01X610023Y13620D02*
G03X610059Y12829I342609J15196D01*
G01X610022Y13620D02*
G03X610059Y13255I66296J6536D01*
G01X610375Y8155D02*
G03X610339Y8520I-70966J-6815D01*
G01X614530Y8155D02*
G03X614508Y8520I-116288J-6826D01*
G01X612955Y8155D02*
G03X612934Y8520I-127468J-7151D01*
G01X626174Y40984D02*
X625118Y11850D01*
G01X624724D02*
X625781Y40984D01*
G01X623988D02*
X623635Y11850D01*
G01X623594Y40984D02*
X623242Y11850D01*
G01X621232Y40984D02*
X620879Y11850D01*
G01X620838Y40984D02*
X620486Y11850D01*
G01X622846Y8520D02*
X622897Y12829D01*
G01X622846Y8946D02*
X622897Y13255D01*
G01X621322Y12829D02*
X621272Y8520D01*
G01X621322Y13255D02*
X621272Y8946D01*
G01X623227Y42460D02*
X622904Y13620D01*
G01X621652Y42460D02*
X621329Y13620D01*
G01X610242Y10688D02*
Y10320D01*
G01X622897Y12829D02*
Y13255D01*
G01X622846Y8520D02*
Y8946D01*
G01X621322Y13255D02*
Y12829D01*
G01X621272Y8946D02*
Y8520D01*
G01X618677D02*
Y8946D01*
G01X618618Y12829D02*
Y13255D01*
G01X617103Y8946D02*
Y8520D01*
G01X617043Y13255D02*
Y12829D01*
G01X614508Y8520D02*
Y8946D01*
G01X614338Y12829D02*
Y13255D01*
G01X612933Y8946D02*
Y8520D01*
G01X612764Y13255D02*
Y12829D01*
G01X610339Y8520D02*
Y8946D01*
G01X610059Y12829D02*
Y13255D01*
G01X619045Y40984D02*
X619397Y11850D01*
G01X618651Y40984D02*
X619003Y11850D01*
G01X616641D02*
X616289Y40984D01*
G01X615895D02*
X616247Y11850D01*
G01X618231Y42460D02*
X618610Y13620D01*
G01X616656Y42460D02*
X617035Y13620D01*
G01X618677Y8946D02*
X618618Y13255D01*
G01X618677Y8520D02*
X618618Y12829D01*
G01X617043Y13255D02*
X617103Y8946D01*
G01X617043Y12829D02*
X617103Y8520D01*
G01X615159Y11850D02*
X614102Y40984D01*
G01X613708D02*
X614764Y11850D01*
G01X612402D02*
X611346Y40984D01*
G01X610952D02*
X612009Y11850D01*
G01X613235Y42460D02*
X614316Y13620D01*
G01X611661Y42460D02*
X612742Y13620D01*
G01X614508Y8946D02*
X614338Y13255D01*
G01X614508Y8520D02*
X614338Y12829D01*
G01X612764Y13255D02*
X612933Y8946D01*
G01X612764Y12829D02*
X612933Y8520D01*
G01X610342Y8155D02*
X610340Y8184D01*
G01X610921Y11850D02*
X609160Y40984D01*
G01X610339Y8946D02*
X610059Y13255D01*
G01X610339Y8520D02*
X610059Y12829D01*
G01X615099Y17559D02*
X612737D01*
G01X619114D02*
X616752D01*
G01X623130D02*
X620768D01*
G01X627146D02*
X624784D01*
G01X621329Y13620D02*
X622904D01*
G01X617035D02*
X618610D01*
G01X612742D02*
X614316D01*
G01X614338Y13255D02*
X612764D01*
G01X618618D02*
X617043D01*
G01X622897D02*
X621322D01*
G01X614338Y12829D02*
X612764D01*
G01X618618D02*
X617043D01*
G01X622897D02*
X621322D01*
G01X612737Y11259D02*
X611083D01*
G01X616752D02*
X615099D01*
G01X620768D02*
X619114D01*
G01X624784D02*
X623130D01*
G01X614508Y8946D02*
X612933D01*
G01X618677D02*
X617103D01*
G01X622846D02*
X621272D01*
G01X614508Y8520D02*
X612933D01*
G01X618677D02*
X617103D01*
G01X622846D02*
X621272D01*
G01X621267Y8361D02*
X622842D01*
G01X617108D02*
X618683D01*
G01X612950D02*
X614525D01*
G01X608791D02*
X610366D01*
G01X621265Y8155D02*
X622840D01*
G01X617110D02*
X618685D01*
G01X612955D02*
X614530D01*
G01X608801D02*
X610375D01*
G01X621398Y28359D02*
X621201Y27991D01*
G01X621398Y28853D02*
X621201Y28485D01*
G01X617382Y28359D02*
X617185Y27991D01*
G01X617382Y28853D02*
X617185Y28485D01*
G01X613366Y28359D02*
X613170Y27991D01*
G01X613366Y28853D02*
X613170Y28485D01*
G01X609351Y28359D02*
X609154Y27991D01*
G01X609351Y28853D02*
X609154Y28485D01*
G01X621595Y36261D02*
X621398Y35526D01*
G01X621595Y36755D02*
X621398Y36020D01*
G01X617579Y36261D02*
X617382Y35526D01*
G01X617579Y36755D02*
X617382Y36020D01*
G01X613563Y36261D02*
X613366Y35526D01*
G01X613563Y36755D02*
X613366Y36020D01*
G01X609548Y36261D02*
X609351Y35526D01*
G01X609548Y36755D02*
X609351Y36020D01*
G01X624784Y39409D02*
Y32716D01*
G01X623130Y39409D02*
Y32716D01*
G01X622579Y28359D02*
Y36020D01*
G01X622382Y36755D02*
Y36261D01*
G01X621595Y36755D02*
Y36261D01*
G01X621398Y36020D02*
Y28359D01*
G01X621260Y44921D02*
Y39409D01*
G01X620768D02*
Y32716D01*
G01X619114Y39409D02*
Y32716D01*
G01X618622Y39409D02*
Y44921D01*
G01X618563Y28359D02*
Y36020D01*
G01X618366Y36755D02*
Y36261D01*
G01X617579Y36755D02*
Y36261D01*
G01X617382Y36020D02*
Y28359D01*
G01X616752Y39409D02*
Y32716D01*
G01X615099Y39409D02*
Y32716D01*
G01X614548Y28359D02*
Y36020D01*
G01X614351Y36755D02*
Y36261D01*
G01X613622Y39409D02*
Y44921D01*
G01X613563Y36755D02*
Y36261D01*
G01X613366Y36020D02*
Y28359D01*
G01X612737Y39409D02*
Y32716D01*
G01X611083Y39409D02*
Y32716D01*
G01X610532Y28359D02*
Y36020D01*
G01X610335Y36755D02*
Y36261D01*
G01X609548Y36755D02*
Y36261D01*
G01X609351Y36020D02*
Y28359D01*
G01X622579Y36020D02*
X622382Y36755D01*
G01X622579Y35526D02*
X622382Y36261D01*
G01X618563Y36020D02*
X618366Y36755D01*
G01X618563Y35526D02*
X618366Y36261D01*
G01X614548Y36020D02*
X614351Y36755D01*
G01X614548Y35526D02*
X614351Y36261D01*
G01X610532Y36020D02*
X610335Y36755D01*
G01X610532Y35526D02*
X610335Y36261D01*
G01X622776Y28485D02*
X622579Y28853D01*
G01X622776Y27991D02*
X622579Y28359D01*
G01X618760Y28485D02*
X618563Y28853D01*
G01X618760Y27991D02*
X618563Y28359D01*
G01X614744Y28485D02*
X614548Y28853D01*
G01X614744Y27991D02*
X614548Y28359D01*
G01X610729Y28485D02*
X610532Y28853D01*
G01X610729Y27991D02*
X610532Y28359D01*
G01X621595Y36755D02*
X622382D01*
G01X617579D02*
X618366D01*
G01X613563D02*
X614351D01*
G01X609548D02*
X610335D01*
G01X614351Y36261D02*
X613563D01*
G01X610335D02*
X609548D01*
G01X618366D02*
X617579D01*
G01X622382D02*
X621595D01*
G01X612737Y35984D02*
X611083D01*
G01X616752D02*
X615099D01*
G01X620768D02*
X619114D01*
G01X624784D02*
X623130D01*
G01X621654Y42703D02*
X621652Y42460D01*
G01X623227D02*
X623229Y42703D01*
G01X616654D02*
X616656Y42460D01*
G01X618231D02*
X618229Y42703D01*
G01X611654D02*
X611661Y42460D01*
G01X613235D02*
X613229Y42703D01*
G01X611654Y42561D02*
X611661Y42460D01*
G01X613235D02*
X613229Y42561D01*
G01X616654D02*
X616656Y42460D01*
G01X618231D02*
X618229Y42561D01*
G01X621654D02*
X621652Y42460D01*
G01X623227D02*
X623229Y42561D01*
G01X623780Y44921D02*
X624409Y45708D01*
G01X618780Y44921D02*
X619409Y45708D01*
G01X613780Y44921D02*
X614409Y45708D01*
G01X608780Y44921D02*
X609409Y45708D01*
G01X624410Y43346D02*
Y42165D01*
G01X624409Y45708D02*
Y43346D01*
G01X623780D02*
Y45979D01*
G01X623622Y40984D02*
Y44921D01*
G01X623229Y44822D02*
Y42561D01*
G01X623189Y45979D02*
Y44601D01*
G01X623137D02*
Y45979D01*
G01X623091D02*
Y44601D01*
G01X623065Y45979D02*
Y44601D01*
G01X622992Y44822D02*
Y56397D01*
G01X622933Y43444D02*
Y44601D01*
G01X622848D02*
Y45979D01*
G01X622835Y43444D02*
Y44822D01*
G01X622822Y45979D02*
Y44601D01*
G01X622796Y45979D02*
Y44601D01*
G01X622048Y44822D02*
Y43444D01*
G01X621811Y45979D02*
Y44601D01*
G01X621786D02*
Y45979D01*
G01X621759D02*
Y44601D01*
G01X621654Y44822D02*
Y42561D01*
G01X621614Y44822D02*
Y56397D01*
G01X621542Y44601D02*
Y45979D01*
G01X621516D02*
Y44601D01*
G01X621470Y45979D02*
Y44601D01*
G01X621418Y45979D02*
Y44601D01*
G01X621103Y44921D02*
Y43346D01*
G01X620827Y45979D02*
Y44601D01*
G01X620474Y43346D02*
Y45708D01*
G01X620473Y42165D02*
Y43346D01*
G01X619410D02*
Y42165D01*
G01X619409Y45708D02*
Y43346D01*
G01X619055Y44601D02*
Y45979D01*
G01X618780Y43346D02*
Y44921D01*
G01X618465Y45979D02*
Y44601D01*
G01X618412D02*
Y45979D01*
G01X618366D02*
Y44601D01*
G01X618341Y45979D02*
Y44601D01*
G01X618268Y44822D02*
Y56397D01*
G01X618229Y44822D02*
Y42561D01*
G01X618124Y44601D02*
Y45979D01*
G01X618097D02*
Y44601D01*
G01X618071Y45979D02*
Y44601D01*
G01X617835Y43444D02*
Y44822D01*
G01X617087Y45979D02*
Y44601D01*
G01X617061D02*
Y45979D01*
G01X617048Y44822D02*
Y43444D01*
G01X617034Y45979D02*
Y44601D01*
G01X617028Y43444D02*
Y44601D01*
G01X616890Y44822D02*
Y56397D01*
G01X616818Y44601D02*
Y45979D01*
G01X616792D02*
Y44601D01*
G01X616746Y45979D02*
Y44601D01*
G01X616693Y45979D02*
Y44601D01*
G01X616654Y44822D02*
Y42561D01*
G01X616260Y44921D02*
Y40984D01*
G01X616103Y45979D02*
Y43346D01*
G01X615474D02*
Y45708D01*
G01X615473Y42165D02*
Y43346D01*
G01X614410D02*
Y42165D01*
G01X614409Y45708D02*
Y43346D01*
G01X614331Y44822D02*
Y45979D01*
G01X613780Y43346D02*
Y44921D01*
G01X613740Y45979D02*
Y44601D01*
G01X613688D02*
Y45979D01*
G01X613642D02*
Y44601D01*
G01X613616Y45979D02*
Y44601D01*
G01X613544Y44822D02*
Y56397D01*
G01X613400Y44601D02*
Y45979D01*
G01X613373D02*
Y44601D01*
G01X613347Y45979D02*
Y44601D01*
G01X613229Y44822D02*
Y42561D01*
G01X612835Y43444D02*
Y44822D01*
G01X612363Y45979D02*
Y44601D01*
G01X612337D02*
Y45979D01*
G01X612310D02*
Y44601D01*
G01X612166Y44822D02*
Y56397D01*
G01X612093Y44601D02*
Y45979D01*
G01X612067D02*
Y44601D01*
G01X612048Y44822D02*
Y43444D01*
G01X612022Y45979D02*
Y44601D01*
G01X611969Y45979D02*
Y44601D01*
G01X611654Y44822D02*
Y42561D01*
G01X611378Y45979D02*
Y44822D01*
G01X611260Y44921D02*
Y40984D01*
G01X611103Y44921D02*
Y43346D01*
G01X610474D02*
Y45708D01*
G01X610473Y42165D02*
Y43346D01*
G01X609607Y44822D02*
Y45979D01*
G01X609410Y43346D02*
Y42165D01*
G01X609409Y45708D02*
Y43346D01*
G01X609016Y45979D02*
Y44601D01*
G01X608963D02*
Y45979D01*
G01X608918D02*
Y44601D01*
G01X608892Y45979D02*
Y44601D01*
G01X608819Y44822D02*
Y56397D01*
G01X608780Y43346D02*
Y44921D01*
G01X620474Y45708D02*
X621103Y44921D01*
G01X615474Y45708D02*
X616103Y44921D01*
G01X610474Y45708D02*
X611103Y44921D01*
G01X613544Y56397D02*
X612166D01*
G01X618268D02*
X616890D01*
G01X622992D02*
X621614D01*
G01X613544Y55019D02*
X612166D01*
G01X618268D02*
X616890D01*
G01X622992D02*
X621614D01*
G01X613544Y54035D02*
X612166D01*
G01X618268D02*
X616890D01*
G01X622992D02*
X621614D01*
G01X613544Y46963D02*
X612166D01*
G01X618268D02*
X616890D01*
G01X622992D02*
X621614D01*
G01X614331Y45979D02*
X611378D01*
G01X619055D02*
X616103D01*
G01X623780D02*
X620827D01*
G01X620474Y45708D02*
X624409D01*
G01X615474D02*
X619409D01*
G01X610474D02*
X614409D01*
G01X621103Y44921D02*
X623780D01*
G01X616103D02*
X618780D01*
G01X611103D02*
X613780D01*
G01X613740Y44601D02*
X611969D01*
G01X619055D02*
X616693D01*
G01X623189D02*
X620827D01*
G01X614404Y43346D02*
X610479D01*
G01X619404D02*
X615479D01*
G01X624404D02*
X620479D01*
G01X621652Y42460D02*
X623227D01*
G01X616656D02*
X618231D01*
G01X611661D02*
X613235D01*
G01X616289Y40984D02*
X613708D01*
G01X621232D02*
X618651D01*
G01X626174D02*
X623594D01*
G01X625118Y70118D02*
G03I-1181J0D01*
G01X626090D02*
G03I-2153J0D01*
G01X617126D02*
G03I-1181J0D01*
G01X618098D02*
G03I-2153J0D01*
G01X624803Y78803D02*
Y69429D01*
G01X623032D02*
Y78803D01*
G01X616811D02*
Y69429D01*
G01X615040D02*
Y78803D01*
G01X608819D02*
Y69429D01*
G01X623032Y71791D02*
X624803D01*
G01X615040D02*
X616811D01*
G01Y70807D02*
X615040D01*
G01X624803D02*
X623032D01*
G01X616811Y69429D02*
X615040D01*
G01X624803D02*
X623032D01*
G01X624053Y85995D02*
G03X625059Y85433I1006J619D01*
G01X614823D02*
G03X615829Y85995I0J1181D01*
G01X613130Y80118D02*
G03I-1181J0D01*
G01X614102D02*
G03I-2153J0D01*
G01X612702Y81086D02*
X612476Y80898D01*
G01X612702Y82215D02*
X612476Y82027D01*
G01X623860Y87389D02*
X625701Y90172D01*
G01X623860Y88071D02*
X625701Y90853D01*
G01X625099Y78803D02*
Y77426D01*
G01X625059Y86389D02*
Y87176D01*
G01X624705Y78803D02*
Y77426D01*
G01X624410Y78803D02*
Y77426D01*
G01X624053Y86389D02*
Y87176D01*
G01X623926Y86831D02*
Y86274D01*
G01X623860Y88071D02*
Y87389D01*
G01X623425Y78803D02*
Y77426D01*
G01X623130D02*
Y78803D01*
G01X623113Y87176D02*
Y87801D01*
G01X622737Y77426D02*
Y78803D01*
G01X622244Y77426D02*
Y78803D01*
G01X621910Y83110D02*
Y83897D01*
G01X621319Y87801D02*
Y87176D01*
G01Y86389D02*
Y83110D01*
G01X620729D02*
Y83897D01*
G01X619154D02*
Y83110D01*
G01X618563Y87801D02*
Y87176D01*
G01Y86389D02*
Y83110D01*
G01X617973Y83897D02*
Y83110D01*
G01X617599Y78803D02*
Y77426D01*
G01X617107Y78803D02*
Y77426D01*
G01X616770Y87801D02*
Y87176D01*
G01X616713Y78803D02*
Y77426D01*
G01X616418Y78803D02*
Y77426D01*
G01X616022Y87389D02*
Y88071D01*
G01X615957Y86274D02*
Y86831D01*
G01X615829Y87176D02*
Y86389D01*
G01X615433Y78803D02*
Y77426D01*
G01X615138D02*
Y78803D01*
G01X614823Y87176D02*
Y86389D01*
G01X614744Y77426D02*
Y78803D01*
G01X614252Y77426D02*
Y78803D01*
G01X613622Y79429D02*
Y80807D01*
G01X613130D02*
Y79429D01*
G01X612835Y80807D02*
Y79429D01*
G01X612737Y82346D02*
Y81150D01*
G01X612702Y82215D02*
Y81086D01*
G01X612638Y79429D02*
Y80807D01*
G01X612540Y81331D02*
Y82459D01*
G01X612476Y82027D02*
Y80898D01*
G01X612441Y81963D02*
Y79429D01*
G01X611457D02*
Y81963D01*
G01X611422Y80898D02*
Y82027D01*
G01X611359Y82459D02*
Y81331D01*
G01X611260Y80807D02*
Y79429D01*
G01X611196Y81086D02*
Y82215D01*
G01X611162Y82346D02*
Y81150D01*
G01X611063Y80807D02*
Y79429D01*
G01X610768Y80807D02*
Y79429D01*
G01X610276Y80807D02*
Y79429D01*
G01X609607Y78803D02*
Y77426D01*
G01X609114Y78803D02*
Y77426D01*
G01X614181Y90853D02*
X616022Y88071D01*
G01X614181Y90172D02*
X616022Y87389D01*
G01X611422Y82027D02*
X611196Y82215D01*
G01X611422Y80898D02*
X611196Y81086D01*
G01X621319Y87801D02*
X623113D01*
G01X616770D02*
X618563D01*
G01X624053Y85995D02*
X615829D01*
G01X618563Y85734D02*
X621319D01*
G01X645729Y85433D02*
X625059D01*
G01X621910Y83897D02*
X617973D01*
G01Y83110D02*
X621910D01*
G01X611359Y82459D02*
X612540D01*
G01Y81331D02*
X611359D01*
G01X610276Y80807D02*
X613622D01*
G01X611457Y79678D02*
X612441D01*
G01X610276Y79429D02*
X613622D01*
G01X617599Y78803D02*
X614252D01*
G01X625591D02*
X622244D01*
G01X617599Y77426D02*
X614252D01*
G01X625591D02*
X622244D01*
G01X623032Y76441D02*
X624803D01*
G01X615040D02*
X616811D01*
G01X622697Y89705D02*
G03X621910Y90492I-787J0D01*
G01X623196Y90614D02*
G03X621910Y91279I-1285J-910D01*
G01X617973Y90492D02*
G03X617185Y89705I-1J-787D01*
G01X617973Y91279D02*
G03X616687Y90614I-1J-1575D01*
G01X624954Y91371D02*
Y90689D01*
G01X621910Y89311D02*
Y91279D01*
G01X617973D02*
Y89311D01*
G01X614929Y90689D02*
Y91371D01*
G01X614181Y90853D02*
Y90172D01*
G01X614141Y90295D02*
Y90977D01*
G01X614929Y91371D02*
X624954D01*
G01X621910Y91279D02*
X617973D01*
G01Y91068D02*
X621910D01*
G01X624954Y90689D02*
X614929D01*
G01X621910Y90492D02*
X617973D01*
G01Y90098D02*
X621910D01*
G01Y89705D02*
X617973D01*
G01X621910Y89311D02*
X617973D01*
G01X624413Y299606D02*
X624425Y300266D01*
G01X624423Y301194D02*
X624392Y299606D01*
G01X620475D02*
X620488Y300266D01*
G01X620486Y301194D02*
X620455Y299606D01*
G01X616538D02*
X616551Y300266D01*
G01X616549Y301194D02*
X616518Y299606D01*
G01X612601D02*
X612614Y300266D01*
G01X612612Y301194D02*
X612581Y299606D01*
G01X623184D02*
X623194Y300197D01*
G01X623192Y301107D02*
X623166Y299606D01*
G01X619247D02*
X619257Y300197D01*
G01X619255Y301107D02*
X619229Y299606D01*
G01X615310D02*
X615320Y300197D01*
G01X615318Y301107D02*
X615292Y299606D01*
G01X611373D02*
X611383Y300197D01*
G01X611381Y301107D02*
X611355Y299606D01*
G01X624398Y293082D02*
X624393Y291295D01*
G01X624384Y291563D02*
X624389Y293350D01*
G01X619318Y297019D02*
X619313Y295232D01*
G01X619303Y295500D02*
X619308Y297287D01*
G01X616524Y293082D02*
X616519Y291295D01*
G01X616510Y291563D02*
X616515Y293350D01*
G01X611444Y297019D02*
X611438Y295232D01*
G01X611429Y295500D02*
X611434Y297287D01*
G01X624408Y293799D02*
Y294783D01*
G01X624252Y290846D02*
Y289862D01*
G01X623386Y290846D02*
Y289862D01*
G01X623231Y294783D02*
Y293799D01*
G01X620471Y294783D02*
Y293799D01*
G01X620315Y298720D02*
Y297736D01*
G01X619449Y298720D02*
Y297736D01*
G01X619294Y293799D02*
Y294783D01*
G01X616534Y293799D02*
Y294783D01*
G01X616378Y290846D02*
Y289862D01*
G01X615512Y290846D02*
Y289862D01*
G01X615357Y294783D02*
Y293799D01*
G01X612597Y294783D02*
Y293799D01*
G01X612441Y298720D02*
Y297736D01*
G01X611575Y298720D02*
Y297736D01*
G01X611420Y293799D02*
Y294783D01*
G01X623250Y293350D02*
X623255Y291563D01*
G01X623245Y291295D02*
X623240Y293082D01*
G01X620456Y297287D02*
X620461Y295500D01*
G01X620452Y295232D02*
X620447Y297019D01*
G01X615375Y293350D02*
X615381Y291563D01*
G01X615371Y291295D02*
X615366Y293082D01*
G01X612582Y297287D02*
X612587Y295500D01*
G01X612578Y295232D02*
X612573Y297019D01*
G01X624472Y299606D02*
X624447Y301107D01*
G01X624444Y300197D02*
X624454Y299606D01*
G01X620535D02*
X620510Y301107D01*
G01X620507Y300197D02*
X620517Y299606D01*
G01X616598D02*
X616573Y301107D01*
G01X616570Y300197D02*
X616580Y299606D01*
G01X612661D02*
X612636Y301107D01*
G01X612633Y300197D02*
X612643Y299606D01*
G01X623246D02*
X623216Y301194D01*
G01X623213Y300266D02*
X623226Y299606D01*
G01X619309D02*
X619279Y301194D01*
G01X619276Y300266D02*
X619289Y299606D01*
G01X615372D02*
X615342Y301194D01*
G01X615339Y300266D02*
X615352Y299606D01*
G01X611435D02*
X611405Y301194D01*
G01X611402Y300266D02*
X611415Y299606D01*
G01X623204Y301477D02*
X624434D01*
G01X619267D02*
X620497D01*
G01X615330D02*
X616560D01*
G01X611393D02*
X612623D01*
G01X623216Y301194D02*
X624423D01*
G01X619279D02*
X620486D01*
G01X615342D02*
X616549D01*
G01X611405D02*
X612612D01*
G01X612636Y301107D02*
X611381D01*
G01X616573D02*
X615318D01*
G01X620510D02*
X619255D01*
G01X624447D02*
X623192D01*
G01X623204Y300492D02*
X624434D01*
G01X619267D02*
X620497D01*
G01X615330D02*
X616560D01*
G01X611393D02*
X612623D01*
G01X612614Y300266D02*
X611402D01*
G01X616551D02*
X615339D01*
G01X620488D02*
X619276D01*
G01X624425D02*
X623213D01*
G01X623194Y300197D02*
X624444D01*
G01X619257D02*
X620507D01*
G01X615320D02*
X616570D01*
G01X611383D02*
X612633D01*
G01X612564Y298720D02*
X611453D01*
G01X620438D02*
X619327D01*
G01Y297736D02*
X620438D01*
G01X611453D02*
X612564D01*
G01X619308Y297287D02*
X620456D01*
G01X611434D02*
X612582D01*
G01X612573Y297019D02*
X611444D01*
G01X620447D02*
X619318D01*
G01X612587Y295500D02*
X611429D01*
G01X620461D02*
X619303D01*
G01X619313Y295232D02*
X620452D01*
G01X611438D02*
X612578D01*
G01X623231Y294783D02*
X624408D01*
G01X619294D02*
X620471D01*
G01X615357D02*
X616534D01*
G01X611420D02*
X612597D01*
G01Y293799D02*
X611420D01*
G01X616534D02*
X615357D01*
G01X620471D02*
X619294D01*
G01X624408D02*
X623231D01*
G01X616515Y293350D02*
X615375D01*
G01X624389D02*
X623250D01*
G01X623240Y293082D02*
X624398D01*
G01X615366D02*
X616524D01*
G01X623255Y291563D02*
X624384D01*
G01X615381D02*
X616510D01*
G01X616519Y291295D02*
X615371D01*
G01X624393D02*
X623245D01*
G01X616501Y290846D02*
X615390D01*
G01X624375D02*
X623264D01*
G01Y289862D02*
X624375D01*
G01X615390D02*
X616501D01*
G01Y316437D02*
X615390D01*
G01X624375D02*
X623264D01*
G01X616501Y315452D02*
X615390D01*
G01X624375D02*
X623264D01*
G01X623245Y315003D02*
X624393D01*
G01X615371D02*
X616519D01*
G01X616510Y314736D02*
X615381D01*
G01X624384D02*
X623255D01*
G01X616524Y313216D02*
X615366D01*
G01X624398D02*
X623240D01*
G01X623250Y312948D02*
X624389D01*
G01X615375D02*
X616515D01*
G01X612597Y312500D02*
X611420D01*
G01X616534D02*
X615357D01*
G01X620471D02*
X619294D01*
G01X624408D02*
X623231D01*
G01X612597Y311515D02*
X611420D01*
G01X616534D02*
X615357D01*
G01X620471D02*
X619294D01*
G01X624408D02*
X623231D01*
G01X612578Y311066D02*
X611438D01*
G01X620452D02*
X619313D01*
G01X619303Y310799D02*
X620461D01*
G01X611429D02*
X612587D01*
G01X623216Y305104D02*
X623246Y306692D01*
G01X623226D02*
X623213Y306032D01*
G01X619279Y305104D02*
X619309Y306692D01*
G01X619289D02*
X619276Y306032D01*
G01X615342Y305104D02*
X615372Y306692D01*
G01X615352D02*
X615339Y306032D01*
G01X611405Y305104D02*
X611435Y306692D01*
G01X611415D02*
X611402Y306032D01*
G01X624447Y305191D02*
X624472Y306692D01*
G01X624454D02*
X624444Y306102D01*
G01X620510Y305191D02*
X620535Y306692D01*
G01X620517D02*
X620507Y306102D01*
G01X616573Y305191D02*
X616598Y306692D01*
G01X616580D02*
X616570Y306102D01*
G01X612636Y305191D02*
X612661Y306692D01*
G01X612643D02*
X612633Y306102D01*
G01X623255Y314736D02*
X623250Y312948D01*
G01X623240Y313216D02*
X623245Y315003D01*
G01X620461Y310799D02*
X620456Y309011D01*
G01X620447Y309279D02*
X620452Y311066D01*
G01X615381Y314736D02*
X615375Y312948D01*
G01X615366Y313216D02*
X615371Y315003D01*
G01X612587Y310799D02*
X612582Y309011D01*
G01X612573Y309279D02*
X612578Y311066D01*
G01X624408Y311515D02*
Y312500D01*
G01X624252Y316437D02*
Y315452D01*
G01X623386D02*
Y316437D01*
G01X623231Y312500D02*
Y311515D01*
G01X620471Y312500D02*
Y311515D01*
G01X620315Y308563D02*
Y307578D01*
G01X619449D02*
Y308563D01*
G01X619294Y311515D02*
Y312500D01*
G01X617441Y323228D02*
Y317618D01*
G01X616534Y311515D02*
Y312500D01*
G01X616378Y316437D02*
Y315452D01*
G01X615512D02*
Y316437D01*
G01X615357Y312500D02*
Y311515D01*
G01X612597Y312500D02*
Y311515D01*
G01X612441Y323228D02*
Y317618D01*
G01Y308563D02*
Y307578D01*
G01X611575D02*
Y308563D01*
G01X611420Y311515D02*
Y312500D01*
G01X624393Y315003D02*
X624398Y313216D01*
G01X624389Y312948D02*
X624384Y314736D01*
G01X619313Y311066D02*
X619318Y309279D01*
G01X619308Y309011D02*
X619303Y310799D01*
G01X616519Y315003D02*
X616524Y313216D01*
G01X616515Y312948D02*
X616510Y314736D01*
G01X611438Y311066D02*
X611444Y309279D01*
G01X611434Y309011D02*
X611429Y310799D01*
G01X623194Y306102D02*
X623184Y306692D01*
G01X623166D02*
X623192Y305191D01*
G01X619257Y306102D02*
X619247Y306692D01*
G01X619229D02*
X619255Y305191D01*
G01X615320Y306102D02*
X615310Y306692D01*
G01X615292D02*
X615318Y305191D01*
G01X611383Y306102D02*
X611373Y306692D01*
G01X611355D02*
X611381Y305191D01*
G01X624425Y306032D02*
X624413Y306692D01*
G01X624392D02*
X624423Y305104D01*
G01X620488Y306032D02*
X620475Y306692D01*
G01X620455D02*
X620486Y305104D01*
G01X616551Y306032D02*
X616538Y306692D01*
G01X616518D02*
X616549Y305104D01*
G01X612614Y306032D02*
X612601Y306692D01*
G01X612581D02*
X612612Y305104D01*
G01X619318Y309279D02*
X620447D01*
G01X611444D02*
X612573D01*
G01X612582Y309011D02*
X611434D01*
G01X620456D02*
X619308D01*
G01X612564Y308563D02*
X611453D01*
G01X620438D02*
X619327D01*
G01X612564Y307578D02*
X611453D01*
G01X620438D02*
X619327D01*
G01X612633Y306102D02*
X611383D01*
G01X616570D02*
X615320D01*
G01X620507D02*
X619257D01*
G01X624444D02*
X623194D01*
G01X623213Y306032D02*
X624425D01*
G01X619276D02*
X620488D01*
G01X615339D02*
X616551D01*
G01X611402D02*
X612614D01*
G01X612623Y305806D02*
X611393D01*
G01X616560D02*
X615330D01*
G01X620497D02*
X619267D01*
G01X624434D02*
X623204D01*
G01X623192Y305191D02*
X624447D01*
G01X619255D02*
X620510D01*
G01X615318D02*
X616573D01*
G01X611381D02*
X612636D01*
G01X612612Y305104D02*
X611405D01*
G01X616549D02*
X615342D01*
G01X620486D02*
X619279D01*
G01X624423D02*
X623216D01*
G01X612623Y304822D02*
X611393D01*
G01X616560D02*
X615330D01*
G01X620497D02*
X619267D01*
G01X624434D02*
X623204D01*
G01X633347Y323228D02*
X617441D01*
G01X620483Y372100D02*
X614331Y366571D01*
G01X612363D02*
X619252Y372853D01*
G01X614331Y366571D02*
X621221D01*
G01X610394Y365315D02*
X608918D01*
G01X621221D02*
X612363D01*
G01X624420D02*
X623189D01*
G01X624420Y371597D02*
Y365315D01*
G01X623189D02*
Y373356D01*
G01X621221Y366571D02*
Y365315D01*
G01X612363D02*
Y366571D01*
G01X610394Y377126D02*
Y365315D01*
G01X608918D02*
Y375115D01*
G01X625650Y372351D02*
X624912Y372100D01*
G01Y373105D02*
X625650Y373356D01*
G01X616546Y377126D02*
X617530D01*
G01X608918D02*
X610394D01*
G01X617284Y375869D02*
X616300D01*
G01X613839Y374361D02*
X612609D01*
G01X623189Y373356D02*
X624420D01*
G01X614823Y376874D02*
X616546Y377126D01*
G01X616300Y375869D02*
X615069Y375618D01*
G01X613839Y376372D02*
X614823Y376874D01*
G01X615069Y375618D02*
X614331Y375115D01*
G01X624912Y372100D02*
X624420Y371597D01*
G01Y372602D02*
X624912Y373105D01*
G01X612855Y375366D02*
X613839Y376372D01*
G01X620975Y372853D02*
X620483Y372100D01*
G01X614331Y375115D02*
X613839Y374361D01*
G01X619252Y372853D02*
X619744Y373859D01*
G01X620975Y375366D02*
X621221Y374361D01*
G01X619744D02*
X619252Y375115D01*
G01X619990Y376372D02*
X620975Y375366D01*
G01X619252Y375115D02*
X618514Y375618D01*
G01X619006Y376874D02*
X619990Y376372D01*
G01X618514Y375618D02*
X617284Y375869D01*
G01X617530Y377126D02*
X619006Y376874D01*
G01X621221Y373859D02*
X620975Y372853D01*
G01X612609Y374361D02*
X612855Y375366D01*
G01X624420Y373356D02*
Y372602D01*
G01X621221Y374361D02*
Y373859D01*
G01X619744D02*
Y374361D01*
G01X629233Y2403D02*
X629239Y2543D01*
G01X630807Y2478D02*
X630814Y2543D01*
G01X629239D02*
X629233Y2478D01*
G01X630814Y2543D02*
X630807Y2403D01*
G01X625217D02*
X625220Y2543D01*
G01X626792Y2478D02*
X626795Y2543D01*
G01X625220D02*
X625217Y2478D01*
G01X626795Y2543D02*
X626792Y2403D01*
G01X633248D02*
X633257Y2543D01*
G01X634823Y2478D02*
X634832Y2543D01*
G01X633257D02*
X633248Y2478D01*
G01X634832Y2543D02*
X634823Y2403D01*
G01X637077Y826D02*
G03Y2401I0J788D01*
G01X629784Y-6693D02*
G03X628996Y-5906I-787J0D01*
G01X640817Y-748D02*
G03X637668I-1574J0D01*
G01X638396Y-6654D02*
X638002Y-7048D01*
G01X636172Y-6654D02*
X635778Y-7048D01*
G01X635177Y6648D02*
X634832Y2543D01*
G01X633730Y8155D02*
X633257Y2543D01*
G01X631150Y8155D02*
X630814Y2543D01*
G01X629575Y8155D02*
X629239Y2543D01*
G01X626995Y8155D02*
X626795Y2543D01*
G01X625420Y8155D02*
X625220Y2543D01*
G01X641152Y14606D02*
Y-6654D01*
G01X640817Y-5934D02*
Y6564D01*
G01X638396Y-355D02*
Y-7048D01*
G01X638061Y15787D02*
Y6141D01*
G01X637668Y-7048D02*
Y-748D01*
G01X636290Y9213D02*
Y6170D01*
G01X636172Y-6654D02*
Y16574D01*
G01X636093Y-6733D02*
Y-7048D01*
G01X635985D02*
Y14606D01*
G01X635177Y-2520D02*
Y17559D01*
G01X634823Y-16D02*
Y28485D01*
G01X634508Y-7874D02*
Y-7087D01*
G01X633721D02*
Y-7874D01*
G01X633248Y-16D02*
Y28485D01*
G01X632933Y-7874D02*
Y-7087D01*
G01X632815Y-2520D02*
Y17559D01*
G01X632343Y36653D02*
Y-5670D01*
G01X631162Y-2520D02*
Y17559D01*
G01X630807Y-16D02*
Y28485D01*
G01X630571Y-7874D02*
Y-7087D01*
G01X629784Y-6693D02*
Y-7874D01*
G01X629233Y-16D02*
Y28485D01*
G01X628800Y17559D02*
Y-2520D01*
G01X627914Y-7048D02*
Y39D01*
G01X627146Y-2520D02*
Y17559D01*
G01X626792Y28485D02*
Y-16D01*
G01X625217D02*
Y28485D01*
G01X641152Y-6654D02*
X641546Y-7048D01*
G01X632343Y-5670D02*
X633721Y-7048D01*
G01X640817Y6564D02*
X636290D01*
G01Y6170D02*
X640817D01*
G01X638061Y6141D02*
X636172D01*
G01X626792Y4983D02*
X625217D01*
G01X630807D02*
X629233D01*
G01X634823D02*
X633248D01*
G01X626792Y4489D02*
X625217D01*
G01X630807D02*
X629233D01*
G01X634823D02*
X633248D01*
G01Y4277D02*
X634823D01*
G01X629233D02*
X630807D01*
G01X625217D02*
X626792D01*
G01X633248Y2543D02*
X634832D01*
G01X629233D02*
X630814D01*
G01X625217D02*
X626795D01*
G01X636172Y2401D02*
X637077D01*
G01X633248Y2338D02*
X634823D01*
G01X629233D02*
X630807D01*
G01X625217D02*
X626792D01*
G01X633248Y1362D02*
X634823D01*
G01X629233D02*
X630807D01*
G01X625217D02*
X626792D01*
G01X636172Y826D02*
X637077D01*
G01X632343Y39D02*
X627914D01*
G01X633248Y-16D02*
X634823D01*
G01X629233D02*
X630807D01*
G01X625217D02*
X626792D01*
G01X632815Y-158D02*
X635177D01*
G01X628800D02*
X631162D01*
G01X638396Y-355D02*
X641152D01*
G01Y-748D02*
X638396D01*
G01X631162Y-2520D02*
X628800D01*
G01X635177D02*
X632815D01*
G01X643376Y-3504D02*
X641152D01*
G01X643376Y-3816D02*
X641152D01*
G01X640817Y-4162D02*
X643376D01*
G01Y-4335D02*
X641152D01*
G01X643376Y-4654D02*
X640817D01*
G01X643376Y-4685D02*
X641152D01*
G01X643376Y-5048D02*
X640817D01*
G01X643376Y-5146D02*
X640817D01*
G01X627914Y-5670D02*
X635985D01*
G01X643376Y-5934D02*
X640817D01*
G01X629678Y-6300D02*
X652323D01*
G01X636172Y-6654D02*
X643376D01*
G01X629575Y8155D02*
X629584Y8361D01*
G01X629610Y8946D02*
X629584Y8361D01*
G01X631150Y8155D02*
X631162Y8283D01*
G01X625420Y8155D02*
X625425Y8361D01*
G01X625441Y8946D02*
X625425Y8361D01*
G01X627000D02*
X627016Y8946D01*
G01X625602Y12829D02*
X625623Y13620D01*
G01X627198D02*
X627177Y12829D01*
G01X627000Y8361D02*
X626995Y8155D01*
G01X633730D02*
X633742Y8361D01*
G01X629610Y8520D02*
G03X629575Y8155I80209J-7875D01*
G01X627016Y8520D02*
G03X626995Y8155I122589J-7236D01*
G01X625441Y8520D02*
G03X625420Y8155I134358J-7913D01*
G01X633779Y8946D02*
G03X633742Y8361I234187J-15106D01*
G01X627198Y13620D02*
G03X627177Y13236I69602J-3999D01*
G01X633779Y8520D02*
G03X633730Y8155I57533J-7909D01*
G01X638849Y16574D02*
G03X638061Y15787I-1J-787D01*
G01X634161Y13255D02*
G03X634210Y13620I-62245J8542D01*
G01X629881Y13255D02*
G03X629916Y13620I-86777J8505D01*
G01X625602Y13255D02*
G03X625623Y13620I-145358J8546D01*
G01X635735Y12829D02*
G03X635785Y13620I-251894J16320D01*
G01X634161Y12829D02*
G03X634210Y13620I-256506J16287D01*
G01X631456Y12829D02*
G03X631491Y13620I-353671J16045D01*
G01X629881Y12829D02*
G03X629916Y13620I-360085J16329D01*
G01X635597Y11259D02*
X635736Y12829D01*
G01X634161D02*
X633779Y8520D01*
G01X634161Y13255D02*
X633779Y8946D01*
G01X638818Y40984D02*
X636352Y11850D01*
G01X638422Y40984D02*
X635957Y11850D01*
G01X636060Y40984D02*
X633595Y11850D01*
G01X633200D02*
X635665Y40984D01*
G01X638214Y42460D02*
X635785Y13620D01*
G01X636639Y42460D02*
X634210Y13620D01*
G01X635577Y11259D02*
X635736Y13236D01*
G01X631357Y11259D02*
X631456Y12829D01*
G01X629881D02*
X629610Y8520D01*
G01X629881Y13255D02*
X629610Y8946D01*
G01X633874Y40984D02*
X632113Y11850D01*
G01X633479Y40984D02*
X631719Y11850D01*
G01X631117Y40984D02*
X629357Y11850D01*
G01X628962D02*
X630723Y40984D01*
G01X633218Y42460D02*
X631491Y13620D01*
G01X631644Y42460D02*
X629916Y13620D01*
G01X631344Y11259D02*
X631456Y13236D01*
G01X627016Y8520D02*
X627177Y12829D01*
G01X627016Y8946D02*
X627146Y12434D01*
G01X625602Y12829D02*
X625441Y8520D01*
G01X625602Y13255D02*
X625441Y8946D01*
G01X628931Y40984D02*
X627874Y11850D01*
G01X628537Y40984D02*
X627480Y11850D01*
G01X628223Y42460D02*
X627198Y13620D01*
G01X626648Y42460D02*
X625623Y13620D01*
G01X627146Y12329D02*
X627177Y13236D01*
G01X635736Y12829D02*
Y13236D01*
G01X634161Y13255D02*
Y12829D01*
G01X633779Y8946D02*
Y8520D01*
G01X631456Y12829D02*
Y13236D01*
G01X629881Y13255D02*
Y12829D01*
G01X629610Y8946D02*
Y8520D01*
G01X627177Y12829D02*
Y13236D01*
G01X627016Y8520D02*
Y8946D01*
G01X625602Y13255D02*
Y12829D01*
G01X625441Y8946D02*
Y8520D01*
G01X631162Y17559D02*
X628800D01*
G01X635177D02*
X632815D01*
G01X636172Y16574D02*
X643376D01*
G01X643563Y14606D02*
X635985D01*
G01X634210Y13620D02*
X635785D01*
G01X629916D02*
X631491D01*
G01X625623D02*
X627198D01*
G01X627146Y13255D02*
X625602D01*
G01X631162D02*
X629881D01*
G01X635177D02*
X634161D01*
G01X627177Y12829D02*
X625602D01*
G01X631456D02*
X629881D01*
G01X635736D02*
X634161D01*
G01X635177Y11259D02*
X646122D01*
G01X631162D02*
X632815D01*
G01X628800D02*
X627146D01*
G01X643376Y9213D02*
X636290D01*
G01X627016Y8946D02*
X625441D01*
G01X631162D02*
X629610D01*
G01X635177D02*
X633779D01*
G01X636290Y8819D02*
X643376D01*
G01X627016Y8520D02*
X625441D01*
G01X631162D02*
X629610D01*
G01X635177D02*
X633779D01*
G01X633742Y8361D02*
X635177D01*
G01X629584D02*
X631162D01*
G01X625425D02*
X627000D01*
G01X633730Y8155D02*
X635177D01*
G01X629575D02*
X631150D01*
G01X625420D02*
X626995D01*
G01X636487Y40048D02*
G03X641387I2450J4085D01*
G01X645315Y44133D02*
G03I-6378J0D01*
G01X645473D02*
X638937Y37598D01*
G01X633445Y28359D02*
X633248Y27991D01*
G01X633445Y28853D02*
X633248Y28485D01*
G01X629429Y28359D02*
X629233Y27991D01*
G01X629429Y28853D02*
X629233Y28485D01*
G01X625414Y28359D02*
X625217Y27991D01*
G01X625414Y28853D02*
X625217Y28485D01*
G01X633642Y36261D02*
X633445Y35526D01*
G01X633642Y36755D02*
X633445Y36020D01*
G01X629626Y36261D02*
X629429Y35526D01*
G01X629626Y36755D02*
X629429Y36020D01*
G01X625611Y36261D02*
X625414Y35526D01*
G01X625611Y36755D02*
X625414Y36020D01*
G01X637658Y28779D02*
Y32716D01*
G01X636260Y44921D02*
Y39409D01*
G01X635177D02*
Y32716D01*
G01X634626Y28359D02*
Y36020D01*
G01X634429Y36755D02*
Y36261D01*
G01X633642Y36755D02*
Y36261D01*
G01X633445Y36020D02*
Y28359D01*
G01X632815Y39409D02*
Y32716D01*
G01X631260Y45979D02*
Y39409D01*
G01X631162D02*
Y32716D01*
G01X630611Y28359D02*
Y36020D01*
G01X630414Y36755D02*
Y36261D01*
G01X629626Y36755D02*
Y36261D01*
G01X629429Y36020D02*
Y28359D01*
G01X628800Y39409D02*
Y32716D01*
G01X627146Y39409D02*
Y32716D01*
G01X626595Y28359D02*
Y36020D01*
G01X626398Y36755D02*
Y36261D01*
G01X626260Y39409D02*
Y44921D01*
G01X625611Y36755D02*
Y36261D01*
G01X625414Y36020D02*
Y28359D01*
G01X634626Y36020D02*
X634429Y36755D01*
G01X634626Y35526D02*
X634429Y36261D01*
G01X630611Y36020D02*
X630414Y36755D01*
G01X630611Y35526D02*
X630414Y36261D01*
G01X626595Y36020D02*
X626398Y36755D01*
G01X626595Y35526D02*
X626398Y36261D01*
G01X634823Y28485D02*
X634626Y28853D01*
G01X634823Y27991D02*
X634626Y28359D01*
G01X630807Y28485D02*
X630611Y28853D01*
G01X630807Y27991D02*
X630611Y28359D01*
G01X626792Y28485D02*
X626595Y28853D01*
G01X626792Y27991D02*
X626595Y28359D01*
G01X632402Y44133D02*
X638937Y37598D01*
G01X633642Y36755D02*
X634429D01*
G01X629626D02*
X630414D01*
G01X625611D02*
X626398D01*
G01Y36261D02*
X625611D01*
G01X630414D02*
X629626D01*
G01X634429D02*
X633642D01*
G01X628800Y35984D02*
X627146D01*
G01X632815D02*
X631162D01*
G01X646122D02*
X635177D01*
G01X643563Y31732D02*
X637658D01*
G01X643563Y28779D02*
X637658D01*
G01X643563Y26811D02*
X632343D01*
G01X631654Y42703D02*
X631644Y42460D01*
G01X633218D02*
X633229Y42703D01*
G01X626654D02*
X626648Y42460D01*
G01X628223D02*
X628229Y42703D01*
G01X626654Y42561D02*
X626648Y42460D01*
G01X628223D02*
X628229Y42561D01*
G01X631654D02*
X631644Y42460D01*
G01X633218D02*
X633229Y42561D01*
G01X636654Y42703D02*
X636639Y42460D01*
G01X638214D02*
X638229Y42703D01*
G01X636654Y42561D02*
X636639Y42460D01*
G01X638214D02*
X638229Y42561D01*
G01X634852Y46583D02*
G03Y41683I4085J-2450D01*
G01X641387Y48219D02*
G03X636487I-2450J-4086D01*
G01X632402Y44133D02*
X638937Y50669D01*
G01X638780Y44921D02*
X639409Y45708D01*
G01X633780Y44921D02*
X634409Y45708D01*
G01X628780Y44921D02*
X629409Y45708D01*
G01X640709Y45979D02*
Y44601D01*
G01X640683D02*
Y45979D01*
G01X640656D02*
Y44601D01*
G01X640512D02*
Y56397D01*
G01X640440Y44601D02*
Y45979D01*
G01X640414Y46102D02*
Y42165D01*
G01X640368Y45979D02*
Y44601D01*
G01X640315Y45979D02*
Y44601D01*
G01X639981Y44822D02*
Y43444D01*
G01X639725Y45979D02*
Y44822D01*
G01X639429Y42165D02*
Y40984D01*
G01X639410Y43346D02*
Y42165D01*
G01X639409Y45708D02*
Y43346D01*
G01X638780D02*
Y44921D01*
G01X638622Y40984D02*
Y44921D01*
G01X638229Y42561D02*
Y44822D01*
G01X637953D02*
Y45979D01*
G01X637835Y43444D02*
Y44822D01*
G01X637363Y45979D02*
Y44601D01*
G01X637310D02*
Y45979D01*
G01X637264D02*
Y44601D01*
G01X637238Y45979D02*
Y44601D01*
G01X637166Y44822D02*
Y56397D01*
G01X637048Y44822D02*
Y43444D01*
G01X637022Y44601D02*
Y45979D01*
G01X636995D02*
Y44601D01*
G01X636969Y45979D02*
Y44601D01*
G01X636654Y42561D02*
Y44822D01*
G01X636103Y44921D02*
Y43346D01*
G01X635985Y45979D02*
Y44601D01*
G01X635959D02*
Y45979D01*
G01X635932D02*
Y44601D01*
G01X635788Y44822D02*
Y56397D01*
G01X635715Y44601D02*
Y45979D01*
G01X635689D02*
Y44601D01*
G01X635644Y45979D02*
Y44601D01*
G01X635591Y45979D02*
Y44601D01*
G01X635474Y43346D02*
Y45708D01*
G01X635473Y42165D02*
Y43346D01*
G01X635000Y45979D02*
Y44822D01*
G01X634410Y43346D02*
Y42165D01*
G01X634409Y45708D02*
Y43346D01*
G01X633780D02*
Y44921D01*
G01X633622Y40984D02*
Y44921D01*
G01X633229Y42561D02*
Y45979D01*
G01X632835Y43444D02*
Y44822D01*
G01X632638Y45979D02*
Y44601D01*
G01X632585D02*
Y45979D01*
G01X632540D02*
Y44601D01*
G01X632514Y45979D02*
Y44601D01*
G01X632441Y44822D02*
Y56397D01*
G01X632297Y44601D02*
Y45979D01*
G01X632270D02*
Y44601D01*
G01X632244Y45979D02*
Y44601D01*
G01X632048Y44822D02*
Y43444D01*
G01X631654Y42561D02*
Y44822D01*
G01X631235Y44601D02*
Y45979D01*
G01X631207D02*
Y44601D01*
G01X631103Y43346D02*
Y44921D01*
G01X631063Y44822D02*
Y56397D01*
G01X630991Y44601D02*
Y45979D01*
G01X630965D02*
Y44601D01*
G01X630919Y45979D02*
Y44601D01*
G01X630866Y45979D02*
Y44601D01*
G01X630474Y43346D02*
Y45708D01*
G01X630473Y42165D02*
Y43346D01*
G01X630276Y45979D02*
Y44822D01*
G01X629410Y43346D02*
Y42165D01*
G01X629409Y45708D02*
Y43346D01*
G01X628780D02*
Y44921D01*
G01X628622Y40984D02*
Y44921D01*
G01X628504Y44822D02*
Y45979D01*
G01X628229Y42561D02*
Y44822D01*
G01X627914Y45979D02*
Y44601D01*
G01X627861D02*
Y45979D01*
G01X627835Y43444D02*
Y44822D01*
G01X627815Y45979D02*
Y44601D01*
G01X627790Y45979D02*
Y44601D01*
G01X627717Y44822D02*
Y56397D01*
G01X627573Y44601D02*
Y45979D01*
G01X627546D02*
Y44601D01*
G01X627520Y45979D02*
Y44601D01*
G01X627048Y44822D02*
Y43444D01*
G01X626654Y42561D02*
Y44822D01*
G01X626536Y45979D02*
Y44601D01*
G01X626510D02*
Y45979D01*
G01X626483D02*
Y44601D01*
G01X626339Y44822D02*
Y56397D01*
G01X626266Y44601D02*
Y45979D01*
G01X626240D02*
Y44601D01*
G01X626195Y45979D02*
Y44601D01*
G01X626142Y45979D02*
Y44601D01*
G01X626103Y44921D02*
Y43346D01*
G01X625551Y45979D02*
Y44822D01*
G01X625474Y43346D02*
Y45708D01*
G01X625473Y42165D02*
Y43346D01*
G01X635474Y45708D02*
X636103Y44921D01*
G01X630474Y45708D02*
X631103Y44921D01*
G01X626103D02*
X625474Y45708D01*
G01X638937Y50669D02*
X645473Y44133D01*
G01X627717Y56397D02*
X626339D01*
G01X632441D02*
X631063D01*
G01X637166D02*
X635788D01*
G01X641890D02*
X640512D01*
G01X627717Y55019D02*
X626339D01*
G01X632441D02*
X631063D01*
G01X637166D02*
X635788D01*
G01X641890D02*
X640512D01*
G01X627717Y54035D02*
X626339D01*
G01X632441D02*
X631063D01*
G01X637166D02*
X635788D01*
G01X641890D02*
X640512D01*
G01X627717Y46963D02*
X626339D01*
G01X632441D02*
X631063D01*
G01X637166D02*
X635788D01*
G01X641890D02*
X640512D01*
G01X628504Y45979D02*
X625551D01*
G01X633229D02*
X630276D01*
G01X637953D02*
X635000D01*
G01X642677D02*
X639725D01*
G01X635474Y45708D02*
X639409D01*
G01X630474D02*
X634409D01*
G01X625474D02*
X629409D01*
G01X636103Y44921D02*
X638780D01*
G01X631103D02*
X633780D01*
G01X628780D02*
X626103D01*
G01X639981Y44601D02*
X642677D01*
G01X627914D02*
X626142D01*
G01X632638D02*
X630866D01*
G01X637363D02*
X635591D01*
G01X629404Y43346D02*
X625479D01*
G01X634404D02*
X630479D01*
G01X639404D02*
X635479D01*
G01X636639Y42460D02*
X638214D01*
G01X631644D02*
X633218D01*
G01X626648D02*
X628223D01*
G01X631117Y40984D02*
X628537D01*
G01X636060D02*
X633479D01*
G01X639429D02*
X638422D01*
G01X633111Y70118D02*
G03I-1182J0D01*
G01X641103D02*
G03I-1181J0D01*
G01X642075D02*
G03I-2153J0D01*
G01X634083D02*
G03I-2154J0D01*
G01X640788Y78803D02*
Y69429D01*
G01X639016D02*
Y78803D01*
G01X632796D02*
Y69429D01*
G01X631024D02*
Y78803D01*
G01X639016Y71791D02*
X640788D01*
G01X631024D02*
X632796D01*
G01Y70807D02*
X631024D01*
G01X640788D02*
X639016D01*
G01X632796Y69429D02*
X631024D01*
G01X640788D02*
X639016D01*
G01X637107Y80118D02*
G03I-1181J0D01*
G01X629114D02*
G03I-1181J0D01*
G01X638079D02*
G03I-2153J0D01*
G01X630087D02*
G03I-2154J0D01*
G01X636678Y81086D02*
X636452Y80898D01*
G01X636678Y82215D02*
X636452Y82027D01*
G01X628686Y81086D02*
X628460Y80898D01*
G01X628686Y82215D02*
X628460Y82027D01*
G01X641575Y78803D02*
Y77426D01*
G01X641083Y78803D02*
Y77426D01*
G01X640689Y78803D02*
Y77426D01*
G01X640394Y78803D02*
Y77426D01*
G01X639410Y78803D02*
Y77426D01*
G01X639114D02*
Y78803D01*
G01X638721Y77426D02*
Y78803D01*
G01X638229Y77426D02*
Y78803D01*
G01X637599Y79429D02*
Y80807D01*
G01X637107D02*
Y79429D01*
G01X636811Y80807D02*
Y79429D01*
G01X636713Y82346D02*
Y81150D01*
G01X636678Y82215D02*
Y81086D01*
G01X636614Y79429D02*
Y80807D01*
G01X636516Y81331D02*
Y82459D01*
G01X636452Y82027D02*
Y80898D01*
G01X636418Y81963D02*
Y79429D01*
G01X635433D02*
Y81963D01*
G01X635399Y80898D02*
Y82027D01*
G01X635335Y82459D02*
Y81331D01*
G01X635237Y80807D02*
Y79429D01*
G01X635173Y81086D02*
Y82215D01*
G01X635138Y82346D02*
Y81150D01*
G01X635040Y80807D02*
Y79429D01*
G01X634744Y80807D02*
Y79429D01*
G01X634252Y80807D02*
Y79429D01*
G01X633583Y78803D02*
Y77426D01*
G01X633091Y78803D02*
Y77426D01*
G01X632697Y78803D02*
Y77426D01*
G01X632402Y78803D02*
Y77426D01*
G01X631418Y78803D02*
Y77426D01*
G01X631122D02*
Y78803D01*
G01X630729Y77426D02*
Y78803D01*
G01X630237Y77426D02*
Y78803D01*
G01X629607Y79429D02*
Y80807D01*
G01X629114D02*
Y79429D01*
G01X628819Y80807D02*
Y79429D01*
G01X628721Y82346D02*
Y81150D01*
G01X628686Y82215D02*
Y81086D01*
G01X628622Y79429D02*
Y80807D01*
G01X628524Y81331D02*
Y82459D01*
G01X628460Y82027D02*
Y80898D01*
G01X628425Y81963D02*
Y79429D01*
G01X627441D02*
Y81963D01*
G01X627407Y80898D02*
Y82027D01*
G01X627343Y82459D02*
Y81331D01*
G01X627244Y80807D02*
Y79429D01*
G01X627181Y81086D02*
Y82215D01*
G01X627146Y82346D02*
Y81150D01*
G01X627048Y80807D02*
Y79429D01*
G01X626752Y80807D02*
Y79429D01*
G01X626260Y80807D02*
Y79429D01*
G01X625591Y78803D02*
Y77426D01*
G01X635399Y82027D02*
X635173Y82215D01*
G01X635399Y80898D02*
X635173Y81086D01*
G01X627407Y82027D02*
X627181Y82215D01*
G01X627407Y80898D02*
X627181Y81086D01*
G01X635335Y82459D02*
X636516D01*
G01X627343D02*
X628524D01*
G01Y81331D02*
X627343D01*
G01X636516D02*
X635335D01*
G01X634252Y80807D02*
X637599D01*
G01X626260D02*
X629607D01*
G01X635433Y79678D02*
X636418D01*
G01X627441D02*
X628425D01*
G01X634252Y79429D02*
X637599D01*
G01X626260D02*
X629607D01*
G01X633583Y78803D02*
X630237D01*
G01X641575D02*
X638229D01*
G01X633583Y77426D02*
X630237D01*
G01X641575D02*
X638229D01*
G01X639016Y76441D02*
X640788D01*
G01X631024D02*
X632796D01*
G01X625741Y90295D02*
Y90977D01*
G01X625701Y90172D02*
Y90853D01*
G01X640161Y299606D02*
X640173Y300266D01*
G01X640171Y301194D02*
X640140Y299606D01*
G01X636224D02*
X636236Y300266D01*
G01X636234Y301194D02*
X636203Y299606D01*
G01X632287D02*
X632299Y300266D01*
G01X632297Y301194D02*
X632266Y299606D01*
G01X628350D02*
X628362Y300266D01*
G01X628360Y301194D02*
X628329Y299606D01*
G01X638932D02*
X638942Y300197D01*
G01X638940Y301107D02*
X638914Y299606D01*
G01X634995D02*
X635005Y300197D01*
G01X635003Y301107D02*
X634977Y299606D01*
G01X631058D02*
X631068Y300197D01*
G01X631066Y301107D02*
X631040Y299606D01*
G01X627121D02*
X627131Y300197D01*
G01X627129Y301107D02*
X627103Y299606D01*
G01X640146Y293082D02*
X640141Y291295D01*
G01X640132Y291563D02*
X640137Y293350D01*
G01X635066Y297019D02*
X635061Y295232D01*
G01X635051Y295500D02*
X635056Y297287D01*
G01X632272Y293082D02*
X632267Y291295D01*
G01X632258Y291563D02*
X632263Y293350D01*
G01X627192Y297019D02*
X627187Y295232D01*
G01X627177Y295500D02*
X627182Y297287D01*
G01X640156Y293799D02*
Y294783D01*
G01X640000Y290846D02*
Y289862D01*
G01X639134Y290846D02*
Y289862D01*
G01X638979Y294783D02*
Y293799D01*
G01X636219Y294783D02*
Y293799D01*
G01X636063Y298720D02*
Y297736D01*
G01X635197Y298720D02*
Y297736D01*
G01X635042Y293799D02*
Y294783D01*
G01X632282Y293799D02*
Y294783D01*
G01X632126Y290846D02*
Y289862D01*
G01X631260Y290846D02*
Y289862D01*
G01X631105Y294783D02*
Y293799D01*
G01X628345Y294783D02*
Y293799D01*
G01X628189Y298720D02*
Y297736D01*
G01X627323Y298720D02*
Y297736D01*
G01X627168Y293799D02*
Y294783D01*
G01X638998Y293350D02*
X639003Y291563D01*
G01X638993Y291295D02*
X638988Y293082D01*
G01X636204Y297287D02*
X636209Y295500D01*
G01X636200Y295232D02*
X636195Y297019D01*
G01X631124Y293350D02*
X631129Y291563D01*
G01X631119Y291295D02*
X631114Y293082D01*
G01X628330Y297287D02*
X628335Y295500D01*
G01X628326Y295232D02*
X628321Y297019D01*
G01X640220Y299606D02*
X640195Y301107D01*
G01X640192Y300197D02*
X640202Y299606D01*
G01X636283D02*
X636258Y301107D01*
G01X636255Y300197D02*
X636265Y299606D01*
G01X632346D02*
X632321Y301107D01*
G01X632318Y300197D02*
X632328Y299606D01*
G01X628409D02*
X628384Y301107D01*
G01X628381Y300197D02*
X628391Y299606D01*
G01X638994D02*
X638964Y301194D01*
G01X638961Y300266D02*
X638974Y299606D01*
G01X635057D02*
X635027Y301194D01*
G01X635024Y300266D02*
X635037Y299606D01*
G01X631120D02*
X631090Y301194D01*
G01X631087Y300266D02*
X631100Y299606D01*
G01X627183D02*
X627153Y301194D01*
G01X627150Y300266D02*
X627163Y299606D01*
G01X638952Y301477D02*
X640182D01*
G01X635015D02*
X636245D01*
G01X631078D02*
X632308D01*
G01X627141D02*
X628371D01*
G01X638964Y301194D02*
X640171D01*
G01X635027D02*
X636234D01*
G01X631090D02*
X632297D01*
G01X627153D02*
X628360D01*
G01X628384Y301107D02*
X627129D01*
G01X632321D02*
X631066D01*
G01X636258D02*
X635003D01*
G01X640195D02*
X638940D01*
G01X638952Y300492D02*
X640182D01*
G01X635015D02*
X636245D01*
G01X631078D02*
X632308D01*
G01X627141D02*
X628371D01*
G01X628362Y300266D02*
X627150D01*
G01X632299D02*
X631087D01*
G01X636236D02*
X635024D01*
G01X640173D02*
X638961D01*
G01X638942Y300197D02*
X640192D01*
G01X635005D02*
X636255D01*
G01X631068D02*
X632318D01*
G01X627131D02*
X628381D01*
G01X628312Y298720D02*
X627201D01*
G01X636186D02*
X635075D01*
G01Y297736D02*
X636186D01*
G01X627201D02*
X628312D01*
G01X635056Y297287D02*
X636204D01*
G01X627182D02*
X628330D01*
G01X628321Y297019D02*
X627192D01*
G01X636195D02*
X635066D01*
G01X628335Y295500D02*
X627177D01*
G01X636209D02*
X635051D01*
G01X635061Y295232D02*
X636200D01*
G01X627187D02*
X628326D01*
G01X638979Y294783D02*
X640156D01*
G01X635042D02*
X636219D01*
G01X631105D02*
X632282D01*
G01X627168D02*
X628345D01*
G01Y293799D02*
X627168D01*
G01X632282D02*
X631105D01*
G01X636219D02*
X635042D01*
G01X640156D02*
X638979D01*
G01X632263Y293350D02*
X631124D01*
G01X640137D02*
X638998D01*
G01X638988Y293082D02*
X640146D01*
G01X631114D02*
X632272D01*
G01X639003Y291563D02*
X640132D01*
G01X631129D02*
X632258D01*
G01X632267Y291295D02*
X631119D01*
G01X640141D02*
X638993D01*
G01X632249Y290846D02*
X631138D01*
G01X640123D02*
X639012D01*
G01Y289862D02*
X640123D01*
G01X631138D02*
X632249D01*
G01Y316437D02*
X631138D01*
G01X640123D02*
X639012D01*
G01X632249Y315452D02*
X631138D01*
G01X640123D02*
X639012D01*
G01X638993Y315003D02*
X640141D01*
G01X631119D02*
X632267D01*
G01X632258Y314736D02*
X631129D01*
G01X640132D02*
X639003D01*
G01X632272Y313216D02*
X631114D01*
G01X640146D02*
X638988D01*
G01X638998Y312948D02*
X640137D01*
G01X631124D02*
X632263D01*
G01X628345Y312500D02*
X627168D01*
G01X632282D02*
X631105D01*
G01X636219D02*
X635042D01*
G01X640156D02*
X638979D01*
G01X628345Y311515D02*
X627168D01*
G01X632282D02*
X631105D01*
G01X636219D02*
X635042D01*
G01X640156D02*
X638979D01*
G01X628326Y311066D02*
X627187D01*
G01X636200D02*
X635061D01*
G01X635051Y310799D02*
X636209D01*
G01X627177D02*
X628335D01*
G01X638964Y305104D02*
X638994Y306692D01*
G01X638974D02*
X638961Y306032D01*
G01X635027Y305104D02*
X635057Y306692D01*
G01X635037D02*
X635024Y306032D01*
G01X631090Y305104D02*
X631120Y306692D01*
G01X631100D02*
X631087Y306032D01*
G01X627153Y305104D02*
X627183Y306692D01*
G01X627163D02*
X627150Y306032D01*
G01X640195Y305191D02*
X640220Y306692D01*
G01X640202D02*
X640192Y306102D01*
G01X636258Y305191D02*
X636283Y306692D01*
G01X636265D02*
X636255Y306102D01*
G01X632321Y305191D02*
X632346Y306692D01*
G01X632328D02*
X632318Y306102D01*
G01X628384Y305191D02*
X628409Y306692D01*
G01X628391D02*
X628381Y306102D01*
G01X639003Y314736D02*
X638998Y312948D01*
G01X638988Y313216D02*
X638993Y315003D01*
G01X636209Y310799D02*
X636204Y309011D01*
G01X636195Y309279D02*
X636200Y311066D01*
G01X631129Y314736D02*
X631124Y312948D01*
G01X631114Y313216D02*
X631119Y315003D01*
G01X628335Y310799D02*
X628330Y309011D01*
G01X628321Y309279D02*
X628326Y311066D01*
G01X640156Y311515D02*
Y312500D01*
G01X640000Y316437D02*
Y315452D01*
G01X639134D02*
Y316437D01*
G01X638979Y312500D02*
Y311515D01*
G01X638347Y323228D02*
Y317618D01*
G01X636219Y312500D02*
Y311515D01*
G01X636063Y308563D02*
Y307578D01*
G01X635197D02*
Y308563D01*
G01X635042Y311515D02*
Y312500D01*
G01X633347Y323228D02*
Y317618D01*
G01X632282Y312500D02*
Y311515D01*
G01X632126Y316437D02*
Y315452D01*
G01X631260D02*
Y316437D01*
G01X631105Y311515D02*
Y312500D01*
G01X628345D02*
Y311515D01*
G01X628189Y308563D02*
Y307578D01*
G01X627323D02*
Y308563D01*
G01X627168Y311515D02*
Y312500D01*
G01X640141Y315003D02*
X640146Y313216D01*
G01X640137Y312948D02*
X640132Y314736D01*
G01X635061Y311066D02*
X635066Y309279D01*
G01X635056Y309011D02*
X635051Y310799D01*
G01X632267Y315003D02*
X632272Y313216D01*
G01X632263Y312948D02*
X632258Y314736D01*
G01X627187Y311066D02*
X627192Y309279D01*
G01X627182Y309011D02*
X627177Y310799D01*
G01X638942Y306102D02*
X638932Y306692D01*
G01X638914D02*
X638940Y305191D01*
G01X635005Y306102D02*
X634995Y306692D01*
G01X634977D02*
X635003Y305191D01*
G01X631068Y306102D02*
X631058Y306692D01*
G01X631040D02*
X631066Y305191D01*
G01X627131Y306102D02*
X627121Y306692D01*
G01X627103D02*
X627129Y305191D01*
G01X640173Y306032D02*
X640161Y306692D01*
G01X640140D02*
X640171Y305104D01*
G01X636236Y306032D02*
X636224Y306692D01*
G01X636203D02*
X636234Y305104D01*
G01X632299Y306032D02*
X632287Y306692D01*
G01X632266D02*
X632297Y305104D01*
G01X628362Y306032D02*
X628350Y306692D01*
G01X628329D02*
X628360Y305104D01*
G01X635066Y309279D02*
X636195D01*
G01X627192D02*
X628321D01*
G01X628330Y309011D02*
X627182D01*
G01X636204D02*
X635056D01*
G01X628312Y308563D02*
X627201D01*
G01X636186D02*
X635075D01*
G01X628312Y307578D02*
X627201D01*
G01X636186D02*
X635075D01*
G01X628381Y306102D02*
X627131D01*
G01X632318D02*
X631068D01*
G01X636255D02*
X635005D01*
G01X640192D02*
X638942D01*
G01X638961Y306032D02*
X640173D01*
G01X635024D02*
X636236D01*
G01X631087D02*
X632299D01*
G01X627150D02*
X628362D01*
G01X628371Y305806D02*
X627141D01*
G01X632308D02*
X631078D01*
G01X636245D02*
X635015D01*
G01X640182D02*
X638952D01*
G01X638940Y305191D02*
X640195D01*
G01X635003D02*
X636258D01*
G01X631066D02*
X632321D01*
G01X627129D02*
X628384D01*
G01X628360Y305104D02*
X627153D01*
G01X632297D02*
X631090D01*
G01X636234D02*
X635027D01*
G01X640171D02*
X638964D01*
G01X628371Y304822D02*
X627141D01*
G01X632308D02*
X631078D01*
G01X636245D02*
X635015D01*
G01X640182D02*
X638952D01*
G01X654252Y323228D02*
X638347D01*
G01X628357Y365315D02*
X627126D01*
G01X632294D02*
X631063D01*
G01X635492D02*
X634262D01*
G01X639429D02*
X638199D01*
G01X639429Y371346D02*
Y365315D01*
G01X638199D02*
Y371346D01*
G01X635492Y371597D02*
Y365315D01*
G01X634262D02*
Y373356D01*
G01X632294Y371346D02*
Y365315D01*
G01X631063D02*
Y371346D01*
G01X628357D02*
Y365315D01*
G01X627126D02*
Y371346D01*
G01X639922Y373105D02*
X640660Y373356D01*
G01X636723Y372351D02*
X635985Y372100D01*
G01Y373105D02*
X636723Y373356D01*
G01X628849Y373105D02*
X629587Y373356D01*
G01X640414Y372351D02*
X639922Y372100D01*
G01X629341Y372351D02*
X628849Y372100D01*
G01X640660Y373356D02*
X641644D01*
G01X634262D02*
X635492D01*
G01X636723D02*
X637707D01*
G01X629587D02*
X630571D01*
G01X625650D02*
X626634D01*
G01X626142Y372351D02*
X625650D01*
G01X630079D02*
X629341D01*
G01X637215D02*
X636723D01*
G01X641152D02*
X640414D01*
G01X639922Y372100D02*
X639675Y371848D01*
G01X639183Y372351D02*
X639922Y373105D01*
G01X635985Y372100D02*
X635492Y371597D01*
G01Y372602D02*
X635985Y373105D01*
G01X628849Y372100D02*
X628603Y371848D01*
G01X628111Y372351D02*
X628849Y373105D01*
G01X639675Y371848D02*
X639429Y371346D01*
G01X628603Y371848D02*
X628357Y371346D01*
G01X631801Y372602D02*
X632294Y371346D01*
G01X638199D02*
X637953Y371848D01*
G01X631063Y371346D02*
X630817Y371848D01*
G01X627126Y371346D02*
X626880Y371848D01*
G01X638445Y373105D02*
X639183Y372351D01*
G01X637953Y371848D02*
X637707Y372100D01*
G01X631309Y373105D02*
X631801Y372602D01*
G01X630817Y371848D02*
X630571Y372100D01*
G01X627372Y373105D02*
X628111Y372351D01*
G01X626880Y371848D02*
X626634Y372100D01*
G01X641644D02*
X641152Y372351D01*
G01X637707Y372100D02*
X637215Y372351D01*
G01X630571Y372100D02*
X630079Y372351D01*
G01X626634Y372100D02*
X626142Y372351D01*
G01X637707Y373356D02*
X638445Y373105D01*
G01X630571Y373356D02*
X631309Y373105D01*
G01X626634Y373356D02*
X627372Y373105D01*
G01X635492Y373356D02*
Y372602D01*
G01X641198Y988189D02*
G03Y996063I0J3937D01*
G01Y988189D02*
G03Y996063I0J3937D01*
G01X652825Y-7058D02*
X652714Y-7051D01*
G01X647402Y-6300D02*
G03X646614Y-7087I-1J-787D01*
G01X645233Y-6436D02*
G03X646008Y-7087I775J136D01*
G01X652323Y-6300D02*
G03X653111Y-5512I0J788D01*
G01X644548Y-4725D02*
G03X644233Y-4095I-788J0D01*
G01X648780Y-3544D02*
G03X649567Y-4331I787J0D01*
G01X653111Y-7087D02*
G03X653898Y-6300I0J787D01*
G01X646727Y-6830D02*
G03X647484Y-7646I787J-29D01*
G01X652009Y-7815D02*
G03X652825Y-7058I29J787D01*
G01X644457Y-6573D02*
G03X646008Y-7874I1551J274D01*
G01X653111D02*
G03X654685Y-6300I-1J1575D01*
G01X643805Y4694D02*
G03X643628Y2665I3700J-1345D01*
G01X643065Y4964D02*
G03X642852Y2527I4440J-1616D01*
G01X653504Y-6260D02*
X652717Y-7048D01*
G01X647274Y6338D02*
X648258Y7322D01*
G01X643805Y4694D02*
X644764Y7329D01*
G01X644024Y7598D02*
X643065Y4964D01*
G01X652825Y-7058D02*
X653898Y21610D01*
G01X647938Y25529D02*
X646727Y-6830D01*
G01X654685Y-6300D02*
Y85602D01*
G01X653898D02*
Y-6300D01*
G01X653504Y-6260D02*
Y86614D01*
G01X653111Y-5512D02*
Y85236D01*
G01X652717Y87176D02*
Y-7048D01*
G01X652550Y-2497D02*
Y3731D01*
G01X651801Y6338D02*
Y25629D01*
G01X648780Y-2497D02*
Y-3544D01*
G01X648455Y-4095D02*
Y60078D01*
G01X647482Y3731D02*
Y-2497D01*
G01X647402Y-7874D02*
Y-7376D01*
G01X647274Y6338D02*
Y25629D01*
G01X646713Y12637D02*
Y-7048D01*
G01X646614Y-7087D02*
Y-7874D01*
G01X646401Y-7087D02*
Y-7874D01*
G01X646008Y-7087D02*
Y-7874D01*
G01X645433Y10511D02*
Y-6260D01*
G01X645335Y-7087D02*
Y-7874D01*
G01X644548D02*
Y-4095D01*
G01X643760Y-7087D02*
Y-7874D01*
G01X643563Y-6841D02*
Y36653D01*
G01X643376Y16574D02*
Y-6654D01*
G01X645233Y-6436D02*
X643628Y2665D01*
G01X642852Y2527D02*
X644457Y-6573D01*
G01X651801Y6338D02*
X650817Y7322D01*
G01X646221Y-7048D02*
X645433Y-6260D01*
G01X643563D02*
X644351Y-7048D01*
G01X643376Y-6654D02*
X643770Y-7048D01*
G01X644495Y6589D02*
X643755Y6858D01*
G01X647274Y6338D02*
X651801D01*
G01X654685Y4330D02*
X653898D01*
G01X652550Y3731D02*
X647482D01*
G01X654685Y3543D02*
X652550D01*
G01X646727Y-6830D02*
X652825Y-7058D01*
G01X652609Y-7571D02*
X647402Y-7376D01*
G01X652009Y-7815D02*
X647484Y-7646D01*
G01X647482Y-2497D02*
X652550D01*
G01X649567Y-4331D02*
X654685D01*
G01Y-5119D02*
X653898D01*
G01Y-5512D02*
X654685D01*
G01Y-6300D02*
X653898D01*
G01X643563Y-6334D02*
X643638D01*
G01X651506Y19271D02*
G03I-1968J0D01*
G01X643376Y15787D02*
G03X642589Y16574I-787J0D01*
G01X651506Y9271D02*
G03I-1968J0D01*
G01X650817Y11653D02*
X651801Y12637D01*
G01X653278Y12933D02*
Y25334D01*
G01X650817Y30944D02*
Y7322D01*
G01X650620Y7854D02*
Y11397D01*
G01Y20413D02*
Y17854D01*
G01X650424Y16181D02*
Y8149D01*
G01Y20118D02*
Y18149D01*
G01X648652Y8149D02*
Y16181D01*
G01Y20118D02*
Y18149D01*
G01X648258Y7322D02*
Y30944D01*
G01X646122Y39409D02*
Y11259D01*
G01X645827Y11850D02*
Y39837D01*
G01X645798Y25334D02*
Y12933D01*
G01X645630Y12637D02*
Y25629D01*
G01X644843D02*
Y12637D01*
G01X647274D02*
X648258Y11653D01*
G01X644764Y7329D02*
X644024Y7598D01*
G01X647592Y16284D02*
X653690Y16056D01*
G01X650620Y20413D02*
X648455D01*
G01X650424Y20118D02*
X648652D01*
G01X650424Y18149D02*
X648652D01*
G01X650620Y17854D02*
X648455D01*
G01X650424Y16181D02*
X648652D01*
G01X650424Y14212D02*
X648652D01*
G01Y14166D02*
X650424D01*
G01X648652Y13228D02*
X650424D01*
G01X653278Y12933D02*
X645798D01*
G01X644843Y12637D02*
X647274D01*
G01X653504D02*
X651801D01*
G01X648455Y11397D02*
X650620D01*
G01X648652Y10905D02*
X650424D01*
G01X645433Y10511D02*
X643563D01*
G01X650620Y10413D02*
X648455D01*
G01X650424Y10118D02*
X648652D01*
G01Y9133D02*
X650424D01*
G01Y8149D02*
X648652D01*
G01X650620Y7854D02*
X648455D01*
G01X650817Y7322D02*
X648258D01*
G01X653898Y25306D02*
X653278Y25332D01*
G01X651506Y29133D02*
G03I-1968J0D01*
G01X647274Y25629D02*
X648258Y26614D01*
G01X650817Y30944D02*
X651801Y31929D01*
G01Y26614D02*
Y31929D01*
G01X650620Y26870D02*
Y30413D01*
G01X650059Y85472D02*
Y39409D01*
G01X648295Y39837D02*
Y44868D01*
G01X647402Y39837D02*
Y39409D01*
G01X647274Y31929D02*
Y26614D01*
G01X646713D02*
Y25629D01*
G01X643704Y44868D02*
Y39837D01*
G01X647274Y31929D02*
X648258Y30944D01*
G01X650817Y26614D02*
X651801Y25629D01*
G01X653153Y25334D02*
X647938Y25529D01*
G01X643704Y39837D02*
X648295D01*
G01X653898Y39765D02*
X654685D01*
G01Y39691D02*
X653898D01*
G01Y39566D02*
X654685D01*
G01X653898Y38958D02*
X654685D01*
G01X653898Y35261D02*
X654685D01*
G01X653898Y34035D02*
X654685D01*
G01Y33302D02*
X653898D01*
G01X647274Y31929D02*
X651801D01*
G01X650817Y30944D02*
X648258D01*
G01X650620Y30413D02*
X648455D01*
G01X650620Y27854D02*
X648455D01*
G01X650620Y26870D02*
X648455D01*
G01X650817Y26614D02*
X653504D01*
G01X648258D02*
X646713D01*
G01X651801Y25629D02*
X653504D01*
G01X645798Y25334D02*
X653278D01*
G01X648780Y52165D02*
G03X649567Y51377I788J0D01*
G01X657618Y44133D02*
G03I-3090J0D01*
G01X643023Y41683D02*
G03Y46583I-4086J2450D01*
G01X649863Y40196D02*
Y48070D01*
G01X648780Y58464D02*
Y52165D01*
G01X647402Y85472D02*
Y44868D01*
G01X647107D02*
Y48070D01*
G01X646811Y45979D02*
Y44868D01*
G01X646759D02*
Y45979D01*
G01X646713D02*
Y44868D01*
G01X646687Y45979D02*
Y44868D01*
G01X646614D02*
Y56397D01*
G01X646470Y44868D02*
Y45979D01*
G01X646444D02*
Y44868D01*
G01X646418Y45979D02*
Y44868D01*
G01X645433Y45979D02*
Y44868D01*
G01X645408D02*
Y45979D01*
G01X645381D02*
Y44868D01*
G01X645237D02*
Y56397D01*
G01X645164Y44868D02*
Y45979D01*
G01X645138D02*
Y44868D01*
G01X645092Y45979D02*
Y44868D01*
G01X645040Y45979D02*
Y44868D01*
G01X644449Y45979D02*
Y44868D01*
G01X643563Y40984D02*
Y40196D01*
G01X642677Y44601D02*
Y45979D01*
G01X642087D02*
Y44601D01*
G01X642034D02*
Y45979D01*
G01X641988D02*
Y44601D01*
G01X641963Y45979D02*
Y44601D01*
G01X641890D02*
Y56397D01*
G01X641746Y44601D02*
Y45979D01*
G01X641719D02*
Y44601D01*
G01X641693Y45979D02*
Y44601D01*
G01X646614Y56397D02*
X645237D01*
G01X646614Y55019D02*
X645237D01*
G01X646614Y54035D02*
X645237D01*
G01X649567Y51377D02*
X654685D01*
G01Y50590D02*
X653898D01*
G01Y49803D02*
X654685D01*
G01Y48622D02*
X653898D01*
G01Y47834D02*
X654685D01*
G01X646614Y46963D02*
X645237D01*
G01X654685Y46259D02*
X653898D01*
G01X647402Y45979D02*
X644449D01*
G01X654685Y45335D02*
X653898D01*
G01X648295Y44868D02*
X643704D01*
G01X653898Y42853D02*
X654685D01*
G01X653898Y41929D02*
X654685D01*
G01X643704Y40984D02*
X643563D01*
G01X649863D02*
X648295D01*
G01X654685Y40498D02*
X653898D01*
G01X654685Y40354D02*
X653898D01*
G01X649863Y40196D02*
X648295D01*
G01X653504Y73474D02*
G03X653898Y72792I788J0D01*
G01Y71428D02*
G03X653504Y72110I-787J0D01*
G01X652717Y73474D02*
G03X653504Y72110I1575J0D01*
G01X654685Y71428D02*
G03X653898Y72792I-1575J1D01*
G01X649567Y59252D02*
G03X648780Y58464I1J-788D01*
G01X644087Y68606D02*
X643549Y67965D01*
G01Y68698D02*
X644087Y69339D01*
G01X652767Y68503D02*
Y68700D01*
G01X652323Y56929D02*
Y85472D01*
G01X649863Y84685D02*
Y67362D01*
G01X647107Y84685D02*
Y67362D01*
G01X645532Y78693D02*
Y67362D01*
G01X644087Y69339D02*
Y68606D01*
G01X643549Y72271D02*
Y68698D01*
G01X643011Y67965D02*
Y72271D01*
G01X653504Y68937D02*
X652717Y69724D01*
G01X653898Y72699D02*
X654685D01*
G01X643011Y72271D02*
X643549D01*
G01X652717Y69724D02*
X652323D01*
G01X653898Y68700D02*
X654685D01*
G01X652717D02*
X653504D01*
G01X654685Y68503D02*
X652767D01*
G01X643549Y67965D02*
X643011D01*
G01X654685Y61023D02*
X652717D01*
G01X654685Y60826D02*
X653898D01*
G01X653504Y60078D02*
X648455D01*
G01X653898Y60039D02*
X654685D01*
G01Y59252D02*
X649567D01*
G01X653504Y56929D02*
X652323D01*
G01X653898Y85602D02*
G03X653111Y86389I-787J0D01*
G01X645729Y85433D02*
G03X646735Y85995I0J1181D01*
G01X645099Y80118D02*
G03I-1181J0D01*
G01X654685Y85602D02*
G03X653111Y87176I-1575J-1D01*
G01X645532Y81542D02*
G03Y78693I-1614J-1424D01*
G01X653504Y82677D02*
X652796Y82440D01*
G01X644670Y81086D02*
X644444Y80898D01*
G01X644670Y82215D02*
X644444Y82027D01*
G01X653715Y86106D02*
X654320Y86610D01*
G01X653111Y85078D02*
X652717Y84685D01*
G01X646862Y86274D02*
Y86831D01*
G01X646735Y87176D02*
Y86389D01*
G01X645729Y87176D02*
Y86389D01*
G01X645591Y79429D02*
Y80807D01*
G01X645532Y84685D02*
Y81542D01*
G01X645099Y80807D02*
Y79429D01*
G01X644803Y80807D02*
Y79429D01*
G01X644705Y82346D02*
Y81150D01*
G01X644670Y82215D02*
Y81086D01*
G01X644607Y79429D02*
Y80807D01*
G01X644508Y81331D02*
Y82459D01*
G01X644444Y82027D02*
Y80898D01*
G01X644410Y81963D02*
Y79429D01*
G01X643425D02*
Y81963D01*
G01X643391Y80898D02*
Y82027D01*
G01X643327Y82459D02*
Y81331D01*
G01X643229Y80807D02*
Y79429D01*
G01X643165Y81086D02*
Y82215D01*
G01X643130Y82346D02*
Y81150D01*
G01X643032Y80807D02*
Y79429D01*
G01X642737Y80807D02*
Y79429D01*
G01X642244Y80807D02*
Y79429D01*
G01X654685Y79133D02*
X653504Y82677D01*
G01X652717D02*
X653898Y79133D01*
G01X653504Y84685D02*
X652717Y85472D01*
G01X643391Y82027D02*
X643165Y82215D01*
G01X643391Y80898D02*
X643165Y81086D01*
G01X653504Y86614D02*
X652717D01*
G01Y85995D02*
X646735D01*
G01X652717Y85826D02*
X653504D01*
G01X654685Y85602D02*
X653898D01*
G01X654320Y85236D02*
X652717D01*
G01X653898Y84744D02*
X654685D01*
G01X652717Y82677D02*
X653504D01*
G01X643327Y82459D02*
X644508D01*
G01X654685Y82452D02*
X653898D01*
G01X654685Y81861D02*
X653898D01*
G01X644508Y81331D02*
X643327D01*
G01X642244Y80807D02*
X645591D01*
G01X643425Y79678D02*
X644410D01*
G01X642244Y79429D02*
X645591D01*
G01X654685Y79133D02*
X653898D01*
G01X653504Y78740D02*
X652717D01*
G01X654685Y78318D02*
X653898D01*
G01X654685Y77727D02*
X653898D01*
G01Y73831D02*
X654685D01*
G01Y73594D02*
X653898D01*
G01X654685Y73263D02*
X653898D01*
G01X655909Y299606D02*
X655921Y300266D01*
G01X655919Y301194D02*
X655888Y299606D01*
G01X651972D02*
X651984Y300266D01*
G01X651982Y301194D02*
X651951Y299606D01*
G01X648035D02*
X648047Y300266D01*
G01X648045Y301194D02*
X648014Y299606D01*
G01X654680D02*
X654690Y300197D01*
G01X654688Y301107D02*
X654663Y299606D01*
G01X650743D02*
X650753Y300197D01*
G01X650751Y301107D02*
X650725Y299606D01*
G01X646806D02*
X646816Y300197D01*
G01X646814Y301107D02*
X646788Y299606D01*
G01X655894Y293082D02*
X655889Y291295D01*
G01X655880Y291563D02*
X655885Y293350D01*
G01X650814Y297019D02*
X650809Y295232D01*
G01X650799Y295500D02*
X650804Y297287D01*
G01X648020Y293082D02*
X648015Y291295D01*
G01X648006Y291563D02*
X648011Y293350D01*
G01X655904Y293799D02*
Y294783D01*
G01X655748Y290846D02*
Y289862D01*
G01X654882Y290846D02*
Y289862D01*
G01X654727Y294783D02*
Y293799D01*
G01X651967Y294783D02*
Y293799D01*
G01X651811Y298720D02*
Y297736D01*
G01X650945Y298720D02*
Y297736D01*
G01X650790Y293799D02*
Y294783D01*
G01X648030Y293799D02*
Y294783D01*
G01X647874Y290846D02*
Y289862D01*
G01X647008Y290846D02*
Y289862D01*
G01X646853Y294783D02*
Y293799D01*
G01X654746Y293350D02*
X654751Y291563D01*
G01X654741Y291295D02*
X654736Y293082D01*
G01X651952Y297287D02*
X651957Y295500D01*
G01X651948Y295232D02*
X651943Y297019D01*
G01X655968Y299606D02*
X655943Y301107D01*
G01X655940Y300197D02*
X655950Y299606D01*
G01X652031D02*
X652006Y301107D01*
G01X652003Y300197D02*
X652013Y299606D01*
G01X654742D02*
X654712Y301194D01*
G01X654709Y300266D02*
X654722Y299606D01*
G01X650805D02*
X650775Y301194D01*
G01X650772Y300266D02*
X650785Y299606D01*
G01X644098D02*
X644110Y300266D01*
G01X644108Y301194D02*
X644077Y299606D01*
G01X642869D02*
X642879Y300197D01*
G01X642877Y301107D02*
X642851Y299606D01*
G01X642940Y297019D02*
X642935Y295232D01*
G01X642925Y295500D02*
X642930Y297287D01*
G01X644093Y294783D02*
Y293799D01*
G01X643937Y298720D02*
Y297736D01*
G01X643071Y298720D02*
Y297736D01*
G01X642916Y293799D02*
Y294783D01*
G01X646872Y293350D02*
X646877Y291563D01*
G01X646867Y291295D02*
X646862Y293082D01*
G01X644078Y297287D02*
X644083Y295500D01*
G01X644074Y295232D02*
X644069Y297019D01*
G01X648094Y299606D02*
X648069Y301107D01*
G01X648066Y300197D02*
X648076Y299606D01*
G01X644157D02*
X644132Y301107D01*
G01X644129Y300197D02*
X644139Y299606D01*
G01X646868D02*
X646838Y301194D01*
G01X646835Y300266D02*
X646848Y299606D01*
G01X642931D02*
X642901Y301194D01*
G01X642898Y300266D02*
X642911Y299606D01*
G01X654700Y301477D02*
X655930D01*
G01X650763D02*
X651993D01*
G01X646826D02*
X648056D01*
G01X642889D02*
X644119D01*
G01X654712Y301194D02*
X655919D01*
G01X650775D02*
X651982D01*
G01X646838D02*
X648045D01*
G01X642901D02*
X644108D01*
G01X644132Y301107D02*
X642877D01*
G01X652006D02*
X650751D01*
G01X648069D02*
X646814D01*
G01X655943D02*
X654688D01*
G01X654700Y300492D02*
X655930D01*
G01X650763D02*
X651993D01*
G01X646826D02*
X648056D01*
G01X642889D02*
X644119D01*
G01X644110Y300266D02*
X642898D01*
G01X651984D02*
X650772D01*
G01X648047D02*
X646835D01*
G01X655921D02*
X654709D01*
G01X654690Y300197D02*
X655940D01*
G01X650753D02*
X652003D01*
G01X646816D02*
X648066D01*
G01X642879D02*
X644129D01*
G01X644060Y298720D02*
X642949D01*
G01X651934D02*
X650823D01*
G01Y297736D02*
X651934D01*
G01X642949D02*
X644060D01*
G01X650804Y297287D02*
X651952D01*
G01X642930D02*
X644078D01*
G01X644069Y297019D02*
X642940D01*
G01X651943D02*
X650814D01*
G01X644083Y295500D02*
X642925D01*
G01X651957D02*
X650799D01*
G01X650809Y295232D02*
X651948D01*
G01X642935D02*
X644074D01*
G01X654727Y294783D02*
X655904D01*
G01X646853D02*
X648030D01*
G01X650790D02*
X651967D01*
G01X642916D02*
X644093D01*
G01Y293799D02*
X642916D01*
G01X648030D02*
X646853D01*
G01X651967D02*
X650790D01*
G01X655904D02*
X654727D01*
G01X648011Y293350D02*
X646872D01*
G01X655885D02*
X654746D01*
G01X654736Y293082D02*
X655894D01*
G01X646862D02*
X648020D01*
G01X654751Y291563D02*
X655880D01*
G01X646877D02*
X648006D01*
G01X648015Y291295D02*
X646867D01*
G01X655889D02*
X654741D01*
G01X647997Y290846D02*
X646886D01*
G01X655871D02*
X654760D01*
G01Y289862D02*
X655871D01*
G01X646886D02*
X647997D01*
G01X654712Y305104D02*
X654742Y306692D01*
G01X654722D02*
X654709Y306032D01*
G01X650775Y305104D02*
X650805Y306692D01*
G01X650785D02*
X650772Y306032D01*
G01X646838Y305104D02*
X646868Y306692D01*
G01X646848D02*
X646835Y306032D01*
G01X655943Y305191D02*
X655968Y306692D01*
G01X655950D02*
X655940Y306102D01*
G01X652006Y305191D02*
X652031Y306692D01*
G01X652013D02*
X652003Y306102D01*
G01X648069Y305191D02*
X648094Y306692D01*
G01X648076D02*
X648066Y306102D01*
G01X654751Y314736D02*
X654746Y312948D01*
G01X654736Y313216D02*
X654741Y315003D01*
G01X651957Y310799D02*
X651952Y309011D01*
G01X651943Y309279D02*
X651948Y311066D01*
G01X646877Y314736D02*
X646872Y312948D01*
G01X646862Y313216D02*
X646867Y315003D01*
G01X655904Y311515D02*
Y312500D01*
G01X655748Y316437D02*
Y315452D01*
G01X654882D02*
Y316437D01*
G01X654727Y312500D02*
Y311515D01*
G01X654252Y323228D02*
Y317618D01*
G01X651967Y312500D02*
Y311515D01*
G01X651811Y308563D02*
Y307578D01*
G01X650945D02*
Y308563D01*
G01X650790Y311515D02*
Y312500D01*
G01X648030Y311515D02*
Y312500D01*
G01X647874Y316437D02*
Y315452D01*
G01X647008D02*
Y316437D01*
G01X646853Y312500D02*
Y311515D01*
G01X655889Y315003D02*
X655894Y313216D01*
G01X655885Y312948D02*
X655880Y314736D01*
G01X650809Y311066D02*
X650814Y309279D01*
G01X650804Y309011D02*
X650799Y310799D01*
G01X648015Y315003D02*
X648020Y313216D01*
G01X648011Y312948D02*
X648006Y314736D01*
G01X654690Y306102D02*
X654680Y306692D01*
G01X654663D02*
X654688Y305191D01*
G01X650753Y306102D02*
X650743Y306692D01*
G01X650725D02*
X650751Y305191D01*
G01X655921Y306032D02*
X655909Y306692D01*
G01X655888D02*
X655919Y305104D01*
G01X651984Y306032D02*
X651972Y306692D01*
G01X651951D02*
X651982Y305104D01*
G01X647997Y316437D02*
X646886D01*
G01X655871D02*
X654760D01*
G01X647997Y315452D02*
X646886D01*
G01X655871D02*
X654760D01*
G01X654741Y315003D02*
X655889D01*
G01X646867D02*
X648015D01*
G01X648006Y314736D02*
X646877D01*
G01X655880D02*
X654751D01*
G01X648020Y313216D02*
X646862D01*
G01X655894D02*
X654736D01*
G01X654746Y312948D02*
X655885D01*
G01X646872D02*
X648011D01*
G01X644093Y312500D02*
X642916D01*
G01X648030D02*
X646853D01*
G01X651967D02*
X650790D01*
G01X655904D02*
X654727D01*
G01X644093Y311515D02*
X642916D01*
G01X648030D02*
X646853D01*
G01X651967D02*
X650790D01*
G01X655904D02*
X654727D01*
G01X644074Y311066D02*
X642935D01*
G01X651948D02*
X650809D01*
G01X650799Y310799D02*
X651957D01*
G01X642925D02*
X644083D01*
G01X642901Y305104D02*
X642931Y306692D01*
G01X642911D02*
X642898Y306032D01*
G01X644132Y305191D02*
X644157Y306692D01*
G01X644139D02*
X644129Y306102D01*
G01X644083Y310799D02*
X644078Y309011D01*
G01X644069Y309279D02*
X644074Y311066D01*
G01X644093Y312500D02*
Y311515D01*
G01X643937Y308563D02*
Y307578D01*
G01X643071D02*
Y308563D01*
G01X642916Y311515D02*
Y312500D01*
G01X642935Y311066D02*
X642940Y309279D01*
G01X642930Y309011D02*
X642925Y310799D01*
G01X646816Y306102D02*
X646806Y306692D01*
G01X646788D02*
X646814Y305191D01*
G01X642879Y306102D02*
X642869Y306692D01*
G01X642851D02*
X642877Y305191D01*
G01X648047Y306032D02*
X648035Y306692D01*
G01X648014D02*
X648045Y305104D01*
G01X644110Y306032D02*
X644098Y306692D01*
G01X644077D02*
X644108Y305104D01*
G01X650814Y309279D02*
X651943D01*
G01X642940D02*
X644069D01*
G01X644078Y309011D02*
X642930D01*
G01X651952D02*
X650804D01*
G01X644060Y308563D02*
X642949D01*
G01X651934D02*
X650823D01*
G01X644060Y307578D02*
X642949D01*
G01X651934D02*
X650823D01*
G01X644129Y306102D02*
X642879D01*
G01X652003D02*
X650753D01*
G01X648066D02*
X646816D01*
G01X655940D02*
X654690D01*
G01X654709Y306032D02*
X655921D01*
G01X650772D02*
X651984D01*
G01X646835D02*
X648047D01*
G01X642898D02*
X644110D01*
G01X644119Y305806D02*
X642889D01*
G01X651993D02*
X650763D01*
G01X648056D02*
X646826D01*
G01X655930D02*
X654700D01*
G01X654688Y305191D02*
X655943D01*
G01X650751D02*
X652006D01*
G01X646814D02*
X648069D01*
G01X642877D02*
X644132D01*
G01X644108Y305104D02*
X642901D01*
G01X651982D02*
X650775D01*
G01X648045D02*
X646838D01*
G01X655919D02*
X654712D01*
G01X644119Y304822D02*
X642889D01*
G01X651993D02*
X650763D01*
G01X648056D02*
X646826D01*
G01X655930D02*
X654700D01*
G01X643366Y365315D02*
X642136D01*
G01X643366Y371346D02*
Y365315D01*
G01X642136D02*
Y371346D01*
G01X642874Y372602D02*
X643366Y371346D01*
G01X642136D02*
X641890Y371848D01*
G01X642382Y373105D02*
X642874Y372602D01*
G01X641890Y371848D02*
X641644Y372100D01*
G01Y373356D02*
X642382Y373105D01*
G01X649684Y1008622D02*
G03X658266I4291J0D01*
G01D02*
G03X649684I-4291J0D01*
G01X671657Y299606D02*
X671669Y300266D01*
G01X671667Y301194D02*
X671636Y299606D01*
G01X667720D02*
X667732Y300266D01*
G01X667730Y301194D02*
X667699Y299606D01*
G01X663783D02*
X663795Y300266D01*
G01X663793Y301194D02*
X663762Y299606D01*
G01X659846D02*
X659858Y300266D01*
G01X659856Y301194D02*
X659825Y299606D01*
G01X674365D02*
X674375Y300197D01*
G01X674373Y301107D02*
X674348Y299606D01*
G01X670428D02*
X670438Y300197D01*
G01X670436Y301107D02*
X670411Y299606D01*
G01X666491D02*
X666501Y300197D01*
G01X666499Y301107D02*
X666474Y299606D01*
G01X662554D02*
X662564Y300197D01*
G01X662562Y301107D02*
X662537Y299606D01*
G01X658617D02*
X658627Y300197D01*
G01X658625Y301107D02*
X658600Y299606D01*
G01X674436Y297019D02*
X674431Y295232D01*
G01X674421Y295500D02*
X674426Y297287D01*
G01X671642Y293082D02*
X671637Y291295D01*
G01X671628Y291563D02*
X671633Y293350D01*
G01X666562Y297019D02*
X666557Y295232D01*
G01X666547Y295500D02*
X666552Y297287D01*
G01X663768Y293082D02*
X663763Y291295D01*
G01X663754Y291563D02*
X663759Y293350D01*
G01X658688Y297019D02*
X658683Y295232D01*
G01X658673Y295500D02*
X658678Y297287D01*
G01X674412Y293799D02*
Y294783D01*
G01X671652Y293799D02*
Y294783D01*
G01X671496Y290846D02*
Y289862D01*
G01X670630Y290846D02*
Y289862D01*
G01X670475Y294783D02*
Y293799D01*
G01X667715Y294783D02*
Y293799D01*
G01X667559Y298720D02*
Y297736D01*
G01X666693Y298720D02*
Y297736D01*
G01X666538Y293799D02*
Y294783D01*
G01X663778Y293799D02*
Y294783D01*
G01X663622Y290846D02*
Y289862D01*
G01X662756Y290846D02*
Y289862D01*
G01X662601Y294783D02*
Y293799D01*
G01X659841Y294783D02*
Y293799D01*
G01X659685Y298720D02*
Y297736D01*
G01X658819Y298720D02*
Y297736D01*
G01X658664Y293799D02*
Y294783D01*
G01X670494Y293350D02*
X670499Y291563D01*
G01X670489Y291295D02*
X670484Y293082D01*
G01X667700Y297287D02*
X667705Y295500D01*
G01X667696Y295232D02*
X667691Y297019D01*
G01X662620Y293350D02*
X662625Y291563D01*
G01X662615Y291295D02*
X662610Y293082D01*
G01X659826Y297287D02*
X659831Y295500D01*
G01X659822Y295232D02*
X659817Y297019D01*
G01X671716Y299606D02*
X671691Y301107D01*
G01X671688Y300197D02*
X671698Y299606D01*
G01X667779D02*
X667754Y301107D01*
G01X667751Y300197D02*
X667761Y299606D01*
G01X663842D02*
X663817Y301107D01*
G01X663814Y300197D02*
X663824Y299606D01*
G01X659905D02*
X659880Y301107D01*
G01X659877Y300197D02*
X659887Y299606D01*
G01X674427D02*
X674397Y301194D01*
G01X674394Y300266D02*
X674407Y299606D01*
G01X670490D02*
X670460Y301194D01*
G01X670457Y300266D02*
X670470Y299606D01*
G01X666553D02*
X666523Y301194D01*
G01X666520Y300266D02*
X666533Y299606D01*
G01X662616D02*
X662586Y301194D01*
G01X662583Y300266D02*
X662596Y299606D01*
G01X658679D02*
X658649Y301194D01*
G01X658646Y300266D02*
X658659Y299606D01*
G01X674385Y301477D02*
X675615D01*
G01X670448D02*
X671678D01*
G01X666511D02*
X667741D01*
G01X662574D02*
X663804D01*
G01X658637D02*
X659867D01*
G01X674397Y301194D02*
X675604D01*
G01X670460D02*
X671667D01*
G01X666523D02*
X667730D01*
G01X662586D02*
X663793D01*
G01X658649D02*
X659856D01*
G01X659880Y301107D02*
X658625D01*
G01X663817D02*
X662562D01*
G01X667754D02*
X666499D01*
G01X675628D02*
X674373D01*
G01X671691D02*
X670436D01*
G01X674385Y300492D02*
X675615D01*
G01X670448D02*
X671678D01*
G01X666511D02*
X667741D01*
G01X662574D02*
X663804D01*
G01X658637D02*
X659867D01*
G01X659858Y300266D02*
X658646D01*
G01X663795D02*
X662583D01*
G01X667732D02*
X666520D01*
G01X675606D02*
X674394D01*
G01X671669D02*
X670457D01*
G01X674375Y300197D02*
X675625D01*
G01X670438D02*
X671688D01*
G01X666501D02*
X667751D01*
G01X662564D02*
X663814D01*
G01X658627D02*
X659877D01*
G01X659808Y298720D02*
X658697D01*
G01X667682D02*
X666571D01*
G01Y297736D02*
X667682D01*
G01X658697D02*
X659808D01*
G01X674426Y297287D02*
X675574D01*
G01X666552D02*
X667700D01*
G01X658678D02*
X659826D01*
G01X659817Y297019D02*
X658688D01*
G01X667691D02*
X666562D01*
G01X659831Y295500D02*
X658673D01*
G01X667705D02*
X666547D01*
G01X675579D02*
X674421D01*
G01X674431Y295232D02*
X675570D01*
G01X666557D02*
X667696D01*
G01X658683D02*
X659822D01*
G01X670475Y294783D02*
X671652D01*
G01X674412D02*
X675589D01*
G01X666538D02*
X667715D01*
G01X662601D02*
X663778D01*
G01X658664D02*
X659841D01*
G01Y293799D02*
X658664D01*
G01X663778D02*
X662601D01*
G01X667715D02*
X666538D01*
G01X671652D02*
X670475D01*
G01X675589D02*
X674412D01*
G01X663759Y293350D02*
X662620D01*
G01X671633D02*
X670494D01*
G01X670484Y293082D02*
X671642D01*
G01X662610D02*
X663768D01*
G01X670499Y291563D02*
X671628D01*
G01X662625D02*
X663754D01*
G01X663763Y291295D02*
X662615D01*
G01X671637D02*
X670489D01*
G01X663745Y290846D02*
X662634D01*
G01X671619D02*
X670508D01*
G01Y289862D02*
X671619D01*
G01X662634D02*
X663745D01*
G01X674397Y305104D02*
X674427Y306692D01*
G01X674407D02*
X674394Y306032D01*
G01X670460Y305104D02*
X670490Y306692D01*
G01X670470D02*
X670457Y306032D01*
G01X666523Y305104D02*
X666553Y306692D01*
G01X666533D02*
X666520Y306032D01*
G01X662586Y305104D02*
X662616Y306692D01*
G01X662596D02*
X662583Y306032D01*
G01X658649Y305104D02*
X658679Y306692D01*
G01X658659D02*
X658646Y306032D01*
G01X671691Y305191D02*
X671716Y306692D01*
G01X671698D02*
X671688Y306102D01*
G01X667754Y305191D02*
X667779Y306692D01*
G01X667761D02*
X667751Y306102D01*
G01X663817Y305191D02*
X663842Y306692D01*
G01X663824D02*
X663814Y306102D01*
G01X659880Y305191D02*
X659905Y306692D01*
G01X659887D02*
X659877Y306102D01*
G01X670499Y314736D02*
X670494Y312948D01*
G01X670484Y313216D02*
X670489Y315003D01*
G01X667705Y310799D02*
X667700Y309011D01*
G01X667691Y309279D02*
X667696Y311066D01*
G01X662625Y314736D02*
X662620Y312948D01*
G01X662610Y313216D02*
X662615Y315003D01*
G01X659831Y310799D02*
X659826Y309011D01*
G01X659817Y309279D02*
X659822Y311066D01*
G01X674412Y311515D02*
Y312500D01*
G01X671652Y311515D02*
Y312500D01*
G01X671496Y316437D02*
Y315452D01*
G01X670630D02*
Y316437D01*
G01X670475Y312500D02*
Y311515D01*
G01X667715Y312500D02*
Y311515D01*
G01X667559Y308563D02*
Y307578D01*
G01X666693D02*
Y308563D01*
G01X666538Y311515D02*
Y312500D01*
G01X663778Y311515D02*
Y312500D01*
G01X663622Y316437D02*
Y315452D01*
G01X662756D02*
Y316437D01*
G01X662601Y312500D02*
Y311515D01*
G01X659841Y312500D02*
Y311515D01*
G01X659685Y308563D02*
Y307578D01*
G01X659252Y323228D02*
Y317618D01*
G01X658819Y307578D02*
Y308563D01*
G01X658664Y311515D02*
Y312500D01*
G01X674431Y311066D02*
X674436Y309279D01*
G01X674426Y309011D02*
X674421Y310799D01*
G01X671637Y315003D02*
X671642Y313216D01*
G01X671633Y312948D02*
X671628Y314736D01*
G01X666557Y311066D02*
X666562Y309279D01*
G01X666552Y309011D02*
X666547Y310799D01*
G01X663763Y315003D02*
X663768Y313216D01*
G01X663759Y312948D02*
X663754Y314736D01*
G01X658683Y311066D02*
X658688Y309279D01*
G01X658678Y309011D02*
X658673Y310799D01*
G01X674375Y306102D02*
X674365Y306692D01*
G01X674348D02*
X674373Y305191D01*
G01X670438Y306102D02*
X670428Y306692D01*
G01X670411D02*
X670436Y305191D01*
G01X666501Y306102D02*
X666491Y306692D01*
G01X666474D02*
X666499Y305191D01*
G01X662564Y306102D02*
X662554Y306692D01*
G01X662537D02*
X662562Y305191D01*
G01X658627Y306102D02*
X658617Y306692D01*
G01X658600D02*
X658625Y305191D01*
G01X671669Y306032D02*
X671657Y306692D01*
G01X671636D02*
X671667Y305104D01*
G01X667732Y306032D02*
X667720Y306692D01*
G01X667699D02*
X667730Y305104D01*
G01X663795Y306032D02*
X663783Y306692D01*
G01X663762D02*
X663793Y305104D01*
G01X659858Y306032D02*
X659846Y306692D01*
G01X659825D02*
X659856Y305104D01*
G01X663745Y316437D02*
X662634D01*
G01X671619D02*
X670508D01*
G01X663745Y315452D02*
X662634D01*
G01X671619D02*
X670508D01*
G01X670489Y315003D02*
X671637D01*
G01X662615D02*
X663763D01*
G01X663754Y314736D02*
X662625D01*
G01X671628D02*
X670499D01*
G01X663768Y313216D02*
X662610D01*
G01X671642D02*
X670484D01*
G01X670494Y312948D02*
X671633D01*
G01X662620D02*
X663759D01*
G01X659841Y312500D02*
X658664D01*
G01X663778D02*
X662601D01*
G01X667715D02*
X666538D01*
G01X675589D02*
X674412D01*
G01X671652D02*
X670475D01*
G01X659841Y311515D02*
X658664D01*
G01X663778D02*
X662601D01*
G01X667715D02*
X666538D01*
G01X675589D02*
X674412D01*
G01X671652D02*
X670475D01*
G01X659822Y311066D02*
X658683D01*
G01X667696D02*
X666557D01*
G01X675570D02*
X674431D01*
G01X674421Y310799D02*
X675579D01*
G01X666547D02*
X667705D01*
G01X658673D02*
X659831D01*
G01X666562Y309279D02*
X667691D01*
G01X658688D02*
X659817D01*
G01X659826Y309011D02*
X658678D01*
G01X667700D02*
X666552D01*
G01X675574D02*
X674426D01*
G01X659808Y308563D02*
X658697D01*
G01X667682D02*
X666571D01*
G01X659808Y307578D02*
X658697D01*
G01X667682D02*
X666571D01*
G01X659877Y306102D02*
X658627D01*
G01X663814D02*
X662564D01*
G01X667751D02*
X666501D01*
G01X675625D02*
X674375D01*
G01X671688D02*
X670438D01*
G01X674394Y306032D02*
X675606D01*
G01X670457D02*
X671669D01*
G01X666520D02*
X667732D01*
G01X662583D02*
X663795D01*
G01X658646D02*
X659858D01*
G01X659867Y305806D02*
X658637D01*
G01X663804D02*
X662574D01*
G01X667741D02*
X666511D01*
G01X675615D02*
X674385D01*
G01X671678D02*
X670448D01*
G01X674373Y305191D02*
X675628D01*
G01X670436D02*
X671691D01*
G01X666499D02*
X667754D01*
G01X662562D02*
X663817D01*
G01X658625D02*
X659880D01*
G01X659856Y305104D02*
X658649D01*
G01X663793D02*
X662586D01*
G01X667730D02*
X666523D01*
G01X675604D02*
X674397D01*
G01X671667D02*
X670460D01*
G01X659867Y304822D02*
X658637D01*
G01X663804D02*
X662574D01*
G01X667741D02*
X666511D01*
G01X675615D02*
X674385D01*
G01X671678D02*
X670448D01*
G01X675158Y323228D02*
X659252D01*
G01X666395Y996063D02*
G03Y988189I0J-3937D01*
G01Y996063D02*
G03Y988189I0J-3937D01*
G01X709253Y996063D02*
X666395D01*
G01X709253D02*
X666395D01*
G01X687405Y299606D02*
X687417Y300266D01*
G01X687415Y301194D02*
X687384Y299606D01*
G01X683468D02*
X683480Y300266D01*
G01X683478Y301194D02*
X683447Y299606D01*
G01X679531D02*
X679543Y300266D01*
G01X679541Y301194D02*
X679510Y299606D01*
G01X675594D02*
X675606Y300266D01*
G01X675604Y301194D02*
X675573Y299606D01*
G01X690113D02*
X690123Y300197D01*
G01X690121Y301107D02*
X690096Y299606D01*
G01X686176D02*
X686186Y300197D01*
G01X686184Y301107D02*
X686159Y299606D01*
G01X682239D02*
X682249Y300197D01*
G01X682247Y301107D02*
X682222Y299606D01*
G01X678302D02*
X678312Y300197D01*
G01X678310Y301107D02*
X678285Y299606D01*
G01X690184Y297019D02*
X690179Y295232D01*
G01X690169Y295500D02*
X690174Y297287D01*
G01X687390Y293082D02*
X687385Y291295D01*
G01X687376Y291563D02*
X687381Y293350D01*
G01X682310Y297019D02*
X682305Y295232D01*
G01X682295Y295500D02*
X682300Y297287D01*
G01X679516Y293082D02*
X679511Y291295D01*
G01X679502Y291563D02*
X679507Y293350D01*
G01X690315Y298720D02*
Y297736D01*
G01X690160Y294783D02*
Y293799D01*
G01X687400D02*
Y294783D01*
G01X687244Y290846D02*
Y289862D01*
G01X686378Y290846D02*
Y289862D01*
G01X686223Y294783D02*
Y293799D01*
G01X683463Y294783D02*
Y293799D01*
G01X683307Y298720D02*
Y297736D01*
G01X682441Y298720D02*
Y297736D01*
G01X682286Y293799D02*
Y294783D01*
G01X679526Y293799D02*
Y294783D01*
G01X679370Y290846D02*
Y289862D01*
G01X678504Y290846D02*
Y289862D01*
G01X678349Y294783D02*
Y293799D01*
G01X675589Y294783D02*
Y293799D01*
G01X675433Y298720D02*
Y297736D01*
G01X674567Y298720D02*
Y297736D01*
G01X686242Y293350D02*
X686247Y291563D01*
G01X686237Y291295D02*
X686232Y293082D01*
G01X683448Y297287D02*
X683453Y295500D01*
G01X683444Y295232D02*
X683439Y297019D01*
G01X678368Y293350D02*
X678373Y291563D01*
G01X678363Y291295D02*
X678358Y293082D01*
G01X675574Y297287D02*
X675579Y295500D01*
G01X675570Y295232D02*
X675565Y297019D01*
G01X687464Y299606D02*
X687439Y301107D01*
G01X687437Y300197D02*
X687446Y299606D01*
G01X683527D02*
X683502Y301107D01*
G01X683500Y300197D02*
X683509Y299606D01*
G01X679590D02*
X679565Y301107D01*
G01X679563Y300197D02*
X679572Y299606D01*
G01X675653D02*
X675628Y301107D01*
G01X675625Y300197D02*
X675635Y299606D01*
G01X690175D02*
X690145Y301194D01*
G01X690142Y300266D02*
X690155Y299606D01*
G01X686238D02*
X686208Y301194D01*
G01X686205Y300266D02*
X686218Y299606D01*
G01X682301D02*
X682271Y301194D01*
G01X682268Y300266D02*
X682281Y299606D01*
G01X678364D02*
X678334Y301194D01*
G01X678331Y300266D02*
X678344Y299606D01*
G01X690133Y301477D02*
X691363D01*
G01X686196D02*
X687426D01*
G01X682259D02*
X683489D01*
G01X678322D02*
X679552D01*
G01X690145Y301194D02*
X691352D01*
G01X686208D02*
X687415D01*
G01X682271D02*
X683478D01*
G01X678334D02*
X679541D01*
G01X679565Y301107D02*
X678310D01*
G01X683502D02*
X682247D01*
G01X687439D02*
X686184D01*
G01X691376D02*
X690121D01*
G01X690133Y300492D02*
X691363D01*
G01X686196D02*
X687426D01*
G01X682259D02*
X683489D01*
G01X678322D02*
X679552D01*
G01X679543Y300266D02*
X678331D01*
G01X683480D02*
X682268D01*
G01X687417D02*
X686205D01*
G01X691354D02*
X690142D01*
G01X690123Y300197D02*
X691374D01*
G01X686186D02*
X687437D01*
G01X682249D02*
X683500D01*
G01X678312D02*
X679563D01*
G01X675556Y298720D02*
X674445D01*
G01X683430D02*
X682319D01*
G01X691304D02*
X690193D01*
G01Y297736D02*
X691304D01*
G01X682319D02*
X683430D01*
G01X674445D02*
X675556D01*
G01X690174Y297287D02*
X691322D01*
G01X682300D02*
X683448D01*
G01X675565Y297019D02*
X674436D01*
G01X683439D02*
X682310D01*
G01X691313D02*
X690184D01*
G01X683453Y295500D02*
X682295D01*
G01X691327D02*
X690169D01*
G01X690179Y295232D02*
X691318D01*
G01X682305D02*
X683444D01*
G01X690160Y294783D02*
X691337D01*
G01X686223D02*
X687400D01*
G01X682286D02*
X683463D01*
G01X678349D02*
X679526D01*
G01Y293799D02*
X678349D01*
G01X683463D02*
X682286D01*
G01X687400D02*
X686223D01*
G01X691337D02*
X690160D01*
G01X679507Y293350D02*
X678368D01*
G01X687381D02*
X686242D01*
G01X686232Y293082D02*
X687390D01*
G01X678358D02*
X679516D01*
G01X686247Y291563D02*
X687376D01*
G01X678373D02*
X679502D01*
G01X679511Y291295D02*
X678363D01*
G01X687385D02*
X686237D01*
G01X679493Y290846D02*
X678382D01*
G01X687367D02*
X686256D01*
G01Y289862D02*
X687367D01*
G01X678382D02*
X679493D01*
G01X690145Y305104D02*
X690175Y306692D01*
G01X690155D02*
X690142Y306032D01*
G01X686208Y305104D02*
X686238Y306692D01*
G01X686218D02*
X686205Y306032D01*
G01X682271Y305104D02*
X682301Y306692D01*
G01X682281D02*
X682268Y306032D01*
G01X678334Y305104D02*
X678364Y306692D01*
G01X678344D02*
X678331Y306032D01*
G01X687439Y305191D02*
X687464Y306692D01*
G01X687446D02*
X687437Y306102D01*
G01X683502Y305191D02*
X683527Y306692D01*
G01X683509D02*
X683500Y306102D01*
G01X679565Y305191D02*
X679590Y306692D01*
G01X679572D02*
X679563Y306102D01*
G01X675628Y305191D02*
X675653Y306692D01*
G01X675635D02*
X675625Y306102D01*
G01X686247Y314736D02*
X686242Y312948D01*
G01X686232Y313216D02*
X686237Y315003D01*
G01X683453Y310799D02*
X683448Y309011D01*
G01X683439Y309279D02*
X683444Y311066D01*
G01X678373Y314736D02*
X678368Y312948D01*
G01X678358Y313216D02*
X678363Y315003D01*
G01X675579Y310799D02*
X675574Y309011D01*
G01X675565Y309279D02*
X675570Y311066D01*
G01X690315Y307578D02*
Y308563D01*
G01X690160Y311515D02*
Y312500D01*
G01X687400Y311515D02*
Y312500D01*
G01X687244Y316437D02*
Y315452D01*
G01X686378D02*
Y316437D01*
G01X686223Y312500D02*
Y311515D01*
G01X683463Y312500D02*
Y311515D01*
G01X683307Y308563D02*
Y307578D01*
G01X682441D02*
Y308563D01*
G01X682286Y311515D02*
Y312500D01*
G01X680158Y323228D02*
Y317618D01*
G01X679526Y311515D02*
Y312500D01*
G01X679370Y316437D02*
Y315452D01*
G01X678504D02*
Y316437D01*
G01X678349Y312500D02*
Y311515D01*
G01X675589Y312500D02*
Y311515D01*
G01X675433Y308563D02*
Y307578D01*
G01X675158Y323228D02*
Y317618D01*
G01X674567Y307578D02*
Y308563D01*
G01X690179Y311066D02*
X690184Y309279D01*
G01X690174Y309011D02*
X690169Y310799D01*
G01X687385Y315003D02*
X687390Y313216D01*
G01X687381Y312948D02*
X687376Y314736D01*
G01X682305Y311066D02*
X682310Y309279D01*
G01X682300Y309011D02*
X682295Y310799D01*
G01X679511Y315003D02*
X679516Y313216D01*
G01X679507Y312948D02*
X679502Y314736D01*
G01X690123Y306102D02*
X690113Y306692D01*
G01X690096D02*
X690121Y305191D01*
G01X686186Y306102D02*
X686176Y306692D01*
G01X686159D02*
X686184Y305191D01*
G01X682249Y306102D02*
X682239Y306692D01*
G01X682222D02*
X682247Y305191D01*
G01X678312Y306102D02*
X678302Y306692D01*
G01X678285D02*
X678310Y305191D01*
G01X687417Y306032D02*
X687405Y306692D01*
G01X687384D02*
X687415Y305104D01*
G01X683480Y306032D02*
X683468Y306692D01*
G01X683447D02*
X683478Y305104D01*
G01X679543Y306032D02*
X679531Y306692D01*
G01X679510D02*
X679541Y305104D01*
G01X675606Y306032D02*
X675594Y306692D01*
G01X675573D02*
X675604Y305104D01*
G01X679493Y316437D02*
X678382D01*
G01X687367D02*
X686256D01*
G01X679493Y315452D02*
X678382D01*
G01X687367D02*
X686256D01*
G01X686237Y315003D02*
X687385D01*
G01X678363D02*
X679511D01*
G01X679502Y314736D02*
X678373D01*
G01X687376D02*
X686247D01*
G01X679516Y313216D02*
X678358D01*
G01X687390D02*
X686232D01*
G01X686242Y312948D02*
X687381D01*
G01X678368D02*
X679507D01*
G01X679526Y312500D02*
X678349D01*
G01X683463D02*
X682286D01*
G01X687400D02*
X686223D01*
G01X691337D02*
X690160D01*
G01X679526Y311515D02*
X678349D01*
G01X683463D02*
X682286D01*
G01X687400D02*
X686223D01*
G01X691337D02*
X690160D01*
G01X683444Y311066D02*
X682305D01*
G01X691318D02*
X690179D01*
G01X690169Y310799D02*
X691327D01*
G01X682295D02*
X683453D01*
G01X690184Y309279D02*
X691313D01*
G01X682310D02*
X683439D01*
G01X674436D02*
X675565D01*
G01X683448Y309011D02*
X682300D01*
G01X691322D02*
X690174D01*
G01X675556Y308563D02*
X674445D01*
G01X683430D02*
X682319D01*
G01X691304D02*
X690193D01*
G01X675556Y307578D02*
X674445D01*
G01X683430D02*
X682319D01*
G01X691304D02*
X690193D01*
G01X679563Y306102D02*
X678312D01*
G01X683500D02*
X682249D01*
G01X687437D02*
X686186D01*
G01X691374D02*
X690123D01*
G01X690142Y306032D02*
X691354D01*
G01X686205D02*
X687417D01*
G01X682268D02*
X683480D01*
G01X678331D02*
X679543D01*
G01X679552Y305806D02*
X678322D01*
G01X683489D02*
X682259D01*
G01X687426D02*
X686196D01*
G01X691363D02*
X690133D01*
G01X690121Y305191D02*
X691376D01*
G01X686184D02*
X687439D01*
G01X682247D02*
X683502D01*
G01X678310D02*
X679565D01*
G01X679541Y305104D02*
X678334D01*
G01X683478D02*
X682271D01*
G01X687415D02*
X686208D01*
G01X691352D02*
X690145D01*
G01X679552Y304822D02*
X678322D01*
G01X683489D02*
X682259D01*
G01X687426D02*
X686196D01*
G01X691363D02*
X690133D01*
G01X696063Y323228D02*
X680158D01*
G01X707090Y299606D02*
X707102Y300266D01*
G01X707100Y301194D02*
X707069Y299606D01*
G01X703153D02*
X703165Y300266D01*
G01X703163Y301194D02*
X703132Y299606D01*
G01X699216D02*
X699228Y300266D01*
G01X699226Y301194D02*
X699195Y299606D01*
G01X695279D02*
X695291Y300266D01*
G01X695289Y301194D02*
X695258Y299606D01*
G01X691342D02*
X691354Y300266D01*
G01X691352Y301194D02*
X691321Y299606D01*
G01X705861D02*
X705871Y300197D01*
G01X705869Y301107D02*
X705844Y299606D01*
G01X701924D02*
X701934Y300197D01*
G01X701932Y301107D02*
X701907Y299606D01*
G01X697987D02*
X697997Y300197D01*
G01X697995Y301107D02*
X697970Y299606D01*
G01X694050D02*
X694060Y300197D01*
G01X694058Y301107D02*
X694033Y299606D01*
G01X705932Y297019D02*
X705927Y295232D01*
G01X705917Y295500D02*
X705922Y297287D01*
G01X703138Y293082D02*
X703133Y291295D01*
G01X703124Y291563D02*
X703129Y293350D01*
G01X698058Y297019D02*
X698053Y295232D01*
G01X698043Y295500D02*
X698048Y297287D01*
G01X695264Y293082D02*
X695259Y291295D01*
G01X695250Y291563D02*
X695255Y293350D01*
G01X707085Y294783D02*
Y293799D01*
G01X706929Y298720D02*
Y297736D01*
G01X706063Y298720D02*
Y297736D01*
G01X705908Y293799D02*
Y294783D01*
G01X703148Y293799D02*
Y294783D01*
G01X702992Y290846D02*
Y289862D01*
G01X702126Y290846D02*
Y289862D01*
G01X701971Y294783D02*
Y293799D01*
G01X699211Y294783D02*
Y293799D01*
G01X699055Y298720D02*
Y297736D01*
G01X698189Y298720D02*
Y297736D01*
G01X698034Y293799D02*
Y294783D01*
G01X695274Y293799D02*
Y294783D01*
G01X695118Y290846D02*
Y289862D01*
G01X694252Y290846D02*
Y289862D01*
G01X694097Y294783D02*
Y293799D01*
G01X691337D02*
Y294783D01*
G01X691181Y298720D02*
Y297736D01*
G01X707070Y297287D02*
X707075Y295500D01*
G01X707066Y295232D02*
X707061Y297019D01*
G01X701990Y293350D02*
X701995Y291563D01*
G01X701985Y291295D02*
X701980Y293082D01*
G01X699196Y297287D02*
X699201Y295500D01*
G01X699192Y295232D02*
X699187Y297019D01*
G01X694116Y293350D02*
X694121Y291563D01*
G01X694111Y291295D02*
X694106Y293082D01*
G01X691322Y297287D02*
X691327Y295500D01*
G01X691318Y295232D02*
X691313Y297019D01*
G01X707149Y299606D02*
X707124Y301107D01*
G01X707122Y300197D02*
X707131Y299606D01*
G01X703212D02*
X703187Y301107D01*
G01X703185Y300197D02*
X703194Y299606D01*
G01X699275D02*
X699250Y301107D01*
G01X699248Y300197D02*
X699257Y299606D01*
G01X695338D02*
X695313Y301107D01*
G01X695311Y300197D02*
X695320Y299606D01*
G01X691401D02*
X691376Y301107D01*
G01X691374Y300197D02*
X691383Y299606D01*
G01X705924D02*
X705893Y301194D01*
G01X705890Y300266D02*
X705903Y299606D01*
G01X701987D02*
X701956Y301194D01*
G01X701953Y300266D02*
X701966Y299606D01*
G01X698050D02*
X698019Y301194D01*
G01X698016Y300266D02*
X698029Y299606D01*
G01X694113D02*
X694082Y301194D01*
G01X694079Y300266D02*
X694092Y299606D01*
G01X705881Y301477D02*
X707111D01*
G01X698007D02*
X699237D01*
G01X701944D02*
X703174D01*
G01X694070D02*
X695300D01*
G01X705893Y301194D02*
X707100D01*
G01X698019D02*
X699226D01*
G01X701956D02*
X703163D01*
G01X694082D02*
X695289D01*
G01X695313Y301107D02*
X694058D01*
G01X699250D02*
X697995D01*
G01X703187D02*
X701932D01*
G01X707124D02*
X705869D01*
G01X705881Y300492D02*
X707111D01*
G01X698007D02*
X699237D01*
G01X701944D02*
X703174D01*
G01X694070D02*
X695300D01*
G01X695291Y300266D02*
X694079D01*
G01X699228D02*
X698016D01*
G01X703165D02*
X701953D01*
G01X707102D02*
X705890D01*
G01X705871Y300197D02*
X707122D01*
G01X697997D02*
X699248D01*
G01X701934D02*
X703185D01*
G01X694060D02*
X695311D01*
G01X699178Y298720D02*
X698067D01*
G01X707052D02*
X705941D01*
G01Y297736D02*
X707052D01*
G01X698067D02*
X699178D01*
G01X705922Y297287D02*
X707070D01*
G01X698048D02*
X699196D01*
G01X699187Y297019D02*
X698058D01*
G01X707061D02*
X705932D01*
G01X699201Y295500D02*
X698043D01*
G01X707075D02*
X705917D01*
G01X705927Y295232D02*
X707066D01*
G01X698053D02*
X699192D01*
G01X705908Y294783D02*
X707085D01*
G01X701971D02*
X703148D01*
G01X698034D02*
X699211D01*
G01X694097D02*
X695274D01*
G01Y293799D02*
X694097D01*
G01X703148D02*
X701971D01*
G01X699211D02*
X698034D01*
G01X707085D02*
X705908D01*
G01X695255Y293350D02*
X694116D01*
G01X703129D02*
X701990D01*
G01X701980Y293082D02*
X703138D01*
G01X694106D02*
X695264D01*
G01X701995Y291563D02*
X703124D01*
G01X694121D02*
X695250D01*
G01X695259Y291295D02*
X694111D01*
G01X703133D02*
X701985D01*
G01X695241Y290846D02*
X694130D01*
G01X703115D02*
X702004D01*
G01Y289862D02*
X703115D01*
G01X694130D02*
X695241D01*
G01X707124Y305191D02*
X707149Y306692D01*
G01X707131D02*
X707122Y306102D01*
G01X705893Y305104D02*
X705924Y306692D01*
G01X705903D02*
X705890Y306032D01*
G01X701956Y305104D02*
X701987Y306692D01*
G01X701966D02*
X701953Y306032D01*
G01X698019Y305104D02*
X698050Y306692D01*
G01X698029D02*
X698016Y306032D01*
G01X694082Y305104D02*
X694113Y306692D01*
G01X694092D02*
X694079Y306032D01*
G01X703187Y305191D02*
X703212Y306692D01*
G01X703194D02*
X703185Y306102D01*
G01X699250Y305191D02*
X699275Y306692D01*
G01X699257D02*
X699248Y306102D01*
G01X695313Y305191D02*
X695338Y306692D01*
G01X695320D02*
X695311Y306102D01*
G01X691376Y305191D02*
X691401Y306692D01*
G01X691383D02*
X691374Y306102D01*
G01X707075Y310799D02*
X707070Y309011D01*
G01X707061Y309279D02*
X707066Y311066D01*
G01X701995Y314736D02*
X701990Y312948D01*
G01X701980Y313216D02*
X701985Y315003D01*
G01X699201Y310799D02*
X699196Y309011D01*
G01X699187Y309279D02*
X699192Y311066D01*
G01X694121Y314736D02*
X694116Y312948D01*
G01X694106Y313216D02*
X694111Y315003D01*
G01X691327Y310799D02*
X691322Y309011D01*
G01X691313Y309279D02*
X691318Y311066D01*
G01X707085Y312500D02*
Y311515D01*
G01X706929Y308563D02*
Y307578D01*
G01X706063D02*
Y308563D01*
G01X705908Y311515D02*
Y312500D01*
G01X703148Y311515D02*
Y312500D01*
G01X702992Y316437D02*
Y315452D01*
G01X702126D02*
Y316437D01*
G01X701971Y312500D02*
Y311515D01*
G01X701063Y323228D02*
Y317618D01*
G01X699211Y312500D02*
Y311515D01*
G01X699055Y308563D02*
Y307578D01*
G01X698189D02*
Y308563D01*
G01X698034Y311515D02*
Y312500D01*
G01X696063Y323228D02*
Y317618D01*
G01X695274Y311515D02*
Y312500D01*
G01X695118Y316437D02*
Y315452D01*
G01X694252D02*
Y316437D01*
G01X694097Y312500D02*
Y311515D01*
G01X691337Y312500D02*
Y311515D01*
G01X691181Y308563D02*
Y307578D01*
G01X705927Y311066D02*
X705932Y309279D01*
G01X705922Y309011D02*
X705917Y310799D01*
G01X703133Y315003D02*
X703138Y313216D01*
G01X703129Y312948D02*
X703124Y314736D01*
G01X698053Y311066D02*
X698058Y309279D01*
G01X698048Y309011D02*
X698043Y310799D01*
G01X695259Y315003D02*
X695264Y313216D01*
G01X695255Y312948D02*
X695250Y314736D01*
G01X705871Y306102D02*
X705861Y306692D01*
G01X705844D02*
X705869Y305191D01*
G01X701934Y306102D02*
X701924Y306692D01*
G01X701907D02*
X701932Y305191D01*
G01X697997Y306102D02*
X697987Y306692D01*
G01X697970D02*
X697995Y305191D01*
G01X694060Y306102D02*
X694050Y306692D01*
G01X694033D02*
X694058Y305191D01*
G01X707102Y306032D02*
X707090Y306692D01*
G01X707069D02*
X707100Y305104D01*
G01X703165Y306032D02*
X703153Y306692D01*
G01X703132D02*
X703163Y305104D01*
G01X699228Y306032D02*
X699216Y306692D01*
G01X699195D02*
X699226Y305104D01*
G01X695291Y306032D02*
X695279Y306692D01*
G01X695258D02*
X695289Y305104D01*
G01X691354Y306032D02*
X691342Y306692D01*
G01X691321D02*
X691352Y305104D01*
G01X695241Y316437D02*
X694130D01*
G01X703115D02*
X702004D01*
G01X695241Y315452D02*
X694130D01*
G01X703115D02*
X702004D01*
G01X701985Y315003D02*
X703133D01*
G01X694111D02*
X695259D01*
G01X695250Y314736D02*
X694121D01*
G01X703124D02*
X701995D01*
G01X695264Y313216D02*
X694106D01*
G01X703138D02*
X701980D01*
G01X701990Y312948D02*
X703129D01*
G01X694116D02*
X695255D01*
G01X695274Y312500D02*
X694097D01*
G01X703148D02*
X701971D01*
G01X699211D02*
X698034D01*
G01X707085D02*
X705908D01*
G01X695274Y311515D02*
X694097D01*
G01X703148D02*
X701971D01*
G01X699211D02*
X698034D01*
G01X707085D02*
X705908D01*
G01X699192Y311066D02*
X698053D01*
G01X707066D02*
X705927D01*
G01X705917Y310799D02*
X707075D01*
G01X698043D02*
X699201D01*
G01X705932Y309279D02*
X707061D01*
G01X698058D02*
X699187D01*
G01X699196Y309011D02*
X698048D01*
G01X707070D02*
X705922D01*
G01X699178Y308563D02*
X698067D01*
G01X707052D02*
X705941D01*
G01X699178Y307578D02*
X698067D01*
G01X707052D02*
X705941D01*
G01X695311Y306102D02*
X694060D01*
G01X699248D02*
X697997D01*
G01X703185D02*
X701934D01*
G01X707122D02*
X705871D01*
G01X705890Y306032D02*
X707102D01*
G01X698016D02*
X699228D01*
G01X701953D02*
X703165D01*
G01X694079D02*
X695291D01*
G01X695300Y305806D02*
X694070D01*
G01X699237D02*
X698007D01*
G01X703174D02*
X701944D01*
G01X707111D02*
X705881D01*
G01X705869Y305191D02*
X707124D01*
G01X697995D02*
X699250D01*
G01X701932D02*
X703187D01*
G01X694058D02*
X695313D01*
G01X695289Y305104D02*
X694082D01*
G01X699226D02*
X698019D01*
G01X703163D02*
X701956D01*
G01X707100D02*
X705893D01*
G01X695300Y304822D02*
X694070D01*
G01X699237D02*
X698007D01*
G01X703174D02*
X701944D01*
G01X707111D02*
X705881D01*
G01X716969Y323228D02*
X701063D01*
G01X722500Y19072D02*
Y13543D01*
G01Y25354D02*
Y20579D01*
G01X721024Y13543D02*
Y25354D01*
G01X722500Y20579D02*
X729390D01*
G01Y19072D02*
X722500D01*
G01Y13543D02*
X721024D01*
G01Y25354D02*
X722500D01*
G01X722838Y299606D02*
X722850Y300266D01*
G01X722848Y301194D02*
X722817Y299606D01*
G01X718901D02*
X718913Y300266D01*
G01X718911Y301194D02*
X718880Y299606D01*
G01X714964D02*
X714976Y300266D01*
G01X714974Y301194D02*
X714943Y299606D01*
G01X711027D02*
X711039Y300266D01*
G01X711037Y301194D02*
X711006Y299606D01*
G01X721609D02*
X721619Y300197D01*
G01X721617Y301107D02*
X721592Y299606D01*
G01X717672D02*
X717682Y300197D01*
G01X717680Y301107D02*
X717655Y299606D01*
G01X713735D02*
X713745Y300197D01*
G01X713743Y301107D02*
X713718Y299606D01*
G01X709798D02*
X709808Y300197D01*
G01X709806Y301107D02*
X709781Y299606D01*
G01X721680Y297019D02*
X721675Y295232D01*
G01X721665Y295500D02*
X721670Y297287D01*
G01X718887Y293082D02*
X718881Y291295D01*
G01X718872Y291563D02*
X718877Y293350D01*
G01X713806Y297019D02*
X713801Y295232D01*
G01X713791Y295500D02*
X713796Y297287D01*
G01X711013Y293082D02*
X711007Y291295D01*
G01X710998Y291563D02*
X711003Y293350D01*
G01X722833Y294783D02*
Y293799D01*
G01X722677Y298720D02*
Y297736D01*
G01X721811Y298720D02*
Y297736D01*
G01X721656Y293799D02*
Y294783D01*
G01X718896Y293799D02*
Y294783D01*
G01X718740Y290846D02*
Y289862D01*
G01X717874Y290846D02*
Y289862D01*
G01X717719Y294783D02*
Y293799D01*
G01X714959Y294783D02*
Y293799D01*
G01X714803Y298720D02*
Y297736D01*
G01X713937Y298720D02*
Y297736D01*
G01X713782Y293799D02*
Y294783D01*
G01X711022Y293799D02*
Y294783D01*
G01X710866Y290846D02*
Y289862D01*
G01X710000Y290846D02*
Y289862D01*
G01X709845Y294783D02*
Y293799D01*
G01X722818Y297287D02*
X722824Y295500D01*
G01X722814Y295232D02*
X722809Y297019D01*
G01X717738Y293350D02*
X717743Y291563D01*
G01X717733Y291295D02*
X717728Y293082D01*
G01X714944Y297287D02*
X714950Y295500D01*
G01X714940Y295232D02*
X714935Y297019D01*
G01X709864Y293350D02*
X709869Y291563D01*
G01X709859Y291295D02*
X709854Y293082D01*
G01X722897Y299606D02*
X722872Y301107D01*
G01X722870Y300197D02*
X722879Y299606D01*
G01X718960D02*
X718935Y301107D01*
G01X718933Y300197D02*
X718942Y299606D01*
G01X715023D02*
X714998Y301107D01*
G01X714996Y300197D02*
X715005Y299606D01*
G01X711086D02*
X711061Y301107D01*
G01X711059Y300197D02*
X711068Y299606D01*
G01X721672D02*
X721641Y301194D01*
G01X721638Y300266D02*
X721651Y299606D01*
G01X717735D02*
X717704Y301194D01*
G01X717701Y300266D02*
X717714Y299606D01*
G01X713798D02*
X713767Y301194D01*
G01X713764Y300266D02*
X713777Y299606D01*
G01X709861D02*
X709830Y301194D01*
G01X709827Y300266D02*
X709840Y299606D01*
G01X721629Y301477D02*
X722859D01*
G01X717692D02*
X718922D01*
G01X713755D02*
X714985D01*
G01X709818D02*
X711048D01*
G01X721641Y301194D02*
X722848D01*
G01X717704D02*
X718911D01*
G01X713767D02*
X714974D01*
G01X709830D02*
X711037D01*
G01X711061Y301107D02*
X709806D01*
G01X714998D02*
X713743D01*
G01X718935D02*
X717680D01*
G01X722872D02*
X721617D01*
G01X721629Y300492D02*
X722859D01*
G01X717692D02*
X718922D01*
G01X713755D02*
X714985D01*
G01X709818D02*
X711048D01*
G01X711039Y300266D02*
X709827D01*
G01X714976D02*
X713764D01*
G01X718913D02*
X717701D01*
G01X722850D02*
X721638D01*
G01X721619Y300197D02*
X722870D01*
G01X717682D02*
X718933D01*
G01X713745D02*
X714996D01*
G01X709808D02*
X711059D01*
G01X714926Y298720D02*
X713815D01*
G01X722800D02*
X721689D01*
G01Y297736D02*
X722800D01*
G01X713815D02*
X714926D01*
G01X721670Y297287D02*
X722818D01*
G01X713796D02*
X714944D01*
G01X714935Y297019D02*
X713806D01*
G01X722809D02*
X721680D01*
G01X714950Y295500D02*
X713791D01*
G01X722824D02*
X721665D01*
G01X721675Y295232D02*
X722814D01*
G01X713801D02*
X714940D01*
G01X721656Y294783D02*
X722833D01*
G01X717719D02*
X718896D01*
G01X713782D02*
X714959D01*
G01X709845D02*
X711022D01*
G01Y293799D02*
X709845D01*
G01X714959D02*
X713782D01*
G01X718896D02*
X717719D01*
G01X722833D02*
X721656D01*
G01X711003Y293350D02*
X709864D01*
G01X718877D02*
X717738D01*
G01X717728Y293082D02*
X718887D01*
G01X709854D02*
X711013D01*
G01X717743Y291563D02*
X718872D01*
G01X709869D02*
X710998D01*
G01X711007Y291295D02*
X709859D01*
G01X718881D02*
X717733D01*
G01X710989Y290846D02*
X709878D01*
G01X718863D02*
X717752D01*
G01Y289862D02*
X718863D01*
G01X709878D02*
X710989D01*
G01X721641Y305104D02*
X721672Y306692D01*
G01X721651D02*
X721638Y306032D01*
G01X717704Y305104D02*
X717735Y306692D01*
G01X717714D02*
X717701Y306032D01*
G01X713767Y305104D02*
X713798Y306692D01*
G01X713777D02*
X713764Y306032D01*
G01X709830Y305104D02*
X709861Y306692D01*
G01X709840D02*
X709827Y306032D01*
G01X722872Y305191D02*
X722897Y306692D01*
G01X722879D02*
X722870Y306102D01*
G01X718935Y305191D02*
X718960Y306692D01*
G01X718942D02*
X718933Y306102D01*
G01X714998Y305191D02*
X715023Y306692D01*
G01X715005D02*
X714996Y306102D01*
G01X711061Y305191D02*
X711086Y306692D01*
G01X711068D02*
X711059Y306102D01*
G01X722824Y310799D02*
X722818Y309011D01*
G01X722809Y309279D02*
X722814Y311066D01*
G01X717743Y314736D02*
X717738Y312948D01*
G01X717728Y313216D02*
X717733Y315003D01*
G01X714950Y310799D02*
X714944Y309011D01*
G01X714935Y309279D02*
X714940Y311066D01*
G01X709869Y314736D02*
X709864Y312948D01*
G01X709854Y313216D02*
X709859Y315003D01*
G01X722833Y312500D02*
Y311515D01*
G01X722677Y308563D02*
Y307578D01*
G01X721969Y323228D02*
Y317618D01*
G01X721811Y307578D02*
Y308563D01*
G01X721656Y311515D02*
Y312500D01*
G01X718896Y311515D02*
Y312500D01*
G01X718740Y316437D02*
Y315452D01*
G01X717874D02*
Y316437D01*
G01X717719Y312500D02*
Y311515D01*
G01X716969Y323228D02*
Y317618D01*
G01X714959Y312500D02*
Y311515D01*
G01X714803Y308563D02*
Y307578D01*
G01X713937D02*
Y308563D01*
G01X713782Y311515D02*
Y312500D01*
G01X711022Y311515D02*
Y312500D01*
G01X710866Y316437D02*
Y315452D01*
G01X710000D02*
Y316437D01*
G01X709845Y312500D02*
Y311515D01*
G01X721675Y311066D02*
X721680Y309279D01*
G01X721670Y309011D02*
X721665Y310799D01*
G01X718881Y315003D02*
X718887Y313216D01*
G01X718877Y312948D02*
X718872Y314736D01*
G01X713801Y311066D02*
X713806Y309279D01*
G01X713796Y309011D02*
X713791Y310799D01*
G01X711007Y315003D02*
X711013Y313216D01*
G01X711003Y312948D02*
X710998Y314736D01*
G01X721619Y306102D02*
X721609Y306692D01*
G01X721592D02*
X721617Y305191D01*
G01X717682Y306102D02*
X717672Y306692D01*
G01X717655D02*
X717680Y305191D01*
G01X713745Y306102D02*
X713735Y306692D01*
G01X713718D02*
X713743Y305191D01*
G01X722850Y306032D02*
X722838Y306692D01*
G01X722817D02*
X722848Y305104D01*
G01X718913Y306032D02*
X718901Y306692D01*
G01X718880D02*
X718911Y305104D01*
G01X714976Y306032D02*
X714964Y306692D01*
G01X714943D02*
X714974Y305104D01*
G01X711039Y306032D02*
X711027Y306692D01*
G01X711006D02*
X711037Y305104D01*
G01X709808Y306102D02*
X709798Y306692D01*
G01X709781D02*
X709806Y305191D01*
G01X710989Y316437D02*
X709878D01*
G01X718863D02*
X717752D01*
G01X710989Y315452D02*
X709878D01*
G01X718863D02*
X717752D01*
G01X717733Y315003D02*
X718881D01*
G01X709859D02*
X711007D01*
G01X710998Y314736D02*
X709869D01*
G01X718872D02*
X717743D01*
G01X711013Y313216D02*
X709854D01*
G01X718887D02*
X717728D01*
G01X717738Y312948D02*
X718877D01*
G01X709864D02*
X711003D01*
G01X711022Y312500D02*
X709845D01*
G01X714959D02*
X713782D01*
G01X718896D02*
X717719D01*
G01X722833D02*
X721656D01*
G01X711022Y311515D02*
X709845D01*
G01X714959D02*
X713782D01*
G01X718896D02*
X717719D01*
G01X722833D02*
X721656D01*
G01X714940Y311066D02*
X713801D01*
G01X722814D02*
X721675D01*
G01X721665Y310799D02*
X722824D01*
G01X713791D02*
X714950D01*
G01X721680Y309279D02*
X722809D01*
G01X713806D02*
X714935D01*
G01X714944Y309011D02*
X713796D01*
G01X722818D02*
X721670D01*
G01X714926Y308563D02*
X713815D01*
G01X722800D02*
X721689D01*
G01X714926Y307578D02*
X713815D01*
G01X722800D02*
X721689D01*
G01X711059Y306102D02*
X709808D01*
G01X714996D02*
X713745D01*
G01X718933D02*
X717682D01*
G01X722870D02*
X721619D01*
G01X721638Y306032D02*
X722850D01*
G01X717701D02*
X718913D01*
G01X713764D02*
X714976D01*
G01X709827D02*
X711039D01*
G01X711048Y305806D02*
X709818D01*
G01X714985D02*
X713755D01*
G01X718922D02*
X717692D01*
G01X722859D02*
X721629D01*
G01X721617Y305191D02*
X722872D01*
G01X717680D02*
X718935D01*
G01X713743D02*
X714998D01*
G01X709806D02*
X711061D01*
G01X711037Y305104D02*
X709830D01*
G01X714974D02*
X713767D01*
G01X718911D02*
X717704D01*
G01X722848D02*
X721641D01*
G01X711048Y304822D02*
X709818D01*
G01X714985D02*
X713755D01*
G01X718922D02*
X717692D01*
G01X722859D02*
X721629D01*
G01X719292Y429133D02*
Y324212D01*
G01X737874Y323228D02*
X721969D01*
G01X719292Y403883D02*
X744542Y429133D01*
G01X713189Y988189D02*
G03X717126Y992126I0J3937D01*
G01Y1018109D02*
Y992126D01*
G01X713189Y988189D02*
G03X717126Y992126I0J3937D01*
G01Y1021653D02*
Y992126D01*
G01X709253Y1023622D02*
Y996063D01*
G01Y1023622D02*
Y996063D01*
G01X721063Y1001574D02*
X718307D01*
G01X725000D02*
X722244D01*
G01D02*
Y1014173D01*
G01X721063Y1018110D02*
Y1001574D01*
G01X718307D02*
Y1018110D01*
G01X717127Y1021653D02*
X717126Y1018109D01*
G01X743505Y1023622D02*
X719095D01*
G01D02*
X717127Y1021653D01*
G01X743504Y1023622D02*
X719095D01*
G01X718307Y1018110D02*
X721063D01*
G01X745473D02*
X717126D01*
G01X722244Y1014173D02*
X725000D01*
G01X719095Y1023622D02*
X717126Y1021653D01*
G01X727049Y-7874D02*
G03Y0I0J3937D01*
G01Y-7874D02*
G03Y0I0J3937D01*
G01X740463Y24349D02*
X739725Y23595D01*
G01D02*
X739233Y22590D01*
G01D02*
X738987Y21836D01*
G01D02*
X738740Y20579D01*
G01X740217Y21836D02*
X739971Y20328D01*
G01D02*
Y18569D01*
G01X738740Y20579D02*
Y18318D01*
G01X736772Y18569D02*
Y17564D01*
G01Y21585D02*
Y20579D01*
G01X732835D02*
Y21585D01*
G01Y17564D02*
Y18569D01*
G01X730866Y25354D02*
Y13543D01*
G01X729390Y20579D02*
Y25354D01*
G01Y13543D02*
Y19072D01*
G01X739971Y18569D02*
X740217Y17061D01*
G01X738740Y18318D02*
X738987Y17061D01*
G01D02*
X739233Y16307D01*
G01D02*
X739725Y15302D01*
G01D02*
X740463Y14548D01*
G01X732835Y21585D02*
X736772D01*
G01Y20579D02*
X732835D01*
G01Y18569D02*
X736772D01*
G01Y17564D02*
X732835D01*
G01X730866Y13543D02*
X729390D01*
G01Y25354D02*
X730866D01*
G01X738586Y299606D02*
X738598Y300266D01*
G01X738596Y301194D02*
X738565Y299606D01*
G01X734649D02*
X734661Y300266D01*
G01X734659Y301194D02*
X734628Y299606D01*
G01X730712D02*
X730724Y300266D01*
G01X730722Y301194D02*
X730691Y299606D01*
G01X726775D02*
X726787Y300266D01*
G01X726785Y301194D02*
X726754Y299606D01*
G01X737357D02*
X737367Y300197D01*
G01X737365Y301107D02*
X737340Y299606D01*
G01X733420D02*
X733430Y300197D01*
G01X733428Y301107D02*
X733403Y299606D01*
G01X729483D02*
X729493Y300197D01*
G01X729491Y301107D02*
X729466Y299606D01*
G01X725546D02*
X725556Y300197D01*
G01X725554Y301107D02*
X725529Y299606D01*
G01X737428Y297019D02*
X737423Y295232D01*
G01X737413Y295500D02*
X737418Y297287D01*
G01X734635Y293082D02*
X734629Y291295D01*
G01X734620Y291563D02*
X734625Y293350D01*
G01X729554Y297019D02*
X729549Y295232D01*
G01X729539Y295500D02*
X729544Y297287D01*
G01X726761Y293082D02*
X726755Y291295D01*
G01X726746Y291563D02*
X726751Y293350D01*
G01X738581Y293799D02*
Y294783D01*
G01X738425Y298720D02*
Y297736D01*
G01X737559Y298720D02*
Y297736D01*
G01X737404Y294783D02*
Y293799D01*
G01X734644D02*
Y294783D01*
G01X734488Y290846D02*
Y289862D01*
G01X733622Y290846D02*
Y289862D01*
G01X733467Y294783D02*
Y293799D01*
G01X730707Y294783D02*
Y293799D01*
G01X730551Y298720D02*
Y297736D01*
G01X729685Y298720D02*
Y297736D01*
G01X729530Y293799D02*
Y294783D01*
G01X726770Y293799D02*
Y294783D01*
G01X726614Y290846D02*
Y289862D01*
G01X725748Y290846D02*
Y289862D01*
G01X725593Y294783D02*
Y293799D01*
G01X738566Y297287D02*
X738572Y295500D01*
G01X738562Y295232D02*
X738557Y297019D01*
G01X733486Y293350D02*
X733491Y291563D01*
G01X733481Y291295D02*
X733476Y293082D01*
G01X730692Y297287D02*
X730698Y295500D01*
G01X730688Y295232D02*
X730683Y297019D01*
G01X725612Y293350D02*
X725617Y291563D01*
G01X725607Y291295D02*
X725602Y293082D01*
G01X738645Y299606D02*
X738620Y301107D01*
G01X738618Y300197D02*
X738627Y299606D01*
G01X734708D02*
X734683Y301107D01*
G01X734681Y300197D02*
X734690Y299606D01*
G01X730771D02*
X730746Y301107D01*
G01X730744Y300197D02*
X730753Y299606D01*
G01X726834D02*
X726809Y301107D01*
G01X726807Y300197D02*
X726816Y299606D01*
G01X737420D02*
X737389Y301194D01*
G01X737387Y300266D02*
X737399Y299606D01*
G01X733483D02*
X733452Y301194D01*
G01X733450Y300266D02*
X733462Y299606D01*
G01X729546D02*
X729515Y301194D01*
G01X729513Y300266D02*
X729525Y299606D01*
G01X725609D02*
X725578Y301194D01*
G01X725575Y300266D02*
X725588Y299606D01*
G01X737377Y301477D02*
X738607D01*
G01X733440D02*
X734670D01*
G01X729503D02*
X730733D01*
G01X725566D02*
X726796D01*
G01X737389Y301194D02*
X738596D01*
G01X733452D02*
X734659D01*
G01X729515D02*
X730722D01*
G01X725578D02*
X726785D01*
G01X726809Y301107D02*
X725554D01*
G01X730746D02*
X729491D01*
G01X734683D02*
X733428D01*
G01X738620D02*
X737365D01*
G01X737377Y300492D02*
X738607D01*
G01X733440D02*
X734670D01*
G01X729503D02*
X730733D01*
G01X725566D02*
X726796D01*
G01X726787Y300266D02*
X725575D01*
G01X730724D02*
X729513D01*
G01X734661D02*
X733450D01*
G01X738598D02*
X737387D01*
G01X737367Y300197D02*
X738618D01*
G01X733430D02*
X734681D01*
G01X729493D02*
X730744D01*
G01X725556D02*
X726807D01*
G01X730674Y298720D02*
X729563D01*
G01X738548D02*
X737437D01*
G01Y297736D02*
X738548D01*
G01X729563D02*
X730674D01*
G01X737418Y297287D02*
X738566D01*
G01X729544D02*
X730692D01*
G01X730683Y297019D02*
X729554D01*
G01X738557D02*
X737428D01*
G01X730698Y295500D02*
X729539D01*
G01X738572D02*
X737413D01*
G01X737423Y295232D02*
X738562D01*
G01X729549D02*
X730688D01*
G01X737404Y294783D02*
X738581D01*
G01X733467D02*
X734644D01*
G01X729530D02*
X730707D01*
G01X725593D02*
X726770D01*
G01Y293799D02*
X725593D01*
G01X730707D02*
X729530D01*
G01X734644D02*
X733467D01*
G01X738581D02*
X737404D01*
G01X726751Y293350D02*
X725612D01*
G01X734625D02*
X733486D01*
G01X733476Y293082D02*
X734635D01*
G01X725602D02*
X726761D01*
G01X733491Y291563D02*
X734620D01*
G01X725617D02*
X726746D01*
G01X726755Y291295D02*
X725607D01*
G01X734629D02*
X733481D01*
G01X726737Y290846D02*
X725626D01*
G01X734611D02*
X733500D01*
G01Y289862D02*
X734611D01*
G01X725626D02*
X726737D01*
G01X737389Y305104D02*
X737420Y306692D01*
G01X737399D02*
X737387Y306032D01*
G01X733452Y305104D02*
X733483Y306692D01*
G01X733462D02*
X733450Y306032D01*
G01X729515Y305104D02*
X729546Y306692D01*
G01X729525D02*
X729513Y306032D01*
G01X725578Y305104D02*
X725609Y306692D01*
G01X725588D02*
X725575Y306032D01*
G01X738620Y305191D02*
X738645Y306692D01*
G01X738627D02*
X738618Y306102D01*
G01X734683Y305191D02*
X734708Y306692D01*
G01X734690D02*
X734681Y306102D01*
G01X730746Y305191D02*
X730771Y306692D01*
G01X730753D02*
X730744Y306102D01*
G01X726809Y305191D02*
X726834Y306692D01*
G01X726816D02*
X726807Y306102D01*
G01X738572Y310799D02*
X738566Y309011D01*
G01X738557Y309279D02*
X738562Y311066D01*
G01X733491Y314736D02*
X733486Y312948D01*
G01X733476Y313216D02*
X733481Y315003D01*
G01X730698Y310799D02*
X730692Y309011D01*
G01X730683Y309279D02*
X730688Y311066D01*
G01X725617Y314736D02*
X725612Y312948D01*
G01X725602Y313216D02*
X725607Y315003D01*
G01X738581Y312500D02*
Y311515D01*
G01X738425Y308563D02*
Y307578D01*
G01X737874Y323228D02*
Y317618D01*
G01X737559Y307578D02*
Y308563D01*
G01X737404Y311515D02*
Y312500D01*
G01X734644Y311515D02*
Y312500D01*
G01X734488Y316437D02*
Y315452D01*
G01X733622D02*
Y316437D01*
G01X733467Y312500D02*
Y311515D01*
G01X730707Y312500D02*
Y311515D01*
G01X730551Y308563D02*
Y307578D01*
G01X729685D02*
Y308563D01*
G01X729530Y311515D02*
Y312500D01*
G01X726770Y311515D02*
Y312500D01*
G01X726614Y316437D02*
Y315452D01*
G01X725748D02*
Y316437D01*
G01X725593Y312500D02*
Y311515D01*
G01X737423Y311066D02*
X737428Y309279D01*
G01X737418Y309011D02*
X737413Y310799D01*
G01X734629Y315003D02*
X734635Y313216D01*
G01X734625Y312948D02*
X734620Y314736D01*
G01X729549Y311066D02*
X729554Y309279D01*
G01X729544Y309011D02*
X729539Y310799D01*
G01X726755Y315003D02*
X726761Y313216D01*
G01X726751Y312948D02*
X726746Y314736D01*
G01X737367Y306102D02*
X737357Y306692D01*
G01X737340D02*
X737365Y305191D01*
G01X733430Y306102D02*
X733420Y306692D01*
G01X733403D02*
X733428Y305191D01*
G01X729493Y306102D02*
X729483Y306692D01*
G01X729466D02*
X729491Y305191D01*
G01X725556Y306102D02*
X725546Y306692D01*
G01X725529D02*
X725554Y305191D01*
G01X738598Y306032D02*
X738586Y306692D01*
G01X738565D02*
X738596Y305104D01*
G01X734661Y306032D02*
X734649Y306692D01*
G01X734628D02*
X734659Y305104D01*
G01X730724Y306032D02*
X730712Y306692D01*
G01X730691D02*
X730722Y305104D01*
G01X726787Y306032D02*
X726775Y306692D01*
G01X726754D02*
X726785Y305104D01*
G01X726737Y316437D02*
X725626D01*
G01X734611D02*
X733500D01*
G01X726737Y315452D02*
X725626D01*
G01X734611D02*
X733500D01*
G01X733481Y315003D02*
X734629D01*
G01X725607D02*
X726755D01*
G01X726746Y314736D02*
X725617D01*
G01X734620D02*
X733491D01*
G01X726761Y313216D02*
X725602D01*
G01X734635D02*
X733476D01*
G01X733486Y312948D02*
X734625D01*
G01X725612D02*
X726751D01*
G01X726770Y312500D02*
X725593D01*
G01X730707D02*
X729530D01*
G01X734644D02*
X733467D01*
G01X738581D02*
X737404D01*
G01X726770Y311515D02*
X725593D01*
G01X730707D02*
X729530D01*
G01X734644D02*
X733467D01*
G01X738581D02*
X737404D01*
G01X730688Y311066D02*
X729549D01*
G01X738562D02*
X737423D01*
G01X737413Y310799D02*
X738572D01*
G01X729539D02*
X730698D01*
G01X737428Y309279D02*
X738557D01*
G01X729554D02*
X730683D01*
G01X730692Y309011D02*
X729544D01*
G01X738566D02*
X737418D01*
G01X730674Y308563D02*
X729563D01*
G01X738548D02*
X737437D01*
G01X730674Y307578D02*
X729563D01*
G01X738548D02*
X737437D01*
G01X726807Y306102D02*
X725556D01*
G01X730744D02*
X729493D01*
G01X734681D02*
X733430D01*
G01X738618D02*
X737367D01*
G01X737387Y306032D02*
X738598D01*
G01X733450D02*
X734661D01*
G01X729513D02*
X730724D01*
G01X725575D02*
X726787D01*
G01X726796Y305806D02*
X725566D01*
G01X730733D02*
X729503D01*
G01X734670D02*
X733440D01*
G01X738607D02*
X737377D01*
G01X737365Y305191D02*
X738620D01*
G01X733428D02*
X734683D01*
G01X729491D02*
X730746D01*
G01X725554D02*
X726809D01*
G01X726785Y305104D02*
X725578D01*
G01X730722D02*
X729515D01*
G01X734659D02*
X733452D01*
G01X738596D02*
X737389D01*
G01X726796Y304822D02*
X725566D01*
G01X730733D02*
X729503D01*
G01X734670D02*
X733440D01*
G01X738607D02*
X737377D01*
G01X750197Y353543D02*
G03I-6299J0D01*
G01X739960Y370672D02*
Y364931D01*
G01X738703D02*
Y370672D01*
G01X734725Y363700D02*
Y364931D01*
G01X739960D02*
X744567D01*
G01X734725D02*
X738703D01*
G01X744567Y363700D02*
X734725D01*
G01Y382155D02*
X734934Y380925D01*
G01X735772Y382155D02*
X735981Y381130D01*
G01X737657Y384616D02*
X736400Y383796D01*
G01X736190Y385026D02*
X735563Y384411D01*
G01X736400Y383796D02*
X735981Y383180D01*
G01X735563Y384411D02*
X734934Y383385D01*
G01X735981Y383180D02*
X735772Y382155D01*
G01X734934Y383385D02*
X734725Y382155D01*
G01X738703Y376824D02*
Y373543D01*
G01X737866D02*
Y376824D01*
G01X734725Y370672D02*
Y371902D01*
G01X734934Y380925D02*
X735563Y379900D01*
G01X735981Y381130D02*
X736400Y380515D01*
G01X735563Y379900D02*
X736190Y379284D01*
G01X736400Y380515D02*
X737657Y379694D01*
G01X736190Y379284D02*
X737028Y378874D01*
G01D02*
X737657Y378669D01*
G01D02*
X738703Y378464D01*
G01X737657Y379694D02*
X738913Y379489D01*
G01D02*
X740379D01*
G01X738703Y378464D02*
X740588D01*
G01X737866Y376824D02*
X738703D01*
G01Y373543D02*
X737866D01*
G01X734725Y371902D02*
X744567D01*
G01X738913Y384821D02*
X737657Y384616D01*
G01X738703Y370672D02*
X734725D01*
G01X744567D02*
X739960D01*
G01X738703Y398765D02*
X738913Y398149D01*
G01X738075D02*
X737866Y398765D01*
G01X738075Y392203D02*
X737866Y392818D01*
G01X738703Y389537D02*
X738913Y388922D01*
G01X738075D02*
X737866Y389537D01*
G01X738703Y392613D02*
X738913Y392203D01*
G01X738703Y400815D02*
X738075Y401430D01*
G01X737657Y385641D02*
X737028Y385436D01*
G01X738494Y394663D02*
X739541Y395074D01*
G01X737028Y385436D02*
X736190Y385026D01*
G01X739541Y390767D02*
X739122Y390562D01*
G01X739541Y394048D02*
X739122Y393843D01*
G01X739541Y399995D02*
X739122Y399790D01*
G01Y390562D02*
X738913Y390357D01*
G01X738075Y390972D02*
X738703Y391587D01*
G01X739122Y393843D02*
X738913Y393638D01*
G01X738075Y394253D02*
X738494Y394663D01*
G01X739122Y399790D02*
X738913Y399585D01*
G01X738075Y400200D02*
X738703Y400815D01*
G01X738913Y390357D02*
X738703Y389947D01*
G01X738913Y393638D02*
X738703Y393228D01*
G01X738913Y399585D02*
X738703Y399174D01*
G01X737866Y390357D02*
X738075Y390972D01*
G01X737866Y393638D02*
X738075Y394253D01*
G01X737866Y399585D02*
X738075Y400200D01*
G01X738703Y393228D02*
Y392613D01*
G01Y389947D02*
Y389537D01*
G01Y399174D02*
Y398765D01*
G01X737866D02*
Y399585D01*
G01Y396714D02*
Y397739D01*
G01Y392818D02*
Y393638D01*
G01Y389537D02*
Y390357D01*
G01Y387487D02*
Y388512D01*
G01X738913Y398149D02*
X739332Y397739D01*
G01X738494D02*
X738075Y398149D01*
G01X738913Y392203D02*
X739122Y391998D01*
G01X738703Y391587D02*
X738075Y392203D01*
G01X738913Y388922D02*
X739332Y388512D01*
G01X738494D02*
X738075Y388922D01*
G01X739122Y401225D02*
X739541Y401020D01*
G01X739122Y391998D02*
X739541Y391792D01*
G01Y401020D02*
X744567D01*
G01Y399995D02*
X739541D01*
G01X737866Y397739D02*
X738494D01*
G01X739332D02*
X744567D01*
G01Y396714D02*
X737866D01*
G01X739541Y395074D02*
X744567D01*
G01Y394048D02*
X739541D01*
G01Y391792D02*
X744567D01*
G01Y390767D02*
X739541D01*
G01X737866Y388512D02*
X738494D01*
G01X739332D02*
X744567D01*
G01Y387487D02*
X737866D01*
G01X740588Y385846D02*
X738703D01*
G01X740379Y384821D02*
X738913D01*
G01X738703Y385846D02*
X737657Y385641D01*
G01X750197Y410629D02*
G03I-6299J0D01*
G01X738075Y401430D02*
X737866Y402045D01*
G01X738703Y401840D02*
X738913Y401430D01*
G01D02*
X739122Y401225D01*
G01X738494Y403890D02*
X739541Y404301D01*
G01Y403276D02*
X739122Y403070D01*
G01D02*
X738913Y402865D01*
G01X738075Y403481D02*
X738494Y403890D01*
G01X738913Y402865D02*
X738703Y402455D01*
G01X737866Y402865D02*
X738075Y403481D01*
G01X738703Y402455D02*
Y401840D01*
G01X737866Y402045D02*
Y402865D01*
G01X739541Y404301D02*
X744567D01*
G01Y403276D02*
X739541D01*
G01X728937Y1001574D02*
X726181D01*
G01X732874D02*
X730118D01*
G01X736811D02*
X734055D01*
G01X740748D02*
X737992D01*
G01D02*
Y1018110D01*
G01X736811D02*
Y1001574D01*
G01X734055D02*
Y1018110D01*
G01X732874D02*
Y1001574D01*
G01X730118D02*
Y1018110D01*
G01X728937D02*
Y1001574D01*
G01X726181D02*
Y1018110D01*
G01X725000Y1014173D02*
Y1001574D01*
G01X737992Y1018110D02*
X740748D01*
G01X734055D02*
X736811D01*
G01X726181D02*
X728937D01*
G01X730118D02*
X732874D01*
G01X752246Y-7874D02*
X984201D01*
G01X752246Y0D02*
G03Y-7874I0J-3937D01*
G01D02*
X984201D01*
G01X752246Y0D02*
G03Y-7874I0J-3937D01*
G01X755227Y21333D02*
X755965Y21585D01*
G01X752028Y20579D02*
X751290Y20328D01*
G01Y21333D02*
X752028Y21585D01*
G01X755719Y20579D02*
X755227Y20328D01*
G01X744646Y13794D02*
X745876Y14548D01*
G01X744400Y15051D02*
X745138Y15553D01*
G01X741939Y23846D02*
X741201Y23344D01*
G01X755227Y20328D02*
X754981Y20077D01*
G01X754488Y20579D02*
X755227Y21333D01*
G01X745876Y14548D02*
X746614Y15302D01*
G01X751290Y20328D02*
X750798Y19825D01*
G01Y20831D02*
X751290Y21333D01*
G01X745138Y15553D02*
X746122Y17061D01*
G01X741201Y23344D02*
X740217Y21836D01*
G01X754981Y20077D02*
X754735Y19574D01*
G01X746614Y15302D02*
X747107Y16307D01*
G01D02*
X747353Y17061D01*
G01D02*
X747599Y18318D01*
G01X746122Y17061D02*
X746368Y18569D01*
G01X754735Y19574D02*
Y13543D01*
G01X753504D02*
Y19574D01*
G01X750798Y21585D02*
Y20831D01*
G01Y19825D02*
Y13543D01*
G01X749567D02*
Y21585D01*
G01X747599Y18318D02*
Y20579D01*
G01X746368Y18569D02*
Y20328D01*
G01D02*
X746122Y21836D01*
G01X747599Y20579D02*
X747353Y21836D01*
G01D02*
X747107Y22590D01*
G01X753504Y19574D02*
X753258Y20077D01*
G01X747107Y22590D02*
X746614Y23595D01*
G01X746122Y21836D02*
X745138Y23344D01*
G01X740217Y17061D02*
X741201Y15553D01*
G01X753750Y21333D02*
X754488Y20579D01*
G01X753258Y20077D02*
X753012Y20328D01*
G01X746614Y23595D02*
X745876Y24349D01*
G01X745138Y23344D02*
X744400Y23846D01*
G01X741201Y15553D02*
X741939Y15051D01*
G01X740463Y14548D02*
X741693Y13794D01*
G01X756949Y20328D02*
X756457Y20579D01*
G01X753012Y20328D02*
X752520Y20579D01*
G01X753012Y21585D02*
X753750Y21333D01*
G01X741939Y15051D02*
X743170Y14799D01*
G01X741693Y13794D02*
X743170Y13543D01*
G01X755965Y21585D02*
X756949D01*
G01X749567D02*
X750798D01*
G01X752028D02*
X753012D01*
G01X752520Y20579D02*
X752028D01*
G01X756457D02*
X755719D01*
G01X750798Y13543D02*
X749567D01*
G01X754735D02*
X753504D01*
G01X743170D02*
X744646Y13794D01*
G01X743170Y14799D02*
X744400Y15051D01*
G01X741693Y25103D02*
X740463Y24349D01*
G01X745876D02*
X744646Y25103D01*
G01X744400Y23846D02*
X743170Y24098D01*
G01X744646Y25103D02*
X743170Y25354D01*
G01D02*
X741693Y25103D01*
G01X743170Y24098D02*
X741939Y23846D01*
G01X754334Y299606D02*
X754346Y300266D01*
G01X754344Y301194D02*
X754313Y299606D01*
G01X750397D02*
X750409Y300266D01*
G01X750407Y301194D02*
X750376Y299606D01*
G01X746460D02*
X746472Y300266D01*
G01X746470Y301194D02*
X746439Y299606D01*
G01X742523D02*
X742535Y300266D01*
G01X742533Y301194D02*
X742502Y299606D01*
G01X753105D02*
X753115Y300197D01*
G01X753113Y301107D02*
X753088Y299606D01*
G01X749168D02*
X749178Y300197D01*
G01X749176Y301107D02*
X749151Y299606D01*
G01X745231D02*
X745241Y300197D01*
G01X745239Y301107D02*
X745214Y299606D01*
G01X741294D02*
X741304Y300197D01*
G01X741302Y301107D02*
X741277Y299606D01*
G01X753176Y297019D02*
X753171Y295232D01*
G01X753161Y295500D02*
X753166Y297287D01*
G01X750383Y293082D02*
X750377Y291295D01*
G01X750368Y291563D02*
X750373Y293350D01*
G01X745302Y297019D02*
X745297Y295232D01*
G01X745287Y295500D02*
X745292Y297287D01*
G01X742509Y293082D02*
X742503Y291295D01*
G01X742494Y291563D02*
X742499Y293350D01*
G01X754329Y294783D02*
Y293799D01*
G01X754174Y298720D02*
Y297736D01*
G01X753307Y298720D02*
Y297736D01*
G01X753152Y293799D02*
Y294783D01*
G01X750392Y293799D02*
Y294783D01*
G01X750237Y290846D02*
Y289862D01*
G01X749370Y290846D02*
Y289862D01*
G01X749215Y294783D02*
Y293799D01*
G01X746455Y294783D02*
Y293799D01*
G01X746300Y298720D02*
Y297736D01*
G01X745433Y298720D02*
Y297736D01*
G01X745278Y293799D02*
Y294783D01*
G01X742518Y293799D02*
Y294783D01*
G01X742363Y290846D02*
Y289862D01*
G01X741496Y290846D02*
Y289862D01*
G01X741341Y294783D02*
Y293799D01*
G01X754314Y297287D02*
X754320Y295500D01*
G01X754310Y295232D02*
X754305Y297019D01*
G01X749234Y293350D02*
X749239Y291563D01*
G01X749229Y291295D02*
X749224Y293082D01*
G01X746440Y297287D02*
X746446Y295500D01*
G01X746436Y295232D02*
X746431Y297019D01*
G01X741360Y293350D02*
X741365Y291563D01*
G01X741355Y291295D02*
X741350Y293082D01*
G01X754393Y299606D02*
X754368Y301107D01*
G01X754366Y300197D02*
X754375Y299606D01*
G01X750456D02*
X750431Y301107D01*
G01X750429Y300197D02*
X750438Y299606D01*
G01X746519D02*
X746494Y301107D01*
G01X746492Y300197D02*
X746501Y299606D01*
G01X742582D02*
X742557Y301107D01*
G01X742555Y300197D02*
X742564Y299606D01*
G01X753168D02*
X753137Y301194D01*
G01X753135Y300266D02*
X753147Y299606D01*
G01X749231D02*
X749200Y301194D01*
G01X749198Y300266D02*
X749210Y299606D01*
G01X745294D02*
X745263Y301194D01*
G01X745261Y300266D02*
X745273Y299606D01*
G01X741357D02*
X741326Y301194D01*
G01X741324Y300266D02*
X741336Y299606D01*
G01X753125Y301477D02*
X754355D01*
G01X745251D02*
X746481D01*
G01X749188D02*
X750418D01*
G01X741314D02*
X742544D01*
G01X753137Y301194D02*
X754344D01*
G01X745263D02*
X746470D01*
G01X749200D02*
X750407D01*
G01X741326D02*
X742533D01*
G01X742557Y301107D02*
X741302D01*
G01X746494D02*
X745239D01*
G01X750431D02*
X749176D01*
G01X754368D02*
X753113D01*
G01X753125Y300492D02*
X754355D01*
G01X745251D02*
X746481D01*
G01X749188D02*
X750418D01*
G01X741314D02*
X742544D01*
G01X742535Y300266D02*
X741324D01*
G01X746472D02*
X745261D01*
G01X750409D02*
X749198D01*
G01X754346D02*
X753135D01*
G01X753115Y300197D02*
X754366D01*
G01X745241D02*
X746492D01*
G01X749178D02*
X750429D01*
G01X741304D02*
X742555D01*
G01X746422Y298720D02*
X745311D01*
G01X754296D02*
X753185D01*
G01Y297736D02*
X754296D01*
G01X745311D02*
X746422D01*
G01X753166Y297287D02*
X754314D01*
G01X745292D02*
X746440D01*
G01X746431Y297019D02*
X745302D01*
G01X754305D02*
X753176D01*
G01X746446Y295500D02*
X745287D01*
G01X754320D02*
X753161D01*
G01X753171Y295232D02*
X754310D01*
G01X745297D02*
X746436D01*
G01X753152Y294783D02*
X754329D01*
G01X749215D02*
X750392D01*
G01X745278D02*
X746455D01*
G01X741341D02*
X742518D01*
G01Y293799D02*
X741341D01*
G01X750392D02*
X749215D01*
G01X746455D02*
X745278D01*
G01X754329D02*
X753152D01*
G01X742499Y293350D02*
X741360D01*
G01X750373D02*
X749234D01*
G01X749224Y293082D02*
X750383D01*
G01X741350D02*
X742509D01*
G01X749239Y291563D02*
X750368D01*
G01X741365D02*
X742494D01*
G01X742503Y291295D02*
X741355D01*
G01X750377D02*
X749229D01*
G01X742485Y290846D02*
X741374D01*
G01X750359D02*
X749248D01*
G01Y289862D02*
X750359D01*
G01X741374D02*
X742485D01*
G01X753137Y305104D02*
X753168Y306692D01*
G01X753147D02*
X753135Y306032D01*
G01X749200Y305104D02*
X749231Y306692D01*
G01X749210D02*
X749198Y306032D01*
G01X745263Y305104D02*
X745294Y306692D01*
G01X745273D02*
X745261Y306032D01*
G01X741326Y305104D02*
X741357Y306692D01*
G01X741336D02*
X741324Y306032D01*
G01X754368Y305191D02*
X754393Y306692D01*
G01X754375D02*
X754366Y306102D01*
G01X750431Y305191D02*
X750456Y306692D01*
G01X750438D02*
X750429Y306102D01*
G01X746494Y305191D02*
X746519Y306692D01*
G01X746501D02*
X746492Y306102D01*
G01X742557Y305191D02*
X742582Y306692D01*
G01X742564D02*
X742555Y306102D01*
G01X754320Y310799D02*
X754314Y309011D01*
G01X754305Y309279D02*
X754310Y311066D01*
G01X749239Y314736D02*
X749234Y312948D01*
G01X749224Y313216D02*
X749229Y315003D01*
G01X746446Y310799D02*
X746440Y309011D01*
G01X746431Y309279D02*
X746436Y311066D01*
G01X741365Y314736D02*
X741360Y312948D01*
G01X741350Y313216D02*
X741355Y315003D01*
G01X754329Y312500D02*
Y311515D01*
G01X754174Y308563D02*
Y307578D01*
G01X753307D02*
Y308563D01*
G01X753152Y311515D02*
Y312500D01*
G01X750392Y311515D02*
Y312500D01*
G01X750237Y316437D02*
Y315452D01*
G01X749370D02*
Y316437D01*
G01X749215Y312500D02*
Y311515D01*
G01X746455Y312500D02*
Y311515D01*
G01X746300Y308563D02*
Y307578D01*
G01X745433D02*
Y308563D01*
G01X745278Y311515D02*
Y312500D01*
G01X742874Y323228D02*
Y317618D01*
G01X742518Y312500D02*
Y311515D01*
G01X742363Y316437D02*
Y315452D01*
G01X741496D02*
Y316437D01*
G01X741341Y311515D02*
Y312500D01*
G01X753171Y311066D02*
X753176Y309279D01*
G01X753166Y309011D02*
X753161Y310799D01*
G01X750377Y315003D02*
X750383Y313216D01*
G01X750373Y312948D02*
X750368Y314736D01*
G01X745297Y311066D02*
X745302Y309279D01*
G01X745292Y309011D02*
X745287Y310799D01*
G01X742503Y315003D02*
X742509Y313216D01*
G01X742499Y312948D02*
X742494Y314736D01*
G01X753115Y306102D02*
X753105Y306692D01*
G01X753088D02*
X753113Y305191D01*
G01X749178Y306102D02*
X749168Y306692D01*
G01X749151D02*
X749176Y305191D01*
G01X745241Y306102D02*
X745231Y306692D01*
G01X745214D02*
X745239Y305191D01*
G01X741304Y306102D02*
X741294Y306692D01*
G01X741277D02*
X741302Y305191D01*
G01X754346Y306032D02*
X754334Y306692D01*
G01X754313D02*
X754344Y305104D01*
G01X750409Y306032D02*
X750397Y306692D01*
G01X750376D02*
X750407Y305104D01*
G01X746472Y306032D02*
X746460Y306692D01*
G01X746439D02*
X746470Y305104D01*
G01X742535Y306032D02*
X742523Y306692D01*
G01X742502D02*
X742533Y305104D01*
G01X742485Y316437D02*
X741374D01*
G01X750359D02*
X749248D01*
G01X742485Y315452D02*
X741374D01*
G01X750359D02*
X749248D01*
G01X749229Y315003D02*
X750377D01*
G01X741355D02*
X742503D01*
G01X742494Y314736D02*
X741365D01*
G01X750368D02*
X749239D01*
G01X742509Y313216D02*
X741350D01*
G01X750383D02*
X749224D01*
G01X749234Y312948D02*
X750373D01*
G01X741360D02*
X742499D01*
G01X742518Y312500D02*
X741341D01*
G01X750392D02*
X749215D01*
G01X746455D02*
X745278D01*
G01X754329D02*
X753152D01*
G01X742518Y311515D02*
X741341D01*
G01X750392D02*
X749215D01*
G01X746455D02*
X745278D01*
G01X754329D02*
X753152D01*
G01X746436Y311066D02*
X745297D01*
G01X754310D02*
X753171D01*
G01X753161Y310799D02*
X754320D01*
G01X745287D02*
X746446D01*
G01X753176Y309279D02*
X754305D01*
G01X745302D02*
X746431D01*
G01X746440Y309011D02*
X745292D01*
G01X754314D02*
X753166D01*
G01X746422Y308563D02*
X745311D01*
G01X754296D02*
X753185D01*
G01X746422Y307578D02*
X745311D01*
G01X754296D02*
X753185D01*
G01X742555Y306102D02*
X741304D01*
G01X746492D02*
X745241D01*
G01X750429D02*
X749178D01*
G01X754366D02*
X753115D01*
G01X753135Y306032D02*
X754346D01*
G01X745261D02*
X746472D01*
G01X749198D02*
X750409D01*
G01X741324D02*
X742535D01*
G01X742544Y305806D02*
X741314D01*
G01X746481D02*
X745251D01*
G01X750418D02*
X749188D01*
G01X754355D02*
X753125D01*
G01X753113Y305191D02*
X754368D01*
G01X745239D02*
X746494D01*
G01X749176D02*
X750431D01*
G01X741302D02*
X742557D01*
G01X742533Y305104D02*
X741326D01*
G01X746470D02*
X745263D01*
G01X750407D02*
X749200D01*
G01X754344D02*
X753137D01*
G01X742544Y304822D02*
X741314D01*
G01X746481D02*
X745251D01*
G01X750418D02*
X749188D01*
G01X754355D02*
X753125D01*
G01X758780Y323228D02*
X742874D01*
G01X744567Y364931D02*
Y363700D01*
G01Y382155D02*
X744358Y383385D01*
G01X743520Y382155D02*
X743311Y383180D01*
G01X744358Y383385D02*
X743729Y384411D01*
G01X743311Y383180D02*
X742892Y383796D01*
G01X741635Y378669D02*
X742264Y378874D01*
G01D02*
X743101Y379284D01*
G01X741635Y379694D02*
X742892Y380515D01*
G01X743101Y379284D02*
X743729Y379900D01*
G01X742892Y380515D02*
X743311Y381130D01*
G01X743729Y379900D02*
X744358Y380925D01*
G01X743311Y381130D02*
X743520Y382155D01*
G01X744358Y380925D02*
X744567Y382155D01*
G01Y371902D02*
Y370672D01*
G01X741216Y376824D02*
Y373543D01*
G01X740379D02*
Y376824D01*
G01X743729Y384411D02*
X743101Y385026D01*
G01X742892Y383796D02*
X741635Y384616D01*
G01D02*
X740379Y384821D01*
G01Y376824D02*
X741216D01*
G01Y373543D02*
X740379D01*
G01Y379489D02*
X741635Y379694D01*
G01X740588Y378464D02*
X741635Y378669D01*
G01X744567Y388512D02*
Y387487D01*
G01Y391792D02*
Y390767D01*
G01Y397739D02*
Y396714D01*
G01Y395074D02*
Y394048D01*
G01Y401020D02*
Y399995D01*
G01X743101Y385026D02*
X742264Y385436D01*
G01D02*
X741635Y385641D01*
G01D02*
X740588Y385846D01*
G01X744567Y404301D02*
Y403276D01*
G01X745472Y994290D02*
G03X752953I3741J1D01*
G01X745473Y994291D02*
G03X752953I3740J0D01*
G01X745472Y994290D02*
Y1018109D01*
G01X752953D02*
Y994290D01*
G01X744685Y1001574D02*
X741929D01*
G01X756496D02*
X753740D01*
G01X756496Y1018110D02*
Y1001574D01*
G01X753740D02*
Y1018110D01*
G01X752953Y1021653D02*
Y994291D01*
G01X745473D02*
Y1021653D01*
G01X744685Y1018110D02*
Y1001574D01*
G01X741929D02*
Y1018110D01*
G01X740748D02*
Y1001574D01*
G01X745473Y1021653D02*
X745472Y1018109D01*
G01X752953Y1021653D02*
Y1018109D01*
G01X795079Y1023622D02*
X754922D01*
G01X745473Y1021653D02*
X743505Y1023622D01*
G01X754922D02*
X752953Y1021653D01*
G01X795079Y1023622D02*
X754922D01*
G01X753740Y1018110D02*
X756496D01*
G01X741929D02*
X744685D01*
G01X797048D02*
X752953D01*
G01X745473Y1021653D02*
X743504Y1023622D01*
G01X754922D02*
X752953Y1021653D01*
G01X766300Y21333D02*
X767038Y21585D01*
G01X763101Y20579D02*
X762363Y20328D01*
G01Y21333D02*
X763101Y21585D01*
G01X766792Y20579D02*
X766300Y20328D01*
G01D02*
X766053Y20077D01*
G01X765561Y20579D02*
X766300Y21333D01*
G01X762363Y20328D02*
X761870Y19825D01*
G01Y20831D02*
X762363Y21333D01*
G01X766053Y20077D02*
X765807Y19574D01*
G01X769744D02*
Y13543D01*
G01X768514D02*
Y19574D01*
G01X765807D02*
Y13543D01*
G01X764577D02*
Y19574D01*
G01X761870Y21585D02*
Y20831D01*
G01Y19825D02*
Y13543D01*
G01X760640D02*
Y21585D01*
G01X758672Y19574D02*
Y13543D01*
G01X757441D02*
Y19574D01*
G01X769252Y20831D02*
X769744Y19574D01*
G01X758179Y20831D02*
X758672Y19574D01*
G01X768514D02*
X768268Y20077D01*
G01X764577Y19574D02*
X764331Y20077D01*
G01X757441Y19574D02*
X757195Y20077D01*
G01X768760Y21333D02*
X769252Y20831D01*
G01X768268Y20077D02*
X768022Y20328D01*
G01X764823Y21333D02*
X765561Y20579D01*
G01X764331Y20077D02*
X764085Y20328D01*
G01X757687Y21333D02*
X758179Y20831D01*
G01X757195Y20077D02*
X756949Y20328D01*
G01X768022D02*
X767530Y20579D01*
G01X764085Y20328D02*
X763593Y20579D01*
G01X768022Y21585D02*
X768760Y21333D01*
G01X764085Y21585D02*
X764823Y21333D01*
G01X756949Y21585D02*
X757687Y21333D01*
G01X767038Y21585D02*
X768022D01*
G01X760640D02*
X761870D01*
G01X763101D02*
X764085D01*
G01X763593Y20579D02*
X763101D01*
G01X767530D02*
X766792D01*
G01X758672Y13543D02*
X757441D01*
G01X761870D02*
X760640D01*
G01X765807D02*
X764577D01*
G01X769744D02*
X768514D01*
G01X770082Y299606D02*
X770094Y300266D01*
G01X770092Y301194D02*
X770061Y299606D01*
G01X772790D02*
X772800Y300197D01*
G01X772798Y301107D02*
X772773Y299606D01*
G01X768853D02*
X768863Y300197D01*
G01X768861Y301107D02*
X768836Y299606D01*
G01X772837Y294783D02*
Y293799D01*
G01X770077D02*
Y294783D01*
G01X772856Y293350D02*
X772861Y291563D01*
G01X772851Y291295D02*
X772846Y293082D01*
G01X772853Y299606D02*
X772822Y301194D01*
G01X772820Y300266D02*
X772832Y299606D01*
G01X766145D02*
X766157Y300266D01*
G01X766155Y301194D02*
X766124Y299606D01*
G01X762208D02*
X762220Y300266D01*
G01X762218Y301194D02*
X762187Y299606D01*
G01X758271D02*
X758283Y300266D01*
G01X758281Y301194D02*
X758250Y299606D01*
G01X764916D02*
X764926Y300197D01*
G01X764924Y301107D02*
X764899Y299606D01*
G01X760979D02*
X760989Y300197D01*
G01X760987Y301107D02*
X760962Y299606D01*
G01X757042D02*
X757052Y300197D01*
G01X757050Y301107D02*
X757025Y299606D01*
G01X768924Y297019D02*
X768919Y295232D01*
G01X768909Y295500D02*
X768914Y297287D01*
G01X766131Y293082D02*
X766125Y291295D01*
G01X766116Y291563D02*
X766121Y293350D01*
G01X761050Y297019D02*
X761045Y295232D01*
G01X761035Y295500D02*
X761040Y297287D01*
G01X758257Y293082D02*
X758251Y291295D01*
G01X758242Y291563D02*
X758247Y293350D01*
G01X769922Y298720D02*
Y297736D01*
G01X769055Y298720D02*
Y297736D01*
G01X768900Y294783D02*
Y293799D01*
G01X766140D02*
Y294783D01*
G01X765985Y290846D02*
Y289862D01*
G01X765118Y290846D02*
Y289862D01*
G01X764963Y294783D02*
Y293799D01*
G01X762203Y294783D02*
Y293799D01*
G01X762048Y298720D02*
Y297736D01*
G01X761181Y298720D02*
Y297736D01*
G01X761026Y293799D02*
Y294783D01*
G01X758266Y293799D02*
Y294783D01*
G01X758111Y290846D02*
Y289862D01*
G01X757244Y290846D02*
Y289862D01*
G01X757089Y294783D02*
Y293799D01*
G01X770063Y297287D02*
X770068Y295500D01*
G01X770058Y295232D02*
X770053Y297019D01*
G01X764982Y293350D02*
X764987Y291563D01*
G01X764977Y291295D02*
X764972Y293082D01*
G01X762188Y297287D02*
X762194Y295500D01*
G01X762184Y295232D02*
X762179Y297019D01*
G01X757108Y293350D02*
X757113Y291563D01*
G01X757103Y291295D02*
X757098Y293082D01*
G01X770141Y299606D02*
X770116Y301107D01*
G01X770114Y300197D02*
X770124Y299606D01*
G01X766204D02*
X766179Y301107D01*
G01X766177Y300197D02*
X766187Y299606D01*
G01X762267D02*
X762242Y301107D01*
G01X762240Y300197D02*
X762250Y299606D01*
G01X758330D02*
X758305Y301107D01*
G01X758303Y300197D02*
X758313Y299606D01*
G01X768916D02*
X768885Y301194D01*
G01X768883Y300266D02*
X768895Y299606D01*
G01X764979D02*
X764948Y301194D01*
G01X764946Y300266D02*
X764958Y299606D01*
G01X761042D02*
X761011Y301194D01*
G01X761009Y300266D02*
X761021Y299606D01*
G01X757105D02*
X757074Y301194D01*
G01X757072Y300266D02*
X757084Y299606D01*
G01X772811Y301477D02*
X774040D01*
G01X768874D02*
X770103D01*
G01X764937D02*
X766166D01*
G01X761000D02*
X762229D01*
G01X757063D02*
X758292D01*
G01X772822Y301194D02*
X774029D01*
G01X768885D02*
X770092D01*
G01X764948D02*
X766155D01*
G01X761011D02*
X762218D01*
G01X757074D02*
X758281D01*
G01X758305Y301107D02*
X757050D01*
G01X762242D02*
X760987D01*
G01X766179D02*
X764924D01*
G01X774053D02*
X772798D01*
G01X770116D02*
X768861D01*
G01X772811Y300492D02*
X774040D01*
G01X768874D02*
X770103D01*
G01X764937D02*
X766166D01*
G01X761000D02*
X762229D01*
G01X757063D02*
X758292D01*
G01X758283Y300266D02*
X757072D01*
G01X762220D02*
X761009D01*
G01X766157D02*
X764946D01*
G01X774031D02*
X772820D01*
G01X770094D02*
X768883D01*
G01X772800Y300197D02*
X774051D01*
G01X768863D02*
X770114D01*
G01X764926D02*
X766177D01*
G01X760989D02*
X762240D01*
G01X757052D02*
X758303D01*
G01X762170Y298720D02*
X761059D01*
G01X770044D02*
X768933D01*
G01Y297736D02*
X770044D01*
G01X761059D02*
X762170D01*
G01X768914Y297287D02*
X770063D01*
G01X761040D02*
X762188D01*
G01X762179Y297019D02*
X761050D01*
G01X770053D02*
X768924D01*
G01X762194Y295500D02*
X761035D01*
G01X770068D02*
X768909D01*
G01X768919Y295232D02*
X770058D01*
G01X761045D02*
X762184D01*
G01X772837Y294783D02*
X774014D01*
G01X768900D02*
X770077D01*
G01X764963D02*
X766140D01*
G01X761026D02*
X762203D01*
G01X757089D02*
X758266D01*
G01Y293799D02*
X757089D01*
G01X762203D02*
X761026D01*
G01X766140D02*
X764963D01*
G01X770077D02*
X768900D01*
G01X774014D02*
X772837D01*
G01X758247Y293350D02*
X757108D01*
G01X766121D02*
X764982D01*
G01X773995D02*
X772856D01*
G01X772846Y293082D02*
X774005D01*
G01X764972D02*
X766131D01*
G01X757098D02*
X758257D01*
G01X772861Y291563D02*
X773990D01*
G01X764987D02*
X766116D01*
G01X757113D02*
X758242D01*
G01X758251Y291295D02*
X757103D01*
G01X766125D02*
X764977D01*
G01X774000D02*
X772851D01*
G01X758233Y290846D02*
X757122D01*
G01X766107D02*
X764996D01*
G01X773981D02*
X772870D01*
G01Y289862D02*
X773981D01*
G01X764996D02*
X766107D01*
G01X757122D02*
X758233D01*
G01X772822Y305104D02*
X772853Y306692D01*
G01X772832D02*
X772820Y306032D01*
G01X768885Y305104D02*
X768916Y306692D01*
G01X768895D02*
X768883Y306032D01*
G01X770116Y305191D02*
X770141Y306692D01*
G01X770124D02*
X770114Y306102D01*
G01X772861Y314736D02*
X772856Y312948D01*
G01X772846Y313216D02*
X772851Y315003D01*
G01X770068Y310799D02*
X770063Y309011D01*
G01X770053Y309279D02*
X770058Y311066D01*
G01X772837Y312500D02*
Y311515D01*
G01X770077Y312500D02*
Y311515D01*
G01X772800Y306102D02*
X772790Y306692D01*
G01X772773D02*
X772798Y305191D01*
G01X764948Y305104D02*
X764979Y306692D01*
G01X764958D02*
X764946Y306032D01*
G01X761011Y305104D02*
X761042Y306692D01*
G01X761021D02*
X761009Y306032D01*
G01X757074Y305104D02*
X757105Y306692D01*
G01X757084D02*
X757072Y306032D01*
G01X766179Y305191D02*
X766204Y306692D01*
G01X766187D02*
X766177Y306102D01*
G01X762242Y305191D02*
X762267Y306692D01*
G01X762250D02*
X762240Y306102D01*
G01X758305Y305191D02*
X758330Y306692D01*
G01X758313D02*
X758303Y306102D01*
G01X764987Y314736D02*
X764982Y312948D01*
G01X764972Y313216D02*
X764977Y315003D01*
G01X762194Y310799D02*
X762188Y309011D01*
G01X762179Y309279D02*
X762184Y311066D01*
G01X757113Y314736D02*
X757108Y312948D01*
G01X757098Y313216D02*
X757103Y315003D01*
G01X769922Y308563D02*
Y307578D01*
G01X769055D02*
Y308563D01*
G01X768900Y311515D02*
Y312500D01*
G01X766140Y311515D02*
Y312500D01*
G01X765985Y316437D02*
Y315452D01*
G01X765118D02*
Y316437D01*
G01X764963Y312500D02*
Y311515D01*
G01X763780Y323228D02*
Y317618D01*
G01X762203Y312500D02*
Y311515D01*
G01X762048Y308563D02*
Y307578D01*
G01X761181D02*
Y308563D01*
G01X761026Y311515D02*
Y312500D01*
G01X758780Y323228D02*
Y317618D01*
G01X758266Y311515D02*
Y312500D01*
G01X758111Y316437D02*
Y315452D01*
G01X757244D02*
Y316437D01*
G01X757089Y312500D02*
Y311515D01*
G01X768919Y311066D02*
X768924Y309279D01*
G01X768914Y309011D02*
X768909Y310799D01*
G01X766125Y315003D02*
X766131Y313216D01*
G01X766121Y312948D02*
X766116Y314736D01*
G01X761045Y311066D02*
X761050Y309279D01*
G01X761040Y309011D02*
X761035Y310799D01*
G01X758251Y315003D02*
X758257Y313216D01*
G01X758247Y312948D02*
X758242Y314736D01*
G01X768863Y306102D02*
X768853Y306692D01*
G01X768836D02*
X768861Y305191D01*
G01X764926Y306102D02*
X764916Y306692D01*
G01X764899D02*
X764924Y305191D01*
G01X760989Y306102D02*
X760979Y306692D01*
G01X760962D02*
X760987Y305191D01*
G01X757052Y306102D02*
X757042Y306692D01*
G01X757025D02*
X757050Y305191D01*
G01X770094Y306032D02*
X770082Y306692D01*
G01X770061D02*
X770092Y305104D01*
G01X766157Y306032D02*
X766145Y306692D01*
G01X766124D02*
X766155Y305104D01*
G01X762220Y306032D02*
X762208Y306692D01*
G01X762187D02*
X762218Y305104D01*
G01X758283Y306032D02*
X758271Y306692D01*
G01X758250D02*
X758281Y305104D01*
G01X758233Y316437D02*
X757122D01*
G01X766107D02*
X764996D01*
G01X773981D02*
X772870D01*
G01X758233Y315452D02*
X757122D01*
G01X766107D02*
X764996D01*
G01X773981D02*
X772870D01*
G01X772851Y315003D02*
X774000D01*
G01X764977D02*
X766125D01*
G01X757103D02*
X758251D01*
G01X758242Y314736D02*
X757113D01*
G01X766116D02*
X764987D01*
G01X773990D02*
X772861D01*
G01X758257Y313216D02*
X757098D01*
G01X766131D02*
X764972D01*
G01X774005D02*
X772846D01*
G01X772856Y312948D02*
X773995D01*
G01X764982D02*
X766121D01*
G01X757108D02*
X758247D01*
G01X758266Y312500D02*
X757089D01*
G01X762203D02*
X761026D01*
G01X766140D02*
X764963D01*
G01X770077D02*
X768900D01*
G01X774014D02*
X772837D01*
G01X758266Y311515D02*
X757089D01*
G01X762203D02*
X761026D01*
G01X766140D02*
X764963D01*
G01X770077D02*
X768900D01*
G01X774014D02*
X772837D01*
G01X762184Y311066D02*
X761045D01*
G01X770058D02*
X768919D01*
G01X768909Y310799D02*
X770068D01*
G01X761035D02*
X762194D01*
G01X768924Y309279D02*
X770053D01*
G01X761050D02*
X762179D01*
G01X762188Y309011D02*
X761040D01*
G01X770063D02*
X768914D01*
G01X762170Y308563D02*
X761059D01*
G01X770044D02*
X768933D01*
G01X762170Y307578D02*
X761059D01*
G01X770044D02*
X768933D01*
G01X758303Y306102D02*
X757052D01*
G01X762240D02*
X760989D01*
G01X766177D02*
X764926D01*
G01X770114D02*
X768863D01*
G01X774051D02*
X772800D01*
G01X768883Y306032D02*
X770094D01*
G01X772820D02*
X774031D01*
G01X764946D02*
X766157D01*
G01X761009D02*
X762220D01*
G01X757072D02*
X758283D01*
G01X758292Y305806D02*
X757063D01*
G01X762229D02*
X761000D01*
G01X766166D02*
X764937D01*
G01X770103D02*
X768874D01*
G01X774040D02*
X772811D01*
G01X768861Y305191D02*
X770116D01*
G01X772798D02*
X774053D01*
G01X764924D02*
X766179D01*
G01X760987D02*
X762242D01*
G01X757050D02*
X758305D01*
G01X758281Y305104D02*
X757074D01*
G01X762218D02*
X761011D01*
G01X766155D02*
X764948D01*
G01X770092D02*
X768885D01*
G01X774029D02*
X772822D01*
G01X758292Y304822D02*
X757063D01*
G01X762229D02*
X761000D01*
G01X766166D02*
X764937D01*
G01X770103D02*
X768874D01*
G01X774040D02*
X772811D01*
G01X770473Y324212D02*
Y429133D01*
G01X779685Y323228D02*
X763780D01*
G01X760433Y1001574D02*
X757677D01*
G01X764370D02*
X761614D01*
G01X768307D02*
X765551D01*
G01X772244D02*
X769488D01*
G01X772244Y1018110D02*
Y1001574D01*
G01X769488D02*
Y1018110D01*
G01X768307D02*
Y1001574D01*
G01X765551D02*
Y1018110D01*
G01X764370D02*
Y1001574D01*
G01X761614D02*
Y1018110D01*
G01X760433D02*
Y1001574D01*
G01X757677D02*
Y1018110D01*
G01X769488D02*
X772244D01*
G01X765551D02*
X768307D01*
G01X761614D02*
X764370D01*
G01X757677D02*
X760433D01*
G01X785830Y299606D02*
X785842Y300266D01*
G01X785840Y301194D02*
X785809Y299606D01*
G01X781893D02*
X781905Y300266D01*
G01X781903Y301194D02*
X781872Y299606D01*
G01X777956D02*
X777968Y300266D01*
G01X777966Y301194D02*
X777935Y299606D01*
G01X774019D02*
X774031Y300266D01*
G01X774029Y301194D02*
X773998Y299606D01*
G01X788538D02*
X788548Y300197D01*
G01X788546Y301107D02*
X788521Y299606D01*
G01X784601D02*
X784611Y300197D01*
G01X784609Y301107D02*
X784584Y299606D01*
G01X780664D02*
X780674Y300197D01*
G01X780672Y301107D02*
X780647Y299606D01*
G01X776727D02*
X776737Y300197D01*
G01X776735Y301107D02*
X776710Y299606D01*
G01X784672Y297019D02*
X784667Y295232D01*
G01X784657Y295500D02*
X784663Y297287D01*
G01X781879Y293082D02*
X781874Y291295D01*
G01X781864Y291563D02*
X781869Y293350D01*
G01X776798Y297019D02*
X776793Y295232D01*
G01X776783Y295500D02*
X776788Y297287D01*
G01X774005Y293082D02*
X774000Y291295D01*
G01X773990Y291563D02*
X773995Y293350D01*
G01X788740Y290846D02*
Y289862D01*
G01X788585Y294783D02*
Y293799D01*
G01X785825Y294783D02*
Y293799D01*
G01X785670Y298720D02*
Y297736D01*
G01X784803Y298720D02*
Y297736D01*
G01X784648Y293799D02*
Y294783D01*
G01X781888Y293799D02*
Y294783D01*
G01X781733Y290846D02*
Y289862D01*
G01X780866Y290846D02*
Y289862D01*
G01X780711Y294783D02*
Y293799D01*
G01X777951Y294783D02*
Y293799D01*
G01X777796Y298720D02*
Y297736D01*
G01X776929Y298720D02*
Y297736D01*
G01X776774Y293799D02*
Y294783D01*
G01X774014Y293799D02*
Y294783D01*
G01X773859Y290846D02*
Y289862D01*
G01X772992Y290846D02*
Y289862D01*
G01X788604Y293350D02*
X788609Y291563D01*
G01X788600Y291295D02*
X788594Y293082D01*
G01X785811Y297287D02*
X785816Y295500D01*
G01X785806Y295232D02*
X785801Y297019D01*
G01X780730Y293350D02*
X780735Y291563D01*
G01X780725Y291295D02*
X780720Y293082D01*
G01X777937Y297287D02*
X777942Y295500D01*
G01X777932Y295232D02*
X777927Y297019D01*
G01X785889Y299606D02*
X785864Y301107D01*
G01X785862Y300197D02*
X785872Y299606D01*
G01X781952D02*
X781927Y301107D01*
G01X781925Y300197D02*
X781935Y299606D01*
G01X778015D02*
X777990Y301107D01*
G01X777988Y300197D02*
X777998Y299606D01*
G01X774078D02*
X774053Y301107D01*
G01X774051Y300197D02*
X774061Y299606D01*
G01X788601D02*
X788570Y301194D01*
G01X788568Y300266D02*
X788580Y299606D01*
G01X784664D02*
X784633Y301194D01*
G01X784631Y300266D02*
X784643Y299606D01*
G01X780727D02*
X780696Y301194D01*
G01X780694Y300266D02*
X780706Y299606D01*
G01X776790D02*
X776759Y301194D01*
G01X776757Y300266D02*
X776769Y299606D01*
G01X788559Y301477D02*
X789788D01*
G01X784622D02*
X785851D01*
G01X780685D02*
X781914D01*
G01X776748D02*
X777977D01*
G01X788570Y301194D02*
X789777D01*
G01X784633D02*
X785840D01*
G01X780696D02*
X781903D01*
G01X776759D02*
X777966D01*
G01X777990Y301107D02*
X776735D01*
G01X781927D02*
X780672D01*
G01X785864D02*
X784609D01*
G01X789801D02*
X788546D01*
G01X788559Y300492D02*
X789788D01*
G01X784622D02*
X785851D01*
G01X780685D02*
X781914D01*
G01X776748D02*
X777977D01*
G01X777968Y300266D02*
X776757D01*
G01X781905D02*
X780694D01*
G01X785842D02*
X784631D01*
G01X789779D02*
X788568D01*
G01X788548Y300197D02*
X789799D01*
G01X784611D02*
X785862D01*
G01X780674D02*
X781925D01*
G01X776737D02*
X777988D01*
G01X777918Y298720D02*
X776807D01*
G01X785792D02*
X784681D01*
G01Y297736D02*
X785792D01*
G01X776807D02*
X777918D01*
G01X784663Y297287D02*
X785811D01*
G01X776788D02*
X777937D01*
G01X777927Y297019D02*
X776798D01*
G01X785801D02*
X784672D01*
G01X777942Y295500D02*
X776783D01*
G01X785816D02*
X784657D01*
G01X784667Y295232D02*
X785806D01*
G01X776793D02*
X777932D01*
G01X788585Y294783D02*
X789762D01*
G01X784648D02*
X785825D01*
G01X780711D02*
X781888D01*
G01X776774D02*
X777951D01*
G01Y293799D02*
X776774D01*
G01X781888D02*
X780711D01*
G01X785825D02*
X784648D01*
G01X789762D02*
X788585D01*
G01X781869Y293350D02*
X780730D01*
G01X789743D02*
X788604D01*
G01X788594Y293082D02*
X789753D01*
G01X780720D02*
X781879D01*
G01X788609Y291563D02*
X789738D01*
G01X780735D02*
X781864D01*
G01X781874Y291295D02*
X780725D01*
G01X789748D02*
X788600D01*
G01X781855Y290846D02*
X780744D01*
G01X789729D02*
X788618D01*
G01Y289862D02*
X789729D01*
G01X780744D02*
X781855D01*
G01X788570Y305104D02*
X788601Y306692D01*
G01X788580D02*
X788568Y306032D01*
G01X784633Y305104D02*
X784664Y306692D01*
G01X784643D02*
X784631Y306032D01*
G01X780696Y305104D02*
X780727Y306692D01*
G01X780706D02*
X780694Y306032D01*
G01X776759Y305104D02*
X776790Y306692D01*
G01X776769D02*
X776757Y306032D01*
G01X785864Y305191D02*
X785889Y306692D01*
G01X785872D02*
X785862Y306102D01*
G01X781927Y305191D02*
X781952Y306692D01*
G01X781935D02*
X781925Y306102D01*
G01X777990Y305191D02*
X778015Y306692D01*
G01X777998D02*
X777988Y306102D01*
G01X774053Y305191D02*
X774078Y306692D01*
G01X774061D02*
X774051Y306102D01*
G01X788609Y314736D02*
X788604Y312948D01*
G01X788594Y313216D02*
X788600Y315003D01*
G01X785816Y310799D02*
X785811Y309011D01*
G01X785801Y309279D02*
X785806Y311066D01*
G01X780735Y314736D02*
X780730Y312948D01*
G01X780720Y313216D02*
X780725Y315003D01*
G01X777942Y310799D02*
X777937Y309011D01*
G01X777927Y309279D02*
X777932Y311066D01*
G01X788740Y315452D02*
Y316437D01*
G01X788585Y312500D02*
Y311515D01*
G01X785825Y312500D02*
Y311515D01*
G01X785670Y308563D02*
Y307578D01*
G01X784803D02*
Y308563D01*
G01X784685Y323228D02*
Y317618D01*
G01X784648Y311515D02*
Y312500D01*
G01X781888Y311515D02*
Y312500D01*
G01X781733Y316437D02*
Y315452D01*
G01X780866D02*
Y316437D01*
G01X780711Y312500D02*
Y311515D01*
G01X779685Y323228D02*
Y317618D01*
G01X777951Y312500D02*
Y311515D01*
G01X777796Y308563D02*
Y307578D01*
G01X776929D02*
Y308563D01*
G01X776774Y311515D02*
Y312500D01*
G01X774014Y311515D02*
Y312500D01*
G01X773859Y316437D02*
Y315452D01*
G01X772992D02*
Y316437D01*
G01X784667Y311066D02*
X784672Y309279D01*
G01X784663Y309011D02*
X784657Y310799D01*
G01X781874Y315003D02*
X781879Y313216D01*
G01X781869Y312948D02*
X781864Y314736D01*
G01X776793Y311066D02*
X776798Y309279D01*
G01X776788Y309011D02*
X776783Y310799D01*
G01X774000Y315003D02*
X774005Y313216D01*
G01X773995Y312948D02*
X773990Y314736D01*
G01X788548Y306102D02*
X788538Y306692D01*
G01X788521D02*
X788546Y305191D01*
G01X784611Y306102D02*
X784601Y306692D01*
G01X784584D02*
X784609Y305191D01*
G01X780674Y306102D02*
X780664Y306692D01*
G01X780647D02*
X780672Y305191D01*
G01X776737Y306102D02*
X776727Y306692D01*
G01X776710D02*
X776735Y305191D01*
G01X785842Y306032D02*
X785830Y306692D01*
G01X785809D02*
X785840Y305104D01*
G01X781905Y306032D02*
X781893Y306692D01*
G01X781872D02*
X781903Y305104D01*
G01X777968Y306032D02*
X777956Y306692D01*
G01X777935D02*
X777966Y305104D01*
G01X774031Y306032D02*
X774019Y306692D01*
G01X773998D02*
X774029Y305104D01*
G01X781855Y316437D02*
X780744D01*
G01X789729D02*
X788618D01*
G01X781855Y315452D02*
X780744D01*
G01X789729D02*
X788618D01*
G01X788600Y315003D02*
X789748D01*
G01X780725D02*
X781874D01*
G01X781864Y314736D02*
X780735D01*
G01X789738D02*
X788609D01*
G01X781879Y313216D02*
X780720D01*
G01X789753D02*
X788594D01*
G01X788604Y312948D02*
X789743D01*
G01X780730D02*
X781869D01*
G01X777951Y312500D02*
X776774D01*
G01X781888D02*
X780711D01*
G01X785825D02*
X784648D01*
G01X789762D02*
X788585D01*
G01X777951Y311515D02*
X776774D01*
G01X781888D02*
X780711D01*
G01X785825D02*
X784648D01*
G01X789762D02*
X788585D01*
G01X777932Y311066D02*
X776793D01*
G01X785806D02*
X784667D01*
G01X784657Y310799D02*
X785816D01*
G01X776783D02*
X777942D01*
G01X784672Y309279D02*
X785801D01*
G01X776798D02*
X777927D01*
G01X777937Y309011D02*
X776788D01*
G01X785811D02*
X784663D01*
G01X777918Y308563D02*
X776807D01*
G01X785792D02*
X784681D01*
G01X777918Y307578D02*
X776807D01*
G01X785792D02*
X784681D01*
G01X777988Y306102D02*
X776737D01*
G01X781925D02*
X780674D01*
G01X785862D02*
X784611D01*
G01X789799D02*
X788548D01*
G01X788568Y306032D02*
X789779D01*
G01X784631D02*
X785842D01*
G01X780694D02*
X781905D01*
G01X776757D02*
X777968D01*
G01X777977Y305806D02*
X776748D01*
G01X781914D02*
X780685D01*
G01X785851D02*
X784622D01*
G01X789788D02*
X788559D01*
G01X788546Y305191D02*
X789801D01*
G01X784609D02*
X785864D01*
G01X780672D02*
X781927D01*
G01X776735D02*
X777990D01*
G01X777966Y305104D02*
X776759D01*
G01X781903D02*
X780696D01*
G01X785840D02*
X784633D01*
G01X789777D02*
X788570D01*
G01X777977Y304822D02*
X776748D01*
G01X781914D02*
X780685D01*
G01X785851D02*
X784622D01*
G01X789788D02*
X788559D01*
G01X800591Y323228D02*
X784685D01*
G01X776181Y1001574D02*
X773425D01*
G01X780118D02*
X777363D01*
G01X784055D02*
X781300D01*
G01X787992D02*
X785237D01*
G01X791929D02*
X789174D01*
G01D02*
Y1018110D01*
G01X787992D02*
Y1001574D01*
G01X785237D02*
Y1018110D01*
G01X784055D02*
Y1001574D01*
G01X781300D02*
Y1018110D01*
G01X780118D02*
Y1001574D01*
G01X777363D02*
Y1018110D01*
G01X776181D02*
Y1001574D01*
G01X773425D02*
Y1018110D01*
G01X789174D02*
X791929D01*
G01X785237D02*
X787992D01*
G01X781300D02*
X784055D01*
G01X773425D02*
X776181D01*
G01X777363D02*
X780118D01*
G01X805515Y299606D02*
X805527Y300266D01*
G01X805525Y301194D02*
X805494Y299606D01*
G01X801578D02*
X801590Y300266D01*
G01X801588Y301194D02*
X801557Y299606D01*
G01X797641D02*
X797653Y300266D01*
G01X797651Y301194D02*
X797620Y299606D01*
G01X793704D02*
X793716Y300266D01*
G01X793714Y301194D02*
X793683Y299606D01*
G01X789767D02*
X789779Y300266D01*
G01X789777Y301194D02*
X789746Y299606D01*
G01X804287D02*
X804296Y300197D01*
G01X804294Y301107D02*
X804269Y299606D01*
G01X800350D02*
X800359Y300197D01*
G01X800357Y301107D02*
X800332Y299606D01*
G01X796413D02*
X796422Y300197D01*
G01X796420Y301107D02*
X796395Y299606D01*
G01X792475D02*
X792485Y300197D01*
G01X792483Y301107D02*
X792458Y299606D01*
G01X805501Y293082D02*
X805496Y291295D01*
G01X805487Y291563D02*
X805491Y293350D01*
G01X800420Y297019D02*
X800415Y295232D01*
G01X800405Y295500D02*
X800411Y297287D01*
G01X797627Y293082D02*
X797622Y291295D01*
G01X797613Y291563D02*
X797617Y293350D01*
G01X792546Y297019D02*
X792541Y295232D01*
G01X792531Y295500D02*
X792537Y297287D01*
G01X789753Y293082D02*
X789748Y291295D01*
G01X789738Y291563D02*
X789743Y293350D01*
G01X805510Y293799D02*
Y294783D01*
G01X805355Y290846D02*
Y289862D01*
G01X804488Y290846D02*
Y289862D01*
G01X804333Y294783D02*
Y293799D01*
G01X801573Y294783D02*
Y293799D01*
G01X801418Y298720D02*
Y297736D01*
G01X800551Y298720D02*
Y297736D01*
G01X800396Y293799D02*
Y294783D01*
G01X797636Y293799D02*
Y294783D01*
G01X797481Y290846D02*
Y289862D01*
G01X796614Y290846D02*
Y289862D01*
G01X796459Y294783D02*
Y293799D01*
G01X793699Y294783D02*
Y293799D01*
G01X793544Y298720D02*
Y297736D01*
G01X792677Y298720D02*
Y297736D01*
G01X792522Y293799D02*
Y294783D01*
G01X789762Y293799D02*
Y294783D01*
G01X789607Y290846D02*
Y289862D01*
G01X804352Y293350D02*
X804357Y291563D01*
G01X804348Y291295D02*
X804342Y293082D01*
G01X801559Y297287D02*
X801564Y295500D01*
G01X801554Y295232D02*
X801550Y297019D01*
G01X796478Y293350D02*
X796483Y291563D01*
G01X796474Y291295D02*
X796468Y293082D01*
G01X793685Y297287D02*
X793690Y295500D01*
G01X793680Y295232D02*
X793675Y297019D01*
G01X805574Y299606D02*
X805550Y301107D01*
G01X805547Y300197D02*
X805557Y299606D01*
G01X801637D02*
X801613Y301107D01*
G01X801610Y300197D02*
X801620Y299606D01*
G01X797700D02*
X797675Y301107D01*
G01X797673Y300197D02*
X797683Y299606D01*
G01X793763D02*
X793738Y301107D01*
G01X793736Y300197D02*
X793746Y299606D01*
G01X789826D02*
X789801Y301107D01*
G01X789799Y300197D02*
X789809Y299606D01*
G01X804349D02*
X804318Y301194D01*
G01X804316Y300266D02*
X804328Y299606D01*
G01X800412D02*
X800381Y301194D01*
G01X800379Y300266D02*
X800391Y299606D01*
G01X796475D02*
X796444Y301194D01*
G01X796442Y300266D02*
X796454Y299606D01*
G01X792538D02*
X792507Y301194D01*
G01X792505Y300266D02*
X792517Y299606D01*
G01X804307Y301477D02*
X805537D01*
G01X800370D02*
X801600D01*
G01X796433D02*
X797663D01*
G01X792496D02*
X793725D01*
G01X804318Y301194D02*
X805525D01*
G01X800381D02*
X801588D01*
G01X796444D02*
X797651D01*
G01X792507D02*
X793714D01*
G01X793738Y301107D02*
X792483D01*
G01X801613D02*
X800357D01*
G01X797675D02*
X796420D01*
G01X805550D02*
X804294D01*
G01X804307Y300492D02*
X805537D01*
G01X800370D02*
X801600D01*
G01X796433D02*
X797663D01*
G01X792496D02*
X793725D01*
G01X793716Y300266D02*
X792505D01*
G01X801590D02*
X800379D01*
G01X797653D02*
X796442D01*
G01X805527D02*
X804316D01*
G01X804296Y300197D02*
X805547D01*
G01X800359D02*
X801610D01*
G01X796422D02*
X797673D01*
G01X792485D02*
X793736D01*
G01X793666Y298720D02*
X792555D01*
G01X801540D02*
X800429D01*
G01Y297736D02*
X801540D01*
G01X792555D02*
X793666D01*
G01X800411Y297287D02*
X801559D01*
G01X792537D02*
X793685D01*
G01X793675Y297019D02*
X792546D01*
G01X801550D02*
X800420D01*
G01X793690Y295500D02*
X792531D01*
G01X801564D02*
X800405D01*
G01X800415Y295232D02*
X801554D01*
G01X792541D02*
X793680D01*
G01X804333Y294783D02*
X805510D01*
G01X800396D02*
X801573D01*
G01X796459D02*
X797636D01*
G01X792522D02*
X793699D01*
G01Y293799D02*
X792522D01*
G01X801573D02*
X800396D01*
G01X797636D02*
X796459D01*
G01X805510D02*
X804333D01*
G01X797617Y293350D02*
X796478D01*
G01X805491D02*
X804352D01*
G01X804342Y293082D02*
X805501D01*
G01X796468D02*
X797627D01*
G01X804357Y291563D02*
X805487D01*
G01X796483D02*
X797613D01*
G01X797622Y291295D02*
X796474D01*
G01X805496D02*
X804348D01*
G01X797603Y290846D02*
X796492D01*
G01X805477D02*
X804366D01*
G01Y289862D02*
X805477D01*
G01X796492D02*
X797603D01*
G01X804318Y305104D02*
X804349Y306692D01*
G01X804328D02*
X804316Y306032D01*
G01X800381Y305104D02*
X800412Y306692D01*
G01X800391D02*
X800379Y306032D01*
G01X796444Y305104D02*
X796475Y306692D01*
G01X796454D02*
X796442Y306032D01*
G01X792507Y305104D02*
X792538Y306692D01*
G01X792517D02*
X792505Y306032D01*
G01X805550Y305191D02*
X805574Y306692D01*
G01X805557D02*
X805547Y306102D01*
G01X801613Y305191D02*
X801637Y306692D01*
G01X801620D02*
X801610Y306102D01*
G01X797675Y305191D02*
X797700Y306692D01*
G01X797683D02*
X797673Y306102D01*
G01X793738Y305191D02*
X793763Y306692D01*
G01X793746D02*
X793736Y306102D01*
G01X789801Y305191D02*
X789826Y306692D01*
G01X789809D02*
X789799Y306102D01*
G01X804357Y314736D02*
X804352Y312948D01*
G01X804342Y313216D02*
X804348Y315003D01*
G01X801564Y310799D02*
X801559Y309011D01*
G01X801549Y309279D02*
X801554Y311066D01*
G01X796483Y314736D02*
X796478Y312948D01*
G01X796468Y313216D02*
X796474Y315003D01*
G01X793690Y310799D02*
X793685Y309011D01*
G01X793675Y309279D02*
X793680Y311066D01*
G01X805591Y323228D02*
Y317618D01*
G01X805510Y312500D02*
Y311515D01*
G01X805355Y316437D02*
Y315452D01*
G01X804488D02*
Y316437D01*
G01X804333Y311515D02*
Y312500D01*
G01X801573D02*
Y311515D01*
G01X801418Y308563D02*
Y307578D01*
G01X800591Y323228D02*
Y317618D01*
G01X800551Y307578D02*
Y308563D01*
G01X800396Y311515D02*
Y312500D01*
G01X797636Y311515D02*
Y312500D01*
G01X797481Y316437D02*
Y315452D01*
G01X796614D02*
Y316437D01*
G01X796459Y312500D02*
Y311515D01*
G01X793699D02*
Y312500D01*
G01X793544Y308563D02*
Y307578D01*
G01X792677D02*
Y308563D01*
G01X792522Y312500D02*
Y311515D01*
G01X789762D02*
Y312500D01*
G01X789607Y316437D02*
Y315452D01*
G01X805496Y315003D02*
X805501Y313216D01*
G01X805491Y312948D02*
X805486Y314736D01*
G01X800415Y311066D02*
X800420Y309279D01*
G01X800411Y309011D02*
X800405Y310799D01*
G01X797622Y315003D02*
X797627Y313216D01*
G01X797617Y312948D02*
X797612Y314736D01*
G01X792541Y311066D02*
X792546Y309279D01*
G01X792537Y309011D02*
X792531Y310799D01*
G01X789748Y315003D02*
X789753Y313216D01*
G01X789743Y312948D02*
X789738Y314736D01*
G01X804296Y306102D02*
X804287Y306692D01*
G01X804269D02*
X804294Y305191D01*
G01X800359Y306102D02*
X800350Y306692D01*
G01X800332D02*
X800357Y305191D01*
G01X796422Y306102D02*
X796413Y306692D01*
G01X796395D02*
X796420Y305191D01*
G01X792485Y306102D02*
X792475Y306692D01*
G01X792458D02*
X792483Y305191D01*
G01X805527Y306032D02*
X805515Y306692D01*
G01X805494D02*
X805525Y305104D01*
G01X801590Y306032D02*
X801578Y306692D01*
G01X801557D02*
X801588Y305104D01*
G01X797653Y306032D02*
X797641Y306692D01*
G01X797620D02*
X797651Y305104D01*
G01X793716Y306032D02*
X793704Y306692D01*
G01X793683D02*
X793714Y305104D01*
G01X789779Y306032D02*
X789767Y306692D01*
G01X789746D02*
X789777Y305104D01*
G01X797603Y316437D02*
X796492D01*
G01X805477D02*
X804366D01*
G01X797603Y315452D02*
X796492D01*
G01X805477D02*
X804366D01*
G01X804348Y315003D02*
X805496D01*
G01X796474D02*
X797622D01*
G01X797612Y314736D02*
X796483D01*
G01X805486D02*
X804357D01*
G01X797627Y313216D02*
X796468D01*
G01X805501D02*
X804342D01*
G01X804352Y312948D02*
X805491D01*
G01X796478D02*
X797617D01*
G01X793699Y312500D02*
X792522D01*
G01X801573D02*
X800396D01*
G01X797636D02*
X796459D01*
G01X805510D02*
X804333D01*
G01X793699Y311515D02*
X792522D01*
G01X801573D02*
X800396D01*
G01X797636D02*
X796459D01*
G01X805510D02*
X804333D01*
G01X793680Y311066D02*
X792541D01*
G01X801554D02*
X800415D01*
G01X800405Y310799D02*
X801564D01*
G01X792531D02*
X793690D01*
G01X800420Y309279D02*
X801549D01*
G01X792546D02*
X793675D01*
G01X793685Y309011D02*
X792537D01*
G01X801559D02*
X800411D01*
G01X793666Y308563D02*
X792555D01*
G01X801540D02*
X800429D01*
G01X793666Y307578D02*
X792555D01*
G01X801540D02*
X800429D01*
G01X793736Y306102D02*
X792485D01*
G01X801610D02*
X800359D01*
G01X797673D02*
X796422D01*
G01X805547D02*
X804296D01*
G01X804316Y306032D02*
X805527D01*
G01X800379D02*
X801590D01*
G01X796442D02*
X797653D01*
G01X792505D02*
X793716D01*
G01X793725Y305806D02*
X792496D01*
G01X801600D02*
X800370D01*
G01X797663D02*
X796433D01*
G01X805537D02*
X804307D01*
G01X804294Y305191D02*
X805550D01*
G01X800357D02*
X801613D01*
G01X796420D02*
X797675D01*
G01X792483D02*
X793738D01*
G01X793714Y305104D02*
X792507D01*
G01X801588D02*
X800381D01*
G01X797651D02*
X796444D01*
G01X805525D02*
X804318D01*
G01X793725Y304822D02*
X792496D01*
G01X801600D02*
X800370D01*
G01X797663D02*
X796433D01*
G01X805537D02*
X804307D01*
G01X821496Y323228D02*
X805591D01*
G01X804987Y363031D02*
Y369813D01*
G01X796536D02*
Y363031D01*
G01X794725D02*
Y377519D01*
G01X796536Y363031D02*
X794725D01*
G01X806798D02*
X804987D01*
G01Y371662D02*
Y377519D01*
G01X796536D02*
Y371662D01*
G01X804987Y377519D02*
X806798D01*
G01X794725D02*
X796536D01*
G01Y371662D02*
X804987D01*
G01Y369813D02*
X796536D01*
G01X797047Y992126D02*
Y1018109D01*
G01X797048Y992126D02*
G03X800984Y988189I3937J0D01*
G01X902165D02*
X800984D01*
G01X797048Y992126D02*
G03X800985Y988189I3937J0D01*
G01X902166D02*
X800985D01*
G01X797048Y992126D02*
Y1021653D01*
G01X859109Y996063D02*
X804922D01*
G01D02*
Y1023622D01*
G01X859109Y996063D02*
X804922D01*
G01D02*
Y1023622D01*
G01X795866Y1001574D02*
X793111D01*
G01X795866Y1018110D02*
Y1001574D01*
G01X793111D02*
Y1018110D01*
G01X791929D02*
Y1001574D01*
G01X804922Y1023622D02*
X1325399D01*
G01X804922D02*
X1325399D01*
G01X797048Y1021653D02*
X797047Y1018109D01*
G01X797048Y1021653D02*
X795079Y1023622D01*
G01X793111Y1018110D02*
X795866D01*
G01X797048Y1021653D02*
X795079Y1023622D01*
G01X795464Y1028712D02*
X795665Y1028610D01*
G01X795164Y1030347D02*
X794864Y1030450D01*
G01Y1028405D02*
X795164Y1028303D01*
G01X794764Y1031063D02*
X795264Y1030960D01*
G01X797466Y1031063D02*
X798066D01*
G01X792363D02*
X794764D01*
G01X794864Y1030450D02*
X792963D01*
G01Y1029019D02*
X794864D01*
G01X792963Y1028405D02*
X794864D01*
G01Y1026872D02*
X792963D01*
G01X794764Y1026259D02*
X792363D01*
G01X798066D02*
X797466D01*
G01X795264Y1026362D02*
X794764Y1026259D01*
G01X795264Y1030960D02*
X795665Y1030654D01*
G01X795364Y1030143D02*
X795164Y1030347D01*
G01Y1028303D02*
X795364Y1028099D01*
G01X795665Y1030654D02*
X795965Y1030245D01*
G01X795665Y1028610D02*
X795965Y1028201D01*
G01Y1030245D02*
X796065Y1029939D01*
G01X795464Y1029836D02*
X795364Y1030143D01*
G01X795965Y1028201D02*
X796065Y1027894D01*
G01X795364Y1028099D02*
X795464Y1027792D01*
G01X798066Y1031063D02*
Y1026259D01*
G01X797466D02*
Y1030245D01*
G01X796866Y1029529D02*
Y1030347D01*
G01X796065Y1027894D02*
Y1027383D01*
G01Y1029939D02*
Y1029529D01*
G01X795464Y1029632D02*
Y1029836D01*
G01Y1027792D02*
Y1027486D01*
G01X792963Y1026872D02*
Y1028405D01*
G01Y1030450D02*
Y1029019D01*
G01X792363Y1026259D02*
Y1031063D01*
G01X796065Y1027383D02*
X795965Y1027077D01*
G01X795464Y1027486D02*
X795364Y1027179D01*
G01X796065Y1029529D02*
X795965Y1029223D01*
G01X795364Y1029325D02*
X795464Y1029632D01*
G01X795965Y1027077D02*
X795665Y1026668D01*
G01X795965Y1029223D02*
X795665Y1028814D01*
G01X795364Y1027179D02*
X795164Y1026975D01*
G01Y1029121D02*
X795364Y1029325D01*
G01X797466Y1030245D02*
X796866Y1029529D01*
G01Y1030347D02*
X797466Y1031063D01*
G01X795665Y1026668D02*
X795264Y1026362D01*
G01X795164Y1026975D02*
X794864Y1026872D01*
G01Y1029019D02*
X795164Y1029121D01*
G01X795665Y1028814D02*
X795464Y1028712D01*
G01X821263Y299606D02*
X821275Y300266D01*
G01X821273Y301194D02*
X821242Y299606D01*
G01X817326D02*
X817338Y300266D01*
G01X817336Y301194D02*
X817305Y299606D01*
G01X813389D02*
X813401Y300266D01*
G01X813399Y301194D02*
X813368Y299606D01*
G01X809452D02*
X809464Y300266D01*
G01X809462Y301194D02*
X809431Y299606D01*
G01X820035D02*
X820044Y300197D01*
G01X820042Y301107D02*
X820017Y299606D01*
G01X816098D02*
X816107Y300197D01*
G01X816105Y301107D02*
X816080Y299606D01*
G01X812161D02*
X812170Y300197D01*
G01X812168Y301107D02*
X812143Y299606D01*
G01X808224D02*
X808233Y300197D01*
G01X808231Y301107D02*
X808206Y299606D01*
G01X821249Y293082D02*
X821244Y291295D01*
G01X821235Y291563D02*
X821239Y293350D01*
G01X816168Y297019D02*
X816163Y295232D01*
G01X816153Y295500D02*
X816159Y297287D01*
G01X813375Y293082D02*
X813370Y291295D01*
G01X813361Y291563D02*
X813365Y293350D01*
G01X808294Y297019D02*
X808289Y295232D01*
G01X808279Y295500D02*
X808285Y297287D01*
G01X821654Y290157D02*
Y290354D01*
G01X821258Y293799D02*
Y294783D01*
G01X821103Y290846D02*
Y289862D01*
G01X820237Y290846D02*
Y289862D01*
G01X820081Y294783D02*
Y293799D01*
G01X817321Y294783D02*
Y293799D01*
G01X817166Y298720D02*
Y297736D01*
G01X816300Y298720D02*
Y297736D01*
G01X816144Y293799D02*
Y294783D01*
G01X814272Y290157D02*
Y290354D01*
G01X813384Y293799D02*
Y294783D01*
G01X813229Y290846D02*
Y289862D01*
G01X812796Y290354D02*
Y290157D01*
G01X812363Y290846D02*
Y289862D01*
G01X812207Y294783D02*
Y293799D01*
G01X809447Y294783D02*
Y293799D01*
G01X809292Y298720D02*
Y297736D01*
G01X808425Y298720D02*
Y297736D01*
G01X808270Y293799D02*
Y294783D01*
G01X820100Y293350D02*
X820105Y291563D01*
G01X820096Y291295D02*
X820090Y293082D01*
G01X817307Y297287D02*
X817312Y295500D01*
G01X817302Y295232D02*
X817298Y297019D01*
G01X812226Y293350D02*
X812231Y291563D01*
G01X812222Y291295D02*
X812216Y293082D01*
G01X809433Y297287D02*
X809438Y295500D01*
G01X809428Y295232D02*
X809424Y297019D01*
G01X821322Y299606D02*
X821298Y301107D01*
G01X821295Y300197D02*
X821305Y299606D01*
G01X817385D02*
X817361Y301107D01*
G01X817358Y300197D02*
X817368Y299606D01*
G01X813448D02*
X813424Y301107D01*
G01X813421Y300197D02*
X813431Y299606D01*
G01X809511D02*
X809487Y301107D01*
G01X809484Y300197D02*
X809494Y299606D01*
G01X820097D02*
X820066Y301194D01*
G01X820064Y300266D02*
X820076Y299606D01*
G01X816160D02*
X816129Y301194D01*
G01X816127Y300266D02*
X816139Y299606D01*
G01X812223D02*
X812192Y301194D01*
G01X812190Y300266D02*
X812202Y299606D01*
G01X808286D02*
X808255Y301194D01*
G01X808253Y300266D02*
X808265Y299606D01*
G01X820055Y301477D02*
X821285D01*
G01X816118D02*
X817348D01*
G01X812181D02*
X813411D01*
G01X808244D02*
X809474D01*
G01X820066Y301194D02*
X821273D01*
G01X816129D02*
X817336D01*
G01X812192D02*
X813399D01*
G01X808255D02*
X809462D01*
G01X809487Y301107D02*
X808231D01*
G01X813424D02*
X812168D01*
G01X817361D02*
X816105D01*
G01X821298D02*
X820042D01*
G01X820055Y300492D02*
X821285D01*
G01X816118D02*
X817348D01*
G01X812181D02*
X813411D01*
G01X808244D02*
X809474D01*
G01X809464Y300266D02*
X808253D01*
G01X813401D02*
X812190D01*
G01X817338D02*
X816127D01*
G01X821275D02*
X820064D01*
G01X820044Y300197D02*
X821295D01*
G01X816107D02*
X817358D01*
G01X812170D02*
X813421D01*
G01X808233D02*
X809484D01*
G01X809414Y298720D02*
X808303D01*
G01X817288D02*
X816177D01*
G01Y297736D02*
X817288D01*
G01X808303D02*
X809414D01*
G01X816159Y297287D02*
X817307D01*
G01X808285D02*
X809433D01*
G01X809424Y297019D02*
X808294D01*
G01X817298D02*
X816168D01*
G01X809438Y295500D02*
X808279D01*
G01X817312D02*
X816153D01*
G01X816163Y295232D02*
X817302D01*
G01X808289D02*
X809428D01*
G01X820081Y294783D02*
X821258D01*
G01X816144D02*
X817321D01*
G01X812207D02*
X813384D01*
G01X808270D02*
X809447D01*
G01Y293799D02*
X808270D01*
G01X813384D02*
X812207D01*
G01X817321D02*
X816144D01*
G01X821258D02*
X820081D01*
G01X813365Y293350D02*
X812226D01*
G01X821239D02*
X820100D01*
G01X820090Y293082D02*
X821249D01*
G01X812216D02*
X813375D01*
G01X820105Y291563D02*
X821235D01*
G01X812231D02*
X813361D01*
G01X813370Y291295D02*
X812222D01*
G01X821244D02*
X820096D01*
G01X813351Y290846D02*
X812240D01*
G01X821225D02*
X820114D01*
G01X821654Y290157D02*
X812796D01*
G01X820114Y289862D02*
X821225D01*
G01X812240D02*
X813351D01*
G01X820066Y305104D02*
X820097Y306692D01*
G01X820076D02*
X820064Y306032D01*
G01X816129Y305104D02*
X816160Y306692D01*
G01X816139D02*
X816127Y306032D01*
G01X812192Y305104D02*
X812223Y306692D01*
G01X812202D02*
X812190Y306032D01*
G01X808255Y305104D02*
X808286Y306692D01*
G01X808265D02*
X808253Y306032D01*
G01X821298Y305191D02*
X821322Y306692D01*
G01X821305D02*
X821295Y306102D01*
G01X817361Y305191D02*
X817385Y306692D01*
G01X817368D02*
X817358Y306102D01*
G01X813424Y305191D02*
X813448Y306692D01*
G01X813431D02*
X813421Y306102D01*
G01X809487Y305191D02*
X809511Y306692D01*
G01X809494D02*
X809484Y306102D01*
G01X820105Y314736D02*
X820100Y312948D01*
G01X820090Y313216D02*
X820096Y315003D01*
G01X817312Y310799D02*
X817307Y309011D01*
G01X817297Y309279D02*
X817302Y311066D01*
G01X812231Y314736D02*
X812226Y312948D01*
G01X812216Y313216D02*
X812222Y315003D01*
G01X809438Y310799D02*
X809433Y309011D01*
G01X809423Y309279D02*
X809428Y311066D01*
G01X822146Y315748D02*
Y315944D01*
G01X821654Y315748D02*
Y315944D01*
G01X821496Y323228D02*
Y317618D01*
G01X821408Y315748D02*
Y315944D01*
G01X821258Y311515D02*
Y312500D01*
G01X821162Y315748D02*
Y315944D01*
G01X821103Y316437D02*
Y315452D01*
G01X820916Y315748D02*
Y315944D01*
G01X820670Y315748D02*
Y315944D01*
G01X820237Y315452D02*
Y316437D01*
G01X820177Y315748D02*
Y315944D01*
G01X820081Y312500D02*
Y311515D01*
G01X819931Y315748D02*
Y315944D01*
G01X819685Y315748D02*
Y315944D01*
G01X819193Y315748D02*
Y315944D01*
G01X817963Y315748D02*
Y315944D01*
G01X817717Y315748D02*
Y315944D01*
G01X817321Y312500D02*
Y311515D01*
G01X817166Y308563D02*
Y307578D01*
G01X816979Y315748D02*
Y315944D01*
G01X816733Y315748D02*
Y315944D01*
G01X816487Y315748D02*
Y315944D01*
G01X816300Y307578D02*
Y308563D01*
G01X816240Y315944D02*
Y315748D01*
G01X816144Y311515D02*
Y312500D01*
G01X815994Y315748D02*
Y315944D01*
G01X815748Y315748D02*
Y315944D01*
G01X815502Y315748D02*
Y315944D01*
G01X815010Y315748D02*
Y315944D01*
G01X814764Y315748D02*
Y315944D01*
G01X814518Y315748D02*
Y315944D01*
G01X814026Y315748D02*
Y315944D01*
G01X813384Y311515D02*
Y312500D01*
G01X813229Y316437D02*
Y315452D01*
G01X812363D02*
Y316437D01*
G01X812207Y312500D02*
Y311515D01*
G01X809447Y312500D02*
Y311515D01*
G01X809292Y308563D02*
Y307578D01*
G01X808425D02*
Y308563D01*
G01X808270Y311515D02*
Y312500D01*
G01X821244Y315003D02*
X821249Y313216D01*
G01X821239Y312948D02*
X821234Y314736D01*
G01X816163Y311066D02*
X816168Y309279D01*
G01X816159Y309011D02*
X816153Y310799D01*
G01X813370Y315003D02*
X813375Y313216D01*
G01X813365Y312948D02*
X813360Y314736D01*
G01X808289Y311066D02*
X808294Y309279D01*
G01X808285Y309011D02*
X808279Y310799D01*
G01X820044Y306102D02*
X820035Y306692D01*
G01X820017D02*
X820042Y305191D01*
G01X816107Y306102D02*
X816098Y306692D01*
G01X816080D02*
X816105Y305191D01*
G01X812170Y306102D02*
X812161Y306692D01*
G01X812143D02*
X812168Y305191D01*
G01X808233Y306102D02*
X808224Y306692D01*
G01X808206D02*
X808231Y305191D01*
G01X821275Y306032D02*
X821263Y306692D01*
G01X821242D02*
X821273Y305104D01*
G01X817338Y306032D02*
X817326Y306692D01*
G01X817305D02*
X817336Y305104D01*
G01X813401Y306032D02*
X813389Y306692D01*
G01X813368D02*
X813399Y305104D01*
G01X809464Y306032D02*
X809452Y306692D01*
G01X809431D02*
X809462Y305104D01*
G01X813351Y316437D02*
X812240D01*
G01X821225D02*
X820114D01*
G01X823130Y315748D02*
X814026D01*
G01X813351Y315452D02*
X812240D01*
G01X821225D02*
X820114D01*
G01X820096Y315003D02*
X821244D01*
G01X812222D02*
X813370D01*
G01X813360Y314736D02*
X812231D01*
G01X821234D02*
X820105D01*
G01X813375Y313216D02*
X812216D01*
G01X821249D02*
X820090D01*
G01X820100Y312948D02*
X821239D01*
G01X812226D02*
X813365D01*
G01X809447Y312500D02*
X808270D01*
G01X813384D02*
X812207D01*
G01X817321D02*
X816144D01*
G01X821258D02*
X820081D01*
G01X809447Y311515D02*
X808270D01*
G01X813384D02*
X812207D01*
G01X817321D02*
X816144D01*
G01X821258D02*
X820081D01*
G01X809428Y311066D02*
X808289D01*
G01X817302D02*
X816163D01*
G01X816153Y310799D02*
X817312D01*
G01X808279D02*
X809438D01*
G01X816168Y309279D02*
X817297D01*
G01X808294D02*
X809423D01*
G01X809433Y309011D02*
X808285D01*
G01X817307D02*
X816159D01*
G01X809414Y308563D02*
X808303D01*
G01X817288D02*
X816177D01*
G01X809414Y307578D02*
X808303D01*
G01X817288D02*
X816177D01*
G01X809484Y306102D02*
X808233D01*
G01X813421D02*
X812170D01*
G01X817358D02*
X816107D01*
G01X821295D02*
X820044D01*
G01X820064Y306032D02*
X821275D01*
G01X816127D02*
X817338D01*
G01X812190D02*
X813401D01*
G01X808253D02*
X809464D01*
G01X809474Y305806D02*
X808244D01*
G01X813411D02*
X812181D01*
G01X817348D02*
X816118D01*
G01X821285D02*
X820055D01*
G01X820042Y305191D02*
X821298D01*
G01X816105D02*
X817361D01*
G01X812168D02*
X813424D01*
G01X808231D02*
X809487D01*
G01X809462Y305104D02*
X808255D01*
G01X813399D02*
X812192D01*
G01X817336D02*
X816129D01*
G01X821273D02*
X820066D01*
G01X809474Y304822D02*
X808244D01*
G01X813411D02*
X812181D01*
G01X817348D02*
X816118D01*
G01X821285D02*
X820055D01*
G01X820079Y377519D02*
Y363031D01*
G01X818268D02*
Y375053D01*
G01X814042Y369196D02*
Y367963D01*
G01X809213D02*
Y369196D01*
G01X806798Y377519D02*
Y363031D01*
G01X814042Y367963D02*
X809213D01*
G01X820079Y363031D02*
X818268D01*
G01Y375053D02*
X816457Y372895D01*
G01Y375361D02*
X818268Y377519D01*
G01X816457Y372895D02*
Y375361D01*
G01X814042Y372895D02*
Y371662D01*
G01X809213D02*
Y372895D01*
G01X818268Y377519D02*
X820079D01*
G01X809213Y372895D02*
X814042D01*
G01Y371662D02*
X809213D01*
G01Y369196D02*
X814042D01*
G01X823426Y301675D02*
G03Y304623I2559J1474D01*
G01X823425Y299903D02*
G03X829725Y301389I2560J3246D01*
G01X823425Y299534D02*
G03X829725Y300777I2559J3615D01*
G01X837011Y299606D02*
X837024Y300266D01*
G01X837021Y301194D02*
X836990Y299606D01*
G01X833074D02*
X833087Y300266D01*
G01X833084Y301194D02*
X833053Y299606D01*
G01X835783D02*
X835792Y300197D01*
G01X835790Y301107D02*
X835765Y299606D01*
G01X831846D02*
X831855Y300197D01*
G01X831853Y301107D02*
X831828Y299606D01*
G01X836997Y293082D02*
X836992Y291295D01*
G01X836983Y291563D02*
X836987Y293350D01*
G01X831916Y297019D02*
X831911Y295232D01*
G01X831901Y295500D02*
X831907Y297287D01*
G01X837006Y294783D02*
Y293799D01*
G01X836851Y290846D02*
Y289862D01*
G01X835985Y290846D02*
Y289862D01*
G01X835829Y293799D02*
Y294783D01*
G01X835433Y290157D02*
Y290354D01*
G01X833465Y290157D02*
Y290354D01*
G01X833219Y290157D02*
Y290354D01*
G01X833069Y294783D02*
Y293799D01*
G01X832914Y298720D02*
Y297736D01*
G01X832727Y290157D02*
Y290354D01*
G01X832048Y298720D02*
Y297736D01*
G01X831988Y290354D02*
Y290157D01*
G01X831892Y293799D02*
Y294783D01*
G01X831742Y290354D02*
Y290157D01*
G01X835848Y293350D02*
X835853Y291563D01*
G01X835844Y291295D02*
X835838Y293082D01*
G01X833055Y297287D02*
X833060Y295500D01*
G01X833050Y295232D02*
X833046Y297019D01*
G01X837070Y299606D02*
X837046Y301107D01*
G01X837043Y300197D02*
X837053Y299606D01*
G01X835845D02*
X835814Y301194D01*
G01X835812Y300266D02*
X835824Y299606D01*
G01X831250Y290354D02*
Y290157D01*
G01X830758D02*
Y290354D01*
G01X830512D02*
Y290157D01*
G01X830118Y299606D02*
Y306692D01*
G01X829725Y305522D02*
Y300777D01*
G01X829528Y290354D02*
Y290157D01*
G01X829521Y298031D02*
Y299606D01*
G01X827559Y290354D02*
Y290157D01*
G01X826575Y290354D02*
Y290157D01*
G01X826329D02*
Y290354D01*
G01X825837D02*
Y290157D01*
G01X825345Y290354D02*
Y290157D01*
G01X825099Y290354D02*
Y290157D01*
G01X824361D02*
Y290354D01*
G01X823868Y290157D02*
Y290354D01*
G01X823629Y299606D02*
Y298031D01*
G01X823622Y290157D02*
Y290354D01*
G01X823425Y306764D02*
Y299534D01*
G01X823032Y306692D02*
Y299606D01*
G01X833133D02*
X833109Y301107D01*
G01X833106Y300197D02*
X833116Y299606D01*
G01X831908D02*
X831877Y301194D01*
G01X831875Y300266D02*
X831887Y299606D01*
G01X835803Y301477D02*
X837033D01*
G01X831866D02*
X833096D01*
G01X835814Y301194D02*
X837021D01*
G01X831877D02*
X833084D01*
G01X833109Y301107D02*
X831853D01*
G01X837046D02*
X835790D01*
G01X835803Y300492D02*
X837033D01*
G01X831866D02*
X833096D01*
G01X833087Y300266D02*
X831875D01*
G01X837024D02*
X835812D01*
G01X835792Y300197D02*
X837043D01*
G01X831855D02*
X833106D01*
G01X833036Y298720D02*
X831925D01*
G01X829521Y298031D02*
X877559D01*
G01X831925Y297736D02*
X833036D01*
G01X831907Y297287D02*
X833055D01*
G01X833046Y297019D02*
X831916D01*
G01X833060Y295500D02*
X831901D01*
G01X831911Y295232D02*
X833050D01*
G01X835829Y294783D02*
X837006D01*
G01X831892D02*
X833069D01*
G01Y293799D02*
X831892D01*
G01X837006D02*
X835829D01*
G01X836987Y293350D02*
X835848D01*
G01X835838Y293082D02*
X836997D01*
G01X835853Y291563D02*
X836983D01*
G01X836992Y291295D02*
X835844D01*
G01X836973Y290846D02*
X835863D01*
G01X835433Y290157D02*
X844784D01*
G01X833465D02*
X823622D01*
G01X835863Y289862D02*
X836973D01*
G01X829725Y304910D02*
G03X823425Y306396I-3741J-1761D01*
G01X829725Y305522D02*
G03X823425Y306764I-3740J-2373D01*
G01X835814Y305104D02*
X835845Y306692D01*
G01X835824D02*
X835812Y306032D01*
G01X831877Y305104D02*
X831908Y306692D01*
G01X831887D02*
X831875Y306032D01*
G01X837046Y305191D02*
X837070Y306692D01*
G01X837053D02*
X837043Y306102D01*
G01X833109Y305191D02*
X833133Y306692D01*
G01X833116D02*
X833106Y306102D01*
G01X835853Y314736D02*
X835848Y312948D01*
G01X835838Y313216D02*
X835844Y315003D01*
G01X833060Y310799D02*
X833055Y309011D01*
G01X833045Y309279D02*
X833050Y311066D01*
G01X837006Y311515D02*
Y312500D01*
G01X836851Y316437D02*
Y315452D01*
G01X835985D02*
Y316437D01*
G01X835925Y315944D02*
Y315748D01*
G01X835829Y312500D02*
Y311515D01*
G01X833957Y315748D02*
Y315944D01*
G01X833069Y312500D02*
Y311515D01*
G01X832914Y308563D02*
Y307578D01*
G01X832481Y315748D02*
Y315944D01*
G01X832048Y307578D02*
Y308563D01*
G01X831892Y311515D02*
Y312500D01*
G01X836992Y315003D02*
X836997Y313216D01*
G01X836987Y312948D02*
X836982Y314736D01*
G01X835792Y306102D02*
X835783Y306692D01*
G01X835765D02*
X835790Y305191D01*
G01X837024Y306032D02*
X837011Y306692D01*
G01X836990D02*
X837021Y305104D01*
G01X829521Y306692D02*
Y308267D01*
G01X826496Y323228D02*
Y317618D01*
G01X826083Y315748D02*
Y315944D01*
G01X825099D02*
Y315748D01*
G01X823629Y308267D02*
Y306692D01*
G01X823130Y315748D02*
Y315944D01*
G01X822884Y315748D02*
Y315944D01*
G01X822392Y315748D02*
Y315944D01*
G01X831911Y311066D02*
X831916Y309279D01*
G01X831907Y309011D02*
X831901Y310799D01*
G01X831855Y306102D02*
X831846Y306692D01*
G01X831828D02*
X831853Y305191D01*
G01X833087Y306032D02*
X833074Y306692D01*
G01X833053D02*
X833084Y305104D01*
G01X836973Y316437D02*
X835862D01*
G01X833957Y315748D02*
X825099D01*
G01X845276D02*
X835925D01*
G01X836973Y315452D02*
X835862D01*
G01X835844Y315003D02*
X836992D01*
G01X836982Y314736D02*
X835853D01*
G01X836997Y313216D02*
X835838D01*
G01X835848Y312948D02*
X836987D01*
G01X833069Y312500D02*
X831892D01*
G01X837006D02*
X835829D01*
G01X833069Y311515D02*
X831892D01*
G01X837006D02*
X835829D01*
G01X833050Y311066D02*
X831911D01*
G01X831901Y310799D02*
X833060D01*
G01X831916Y309279D02*
X833045D01*
G01X833055Y309011D02*
X831907D01*
G01X833036Y308563D02*
X831925D01*
G01X877559Y308267D02*
X829521D01*
G01X833036Y307578D02*
X831925D01*
G01X833106Y306102D02*
X831855D01*
G01X837043D02*
X835792D01*
G01X835812Y306032D02*
X837024D01*
G01X831875D02*
X833087D01*
G01X833096Y305806D02*
X831866D01*
G01X837033D02*
X835803D01*
G01X835790Y305191D02*
X837046D01*
G01X831853D02*
X833109D01*
G01X833084Y305104D02*
X831877D01*
G01X837021D02*
X835814D01*
G01X833096Y304822D02*
X831866D01*
G01X837033D02*
X835803D01*
G01X842402Y323228D02*
X826496D01*
G01X837284Y370737D02*
Y363031D01*
G01X835775D02*
Y372895D01*
G01X833360Y364572D02*
Y363031D01*
G01X832454Y371354D02*
X824909Y364572D01*
G01X822494D02*
X830945Y372279D01*
G01X822494Y363031D02*
Y364572D01*
G01X824909D02*
X833360D01*
G01Y363031D02*
X822494D01*
G01X837284D02*
X835775D01*
G01X837887Y371354D02*
X837284Y370737D01*
G01Y371970D02*
X837887Y372587D01*
G01X833058Y372279D02*
X832454Y371354D01*
G01X824909Y375053D02*
X824305Y374128D01*
G01X830945Y372279D02*
X831549Y373512D01*
G01X833360D02*
X833058Y372279D01*
G01X837284Y372895D02*
Y371970D01*
G01X833360Y374128D02*
Y373512D01*
G01X833058Y375361D02*
X833360Y374128D01*
G01X831549D02*
X830945Y375053D01*
G01X838793Y371662D02*
X837887Y371354D01*
G01Y372587D02*
X838793Y372895D01*
G01X824305Y376594D02*
X825512Y377211D01*
G01X825814Y375670D02*
X824909Y375053D01*
G01X823098Y375361D02*
X824305Y376594D01*
G01X822796Y374128D02*
X823098Y375361D01*
G01X831549Y373512D02*
Y374128D01*
G01X831851Y376594D02*
X833058Y375361D01*
G01X830945Y375053D02*
X830040Y375670D01*
G01X830643Y377211D02*
X831851Y376594D01*
G01X830040Y375670D02*
X828531Y375978D01*
G01X828832Y377519D02*
X830643Y377211D01*
G01X827625Y377519D02*
X828832D01*
G01X828531Y375978D02*
X827323D01*
G01X824305Y374128D02*
X822796D01*
G01X835775Y372895D02*
X837284D01*
G01X825512Y377211D02*
X827625Y377519D01*
G01X827323Y375978D02*
X825814Y375670D01*
G01X852759Y299606D02*
X852772Y300266D01*
G01X852769Y301194D02*
X852738Y299606D01*
G01X848822D02*
X848835Y300266D01*
G01X848832Y301194D02*
X848801Y299606D01*
G01X844885D02*
X844898Y300266D01*
G01X844895Y301194D02*
X844864Y299606D01*
G01X840948D02*
X840961Y300266D01*
G01X840958Y301194D02*
X840927Y299606D01*
G01X851531D02*
X851540Y300197D01*
G01X851538Y301107D02*
X851513Y299606D01*
G01X847594D02*
X847603Y300197D01*
G01X847601Y301107D02*
X847576Y299606D01*
G01X843657D02*
X843666Y300197D01*
G01X843664Y301107D02*
X843639Y299606D01*
G01X839720D02*
X839729Y300197D01*
G01X839727Y301107D02*
X839702Y299606D01*
G01X852745Y293082D02*
X852740Y291295D01*
G01X852731Y291563D02*
X852735Y293350D01*
G01X847664Y297019D02*
X847659Y295232D01*
G01X847650Y295500D02*
X847655Y297287D01*
G01X844871Y293082D02*
X844866Y291295D01*
G01X844857Y291563D02*
X844861Y293350D01*
G01X839790Y297019D02*
X839785Y295232D01*
G01X839775Y295500D02*
X839781Y297287D01*
G01X854626Y290157D02*
Y290354D01*
G01X852754Y293799D02*
Y294783D01*
G01X852599Y290846D02*
Y289862D01*
G01X851733Y290846D02*
Y289862D01*
G01X851577Y294783D02*
Y293799D01*
G01X848817Y294783D02*
Y293799D01*
G01X848662Y298720D02*
Y297736D01*
G01X848229Y290157D02*
Y290354D01*
G01X847796Y298720D02*
Y297736D01*
G01X847640Y293799D02*
Y294783D01*
G01X846752Y290157D02*
Y290354D01*
G01X844880Y293799D02*
Y294783D01*
G01X844784Y290354D02*
Y290157D01*
G01X844725Y290846D02*
Y289862D01*
G01X843859Y290846D02*
Y289862D01*
G01X843703Y294783D02*
Y293799D01*
G01X840943Y294783D02*
Y293799D01*
G01X840847Y290157D02*
Y290354D01*
G01X840788Y298720D02*
Y297736D01*
G01X839922Y298720D02*
Y297736D01*
G01X839766Y293799D02*
Y294783D01*
G01X839370Y290157D02*
Y290354D01*
G01X851596Y293350D02*
X851601Y291563D01*
G01X851592Y291295D02*
X851587Y293082D01*
G01X848803Y297287D02*
X848808Y295500D01*
G01X848798Y295232D02*
X848794Y297019D01*
G01X843722Y293350D02*
X843727Y291563D01*
G01X843718Y291295D02*
X843713Y293082D01*
G01X840929Y297287D02*
X840934Y295500D01*
G01X840924Y295232D02*
X840920Y297019D01*
G01X852818Y299606D02*
X852794Y301107D01*
G01X852791Y300197D02*
X852801Y299606D01*
G01X848881D02*
X848857Y301107D01*
G01X848854Y300197D02*
X848864Y299606D01*
G01X844944D02*
X844920Y301107D01*
G01X844917Y300197D02*
X844927Y299606D01*
G01X841007D02*
X840983Y301107D01*
G01X840980Y300197D02*
X840990Y299606D01*
G01X851593D02*
X851562Y301194D01*
G01X851560Y300266D02*
X851572Y299606D01*
G01X847656D02*
X847625Y301194D01*
G01X847623Y300266D02*
X847635Y299606D01*
G01X843719D02*
X843688Y301194D01*
G01X843686Y300266D02*
X843698Y299606D01*
G01X839782D02*
X839751Y301194D01*
G01X839749Y300266D02*
X839761Y299606D01*
G01X851551Y301477D02*
X852781D01*
G01X847614D02*
X848844D01*
G01X843677D02*
X844907D01*
G01X839740D02*
X840970D01*
G01X851562Y301194D02*
X852769D01*
G01X847625D02*
X848832D01*
G01X843688D02*
X844895D01*
G01X839751D02*
X840958D01*
G01X840983Y301107D02*
X839727D01*
G01X848857D02*
X847601D01*
G01X844920D02*
X843664D01*
G01X852794D02*
X851538D01*
G01X851551Y300492D02*
X852781D01*
G01X847614D02*
X848844D01*
G01X843677D02*
X844907D01*
G01X839740D02*
X840970D01*
G01X840961Y300266D02*
X839749D01*
G01X848835D02*
X847623D01*
G01X844898D02*
X843686D01*
G01X852772D02*
X851560D01*
G01X851540Y300197D02*
X852791D01*
G01X847603D02*
X848854D01*
G01X843666D02*
X844917D01*
G01X839729D02*
X840980D01*
G01X848784Y298720D02*
X848662D01*
G01X840910D02*
X839800D01*
G01X848784D02*
X847674D01*
G01X847796D02*
X847674D01*
G01Y297736D02*
X848784D01*
G01X839800D02*
X840910D01*
G01X847655Y297287D02*
X848803D01*
G01X839781D02*
X840929D01*
G01X840920Y297019D02*
X839790D01*
G01X848794D02*
X847664D01*
G01X840934Y295500D02*
X839775D01*
G01X848808D02*
X847650D01*
G01X847659Y295232D02*
X848798D01*
G01X839785D02*
X840924D01*
G01X851577Y294783D02*
X852754D01*
G01X843703D02*
X844880D01*
G01X847640D02*
X848817D01*
G01X839766D02*
X840943D01*
G01Y293799D02*
X839766D01*
G01X844880D02*
X843703D01*
G01X848817D02*
X847640D01*
G01X852754D02*
X851577D01*
G01X844861Y293350D02*
X843722D01*
G01X852735D02*
X851596D01*
G01X851587Y293082D02*
X852745D01*
G01X843713D02*
X844871D01*
G01X851601Y291563D02*
X852731D01*
G01X843727D02*
X844857D01*
G01X844866Y291295D02*
X843718D01*
G01X852740D02*
X851592D01*
G01X844847Y290846D02*
X843737D01*
G01X852721D02*
X851611D01*
G01X855611Y290157D02*
X846752D01*
G01X851611Y289862D02*
X851733D01*
G01X851611D02*
X852721D01*
G01X843737D02*
X844847D01*
G01X852599D02*
X852721D01*
G01X851562Y305104D02*
X851593Y306692D01*
G01X851572D02*
X851560Y306032D01*
G01X847625Y305104D02*
X847656Y306692D01*
G01X847635D02*
X847623Y306032D01*
G01X843688Y305104D02*
X843719Y306692D01*
G01X843698D02*
X843686Y306032D01*
G01X839751Y305104D02*
X839782Y306692D01*
G01X839761D02*
X839749Y306032D01*
G01X852794Y305191D02*
X852818Y306692D01*
G01X852801D02*
X852791Y306102D01*
G01X848857Y305191D02*
X848881Y306692D01*
G01X848864D02*
X848854Y306102D01*
G01X844920Y305191D02*
X844944Y306692D01*
G01X844927D02*
X844917Y306102D01*
G01X840983Y305191D02*
X841007Y306692D01*
G01X840990D02*
X840980Y306102D01*
G01X851601Y314736D02*
X851596Y312948D01*
G01X851587Y313216D02*
X851592Y315003D01*
G01X848808Y310799D02*
X848803Y309011D01*
G01X848793Y309279D02*
X848798Y311066D01*
G01X843727Y314736D02*
X843722Y312948D01*
G01X843713Y313216D02*
X843718Y315003D01*
G01X840934Y310799D02*
X840929Y309011D01*
G01X840919Y309279D02*
X840924Y311066D01*
G01X854872Y315944D02*
Y315748D01*
G01X854380D02*
Y315944D01*
G01X854134D02*
Y315748D01*
G01X853150Y315944D02*
Y315748D01*
G01X852754Y311515D02*
Y312500D01*
G01X852599Y316437D02*
Y315452D01*
G01X851733D02*
Y316437D01*
G01X851577Y312500D02*
Y311515D01*
G01X851181Y315944D02*
Y315748D01*
G01X850197Y315944D02*
Y315748D01*
G01X849951D02*
Y315944D01*
G01X849459D02*
Y315748D01*
G01X848967Y315944D02*
Y315748D01*
G01X848817Y311515D02*
Y312500D01*
G01X848721Y315944D02*
Y315748D01*
G01X848662Y308563D02*
Y307578D01*
G01X847983Y315748D02*
Y315944D01*
G01X847796Y307578D02*
Y308563D01*
G01X847640Y312500D02*
Y311515D01*
G01X847490Y315748D02*
Y315944D01*
G01X847402Y323228D02*
Y317618D01*
G01X847244Y315748D02*
Y315944D01*
G01X845276Y315748D02*
Y315944D01*
G01X844880Y311515D02*
Y312500D01*
G01X844725Y316437D02*
Y315452D01*
G01X843859D02*
Y316437D01*
G01X843703Y312500D02*
Y311515D01*
G01X842402Y323228D02*
Y317618D01*
G01X841339Y315748D02*
Y315944D01*
G01X840943Y312500D02*
Y311515D01*
G01X840788Y308563D02*
Y307578D01*
G01X839922D02*
Y308563D01*
G01X839863Y315748D02*
Y315944D01*
G01X839766Y311515D02*
Y312500D01*
G01X852740Y315003D02*
X852745Y313216D01*
G01X852735Y312948D02*
X852730Y314736D01*
G01X847659Y311066D02*
X847664Y309279D01*
G01X847655Y309011D02*
X847650Y310799D01*
G01X844866Y315003D02*
X844871Y313216D01*
G01X844861Y312948D02*
X844856Y314736D01*
G01X839785Y311066D02*
X839790Y309279D01*
G01X839781Y309011D02*
X839775Y310799D01*
G01X851540Y306102D02*
X851531Y306692D01*
G01X851513D02*
X851538Y305191D01*
G01X847603Y306102D02*
X847594Y306692D01*
G01X847576D02*
X847601Y305191D01*
G01X843666Y306102D02*
X843657Y306692D01*
G01X843639D02*
X843664Y305191D01*
G01X839729Y306102D02*
X839720Y306692D01*
G01X839702D02*
X839727Y305191D01*
G01X852772Y306032D02*
X852759Y306692D01*
G01X852738D02*
X852769Y305104D01*
G01X848835Y306032D02*
X848822Y306692D01*
G01X848801D02*
X848832Y305104D01*
G01X844898Y306032D02*
X844885Y306692D01*
G01X844864D02*
X844895Y305104D01*
G01X840961Y306032D02*
X840948Y306692D01*
G01X840927D02*
X840958Y305104D01*
G01X852721Y316437D02*
X852599D01*
G01X844847D02*
X843736D01*
G01X852721D02*
X851610D01*
G01X851733D02*
X851610D01*
G01X857087Y315748D02*
X847244D01*
G01X844847Y315452D02*
X843736D01*
G01X852721D02*
X851610D01*
G01X851592Y315003D02*
X852740D01*
G01X843718D02*
X844866D01*
G01X844856Y314736D02*
X843727D01*
G01X852730D02*
X851601D01*
G01X844871Y313216D02*
X843713D01*
G01X852745D02*
X851587D01*
G01X851596Y312948D02*
X852735D01*
G01X843722D02*
X844861D01*
G01X840943Y312500D02*
X839766D01*
G01X844880D02*
X843703D01*
G01X848817D02*
X847640D01*
G01X852754D02*
X851577D01*
G01X840943Y311515D02*
X839766D01*
G01X844880D02*
X843703D01*
G01X848817D02*
X847640D01*
G01X852754D02*
X851577D01*
G01X840924Y311066D02*
X839785D01*
G01X848798D02*
X847659D01*
G01X847650Y310799D02*
X848808D01*
G01X839775D02*
X840934D01*
G01X847664Y309279D02*
X848793D01*
G01X839790D02*
X840919D01*
G01X840929Y309011D02*
X839781D01*
G01X848803D02*
X847655D01*
G01X840910Y308563D02*
X839799D01*
G01X848784D02*
X847673D01*
G01X840910Y307578D02*
X839799D01*
G01X848784D02*
X847673D01*
G01X848662D02*
X848784D01*
G01X840980Y306102D02*
X839729D01*
G01X844917D02*
X843666D01*
G01X848854D02*
X847603D01*
G01X852791D02*
X851540D01*
G01X851560Y306032D02*
X852772D01*
G01X843686D02*
X844898D01*
G01X847623D02*
X848835D01*
G01X839749D02*
X840961D01*
G01X840970Y305806D02*
X839740D01*
G01X844907D02*
X843677D01*
G01X848844D02*
X847614D01*
G01X852781D02*
X851551D01*
G01X851538Y305191D02*
X852794D01*
G01X843664D02*
X844920D01*
G01X847601D02*
X848857D01*
G01X839727D02*
X840983D01*
G01X840958Y305104D02*
X839751D01*
G01X844895D02*
X843688D01*
G01X848832D02*
X847625D01*
G01X852769D02*
X851562D01*
G01X840970Y304822D02*
X839740D01*
G01X844907D02*
X843677D01*
G01X848844D02*
X847614D01*
G01X852781D02*
X851551D01*
G01X863307Y323228D02*
X847402D01*
G01X854187Y363031D02*
Y370429D01*
G01X850866Y370737D02*
Y363031D01*
G01X849357D02*
Y372895D01*
G01X846942Y370429D02*
Y363031D01*
G01X845433D02*
Y370429D01*
G01X842113D02*
Y363031D01*
G01X840604D02*
Y370429D01*
G01X842113Y363031D02*
X840604D01*
G01X846942D02*
X845433D01*
G01X850866D02*
X849357D01*
G01X855696D02*
X854187D01*
G01X851470Y371354D02*
X850866Y370737D01*
G01Y371970D02*
X851470Y372587D01*
G01X842717Y371354D02*
X842415Y371046D01*
G01X841811Y371662D02*
X842717Y372587D01*
G01X842415Y371046D02*
X842113Y370429D01*
G01X850866Y372895D02*
Y371970D01*
G01X846339D02*
X846942Y370429D01*
G01X854187D02*
X853885Y371046D01*
G01X845433Y370429D02*
X845131Y371046D01*
G01X840604Y370429D02*
X840302Y371046D01*
G01X854488Y372587D02*
X855394Y371662D01*
G01X853885Y371046D02*
X853583Y371354D01*
G01X852375Y371662D02*
X851470Y371354D01*
G01Y372587D02*
X852375Y372895D01*
G01X842717Y372587D02*
X843622Y372895D01*
G01X843320Y371662D02*
X842717Y371354D01*
G01X845735Y372587D02*
X846339Y371970D01*
G01X845131Y371046D02*
X844830Y371354D01*
G01X840906Y372587D02*
X841811Y371662D01*
G01X840302Y371046D02*
X840000Y371354D01*
G01X853583D02*
X852979Y371662D01*
G01X844830Y371354D02*
X844226Y371662D01*
G01X840000Y371354D02*
X839397Y371662D01*
G01X853583Y372895D02*
X854488Y372587D01*
G01X844830Y372895D02*
X845735Y372587D01*
G01X840000Y372895D02*
X840906Y372587D01*
G01X849357Y372895D02*
X850866D01*
G01X852375D02*
X853583D01*
G01X843622D02*
X844830D01*
G01X838793D02*
X840000D01*
G01X839397Y371662D02*
X838793D01*
G01X844226D02*
X843320D01*
G01X852979D02*
X852375D01*
G01X871142Y98805D02*
Y97800D01*
G01Y101821D02*
Y100815D01*
G01X867205Y97800D02*
Y98805D01*
G01Y100815D02*
Y101821D01*
G01X865237Y105590D02*
Y93779D01*
G01X863760Y100815D02*
Y105590D01*
G01Y93779D02*
Y99308D01*
G01X856870D02*
Y93779D01*
G01Y105590D02*
Y100815D01*
G01X855394Y93779D02*
Y105590D01*
G01X863760D02*
X865237D01*
G01X855394D02*
X856870D01*
G01X867205Y101821D02*
X871142D01*
G01X856870Y100815D02*
X863760D01*
G01X871142D02*
X867205D01*
G01X863760Y99308D02*
X856870D01*
G01X867205Y98805D02*
X871142D01*
G01Y97800D02*
X867205D01*
G01X856870Y93779D02*
X855394D01*
G01X865237D02*
X863760D01*
G01X872982Y298228D02*
G03I-1131J0D01*
G01X868507Y299606D02*
X868520Y300266D01*
G01X868517Y301194D02*
X868487Y299606D01*
G01X864570D02*
X864583Y300266D01*
G01X864580Y301194D02*
X864550Y299606D01*
G01X860633D02*
X860646Y300266D01*
G01X860643Y301194D02*
X860613Y299606D01*
G01X856696D02*
X856709Y300266D01*
G01X856706Y301194D02*
X856675Y299606D01*
G01X871216D02*
X871225Y300197D01*
G01X871223Y301107D02*
X871198Y299606D01*
G01X867279D02*
X867288Y300197D01*
G01X867286Y301107D02*
X867261Y299606D01*
G01X863342D02*
X863351Y300197D01*
G01X863349Y301107D02*
X863324Y299606D01*
G01X859405D02*
X859414Y300197D01*
G01X859412Y301107D02*
X859387Y299606D01*
G01X855468D02*
X855477Y300197D01*
G01X855475Y301107D02*
X855450Y299606D01*
G01X871286Y297019D02*
X871281Y295232D01*
G01X871272Y295500D02*
X871277Y297287D01*
G01X868493Y293082D02*
X868488Y291295D01*
G01X868479Y291563D02*
X868483Y293350D01*
G01X863412Y297019D02*
X863407Y295232D01*
G01X863398Y295500D02*
X863403Y297287D01*
G01X860619Y293082D02*
X860614Y291295D01*
G01X860605Y291563D02*
X860609Y293350D01*
G01X855538Y297019D02*
X855533Y295232D01*
G01X855524Y295500D02*
X855529Y297287D01*
G01X871418Y298720D02*
Y297736D01*
G01X871262Y293799D02*
Y294783D01*
G01X868502Y293799D02*
Y294783D01*
G01X868347Y290846D02*
Y289862D01*
G01X867481Y290846D02*
Y289862D01*
G01X867325Y294783D02*
Y293799D01*
G01X866683Y290157D02*
Y290354D01*
G01X866191Y290157D02*
Y290354D01*
G01X865945Y290157D02*
Y290354D01*
G01X865699Y290157D02*
Y290354D01*
G01X865207Y290157D02*
Y290354D01*
G01X864961Y290157D02*
Y290354D01*
G01X864715Y290157D02*
Y290354D01*
G01X864565Y294783D02*
Y293799D01*
G01X864469Y290354D02*
Y290157D01*
G01X864410Y298720D02*
Y297736D01*
G01X864223Y290157D02*
Y290354D01*
G01X863977Y290157D02*
Y290354D01*
G01X863731Y290157D02*
Y290354D01*
G01X863544Y298720D02*
Y297736D01*
G01X863388Y293799D02*
Y294783D01*
G01X862992Y290157D02*
Y290354D01*
G01X862746Y290157D02*
Y290354D01*
G01X861516Y290157D02*
Y290354D01*
G01X861024Y290157D02*
Y290354D01*
G01X860778Y290157D02*
Y290354D01*
G01X860628Y293799D02*
Y294783D01*
G01X860532Y290157D02*
Y290354D01*
G01X860473Y290846D02*
Y289862D01*
G01X860040Y290157D02*
Y290354D01*
G01X859794Y290157D02*
Y290354D01*
G01X859607Y290846D02*
Y289862D01*
G01X859548Y290157D02*
Y290354D01*
G01X859451Y294783D02*
Y293799D01*
G01X859301Y290157D02*
Y290354D01*
G01X859055Y290157D02*
Y290354D01*
G01X858563Y290157D02*
Y290354D01*
G01X858317Y290157D02*
Y290354D01*
G01X857825Y290157D02*
Y290354D01*
G01X857579Y290157D02*
Y290354D01*
G01X856691Y294783D02*
Y293799D01*
G01X856536Y298720D02*
Y297736D01*
G01X855670Y298720D02*
Y297736D01*
G01X855611Y290354D02*
Y290157D01*
G01X855514Y293799D02*
Y294783D01*
G01X867344Y293350D02*
X867349Y291563D01*
G01X867340Y291295D02*
X867335Y293082D01*
G01X864551Y297287D02*
X864556Y295500D01*
G01X864546Y295232D02*
X864542Y297019D01*
G01X859470Y293350D02*
X859475Y291563D01*
G01X859466Y291295D02*
X859461Y293082D01*
G01X856677Y297287D02*
X856682Y295500D01*
G01X856672Y295232D02*
X856668Y297019D01*
G01X868566Y299606D02*
X868542Y301107D01*
G01X868539Y300197D02*
X868549Y299606D01*
G01X864629D02*
X864605Y301107D01*
G01X864602Y300197D02*
X864612Y299606D01*
G01X860692D02*
X860668Y301107D01*
G01X860665Y300197D02*
X860675Y299606D01*
G01X856755D02*
X856731Y301107D01*
G01X856728Y300197D02*
X856738Y299606D01*
G01X871278D02*
X871247Y301194D01*
G01X871245Y300266D02*
X871257Y299606D01*
G01X867341D02*
X867310Y301194D01*
G01X867308Y300266D02*
X867320Y299606D01*
G01X863404D02*
X863373Y301194D01*
G01X863371Y300266D02*
X863383Y299606D01*
G01X859467D02*
X859436Y301194D01*
G01X859434Y300266D02*
X859446Y299606D01*
G01X855530D02*
X855499Y301194D01*
G01X855497Y300266D02*
X855509Y299606D01*
G01X871236Y301477D02*
X872466D01*
G01X867299D02*
X868529D01*
G01X863362D02*
X864592D01*
G01X859425D02*
X860655D01*
G01X855488D02*
X856718D01*
G01X871247Y301194D02*
X872454D01*
G01X867310D02*
X868517D01*
G01X863373D02*
X864580D01*
G01X859436D02*
X860643D01*
G01X855499D02*
X856706D01*
G01X856731Y301107D02*
X855475D01*
G01X860668D02*
X859412D01*
G01X864605D02*
X863349D01*
G01X868542D02*
X867286D01*
G01X872479D02*
X871223D01*
G01X871236Y300492D02*
X872466D01*
G01X867299D02*
X868529D01*
G01X863362D02*
X864592D01*
G01X859425D02*
X860655D01*
G01X855488D02*
X856718D01*
G01X856709Y300266D02*
X855497D01*
G01X860646D02*
X859434D01*
G01X864583D02*
X863371D01*
G01X868520D02*
X867308D01*
G01X872457D02*
X871245D01*
G01X871225Y300197D02*
X872476D01*
G01X867288D02*
X868539D01*
G01X863351D02*
X864602D01*
G01X859414D02*
X860665D01*
G01X855477D02*
X856728D01*
G01X864532Y298720D02*
X864410D01*
G01X856658D02*
X856536D01*
G01X856658D02*
X855548D01*
G01X864532D02*
X863422D01*
G01X872406D02*
X871296D01*
G01X855670D02*
X855548D01*
G01X863544D02*
X863422D01*
G01X871418D02*
X871296D01*
G01Y297736D02*
X872406D01*
G01X863422D02*
X864532D01*
G01X855548D02*
X856658D01*
G01X871277Y297287D02*
X872425D01*
G01X863403D02*
X864551D01*
G01X855529D02*
X856677D01*
G01X856668Y297019D02*
X855538D01*
G01X864542D02*
X863412D01*
G01X872416D02*
X871286D01*
G01X856682Y295500D02*
X855524D01*
G01X864556D02*
X863398D01*
G01X872430D02*
X871272D01*
G01X871281Y295232D02*
X872420D01*
G01X863407D02*
X864546D01*
G01X855533D02*
X856672D01*
G01X871262Y294783D02*
X872439D01*
G01X867325D02*
X868502D01*
G01X863388D02*
X864565D01*
G01X859451D02*
X860628D01*
G01X855514D02*
X856691D01*
G01Y293799D02*
X855514D01*
G01X860628D02*
X859451D01*
G01X864565D02*
X863388D01*
G01X868502D02*
X867325D01*
G01X872439D02*
X871262D01*
G01X860609Y293350D02*
X859470D01*
G01X868483D02*
X867344D01*
G01X867335Y293082D02*
X868493D01*
G01X859461D02*
X860619D01*
G01X867349Y291563D02*
X868479D01*
G01X859475D02*
X860605D01*
G01X860614Y291295D02*
X859466D01*
G01X868488D02*
X867340D01*
G01X860595Y290846D02*
X859485D01*
G01X868469D02*
X867359D01*
G01X857579Y290157D02*
X866683D01*
G01X867359Y289862D02*
X867481D01*
G01X859485D02*
X859607D01*
G01X867359D02*
X868469D01*
G01X859485D02*
X860595D01*
G01X860473D02*
X860595D01*
G01X868347D02*
X868469D01*
G01X871247Y305104D02*
X871278Y306692D01*
G01X871257D02*
X871245Y306032D01*
G01X867310Y305104D02*
X867341Y306692D01*
G01X867320D02*
X867308Y306032D01*
G01X863373Y305104D02*
X863404Y306692D01*
G01X863383D02*
X863371Y306032D01*
G01X859436Y305104D02*
X859467Y306692D01*
G01X859446D02*
X859434Y306032D01*
G01X855499Y305104D02*
X855530Y306692D01*
G01X855509D02*
X855497Y306032D01*
G01X868542Y305191D02*
X868566Y306692D01*
G01X868549D02*
X868539Y306102D01*
G01X864605Y305191D02*
X864629Y306692D01*
G01X864612D02*
X864602Y306102D01*
G01X860668Y305191D02*
X860692Y306692D01*
G01X860675D02*
X860665Y306102D01*
G01X856731Y305191D02*
X856755Y306692D01*
G01X856738D02*
X856728Y306102D01*
G01X867349Y314736D02*
X867344Y312948D01*
G01X867335Y313216D02*
X867340Y315003D01*
G01X864556Y310799D02*
X864551Y309011D01*
G01X864541Y309279D02*
X864546Y311066D01*
G01X859475Y314736D02*
X859470Y312948D01*
G01X859461Y313216D02*
X859466Y315003D01*
G01X856682Y310799D02*
X856677Y309011D01*
G01X856667Y309279D02*
X856672Y311066D01*
G01X871418Y307578D02*
Y308563D01*
G01X871262Y311515D02*
Y312500D01*
G01X868502Y311515D02*
Y312500D01*
G01X868347Y316437D02*
Y315452D01*
G01X868307Y323228D02*
Y317618D01*
G01X867914Y315944D02*
Y315748D01*
G01X867481Y315452D02*
Y316437D01*
G01X867325Y312500D02*
Y311515D01*
G01X866437Y315748D02*
Y315944D01*
G01X864565Y312500D02*
Y311515D01*
G01X864410Y308563D02*
Y307578D01*
G01X863544D02*
Y308563D01*
G01X863388Y311515D02*
Y312500D01*
G01X863307Y323228D02*
Y317618D01*
G01X860628Y311515D02*
Y312500D01*
G01X860473Y316437D02*
Y315452D01*
G01X859607D02*
Y316437D01*
G01X859451Y312500D02*
Y311515D01*
G01X859055Y315748D02*
Y315944D01*
G01X857087Y315748D02*
Y315944D01*
G01X856841Y315748D02*
Y315944D01*
G01X856691Y312500D02*
Y311515D01*
G01X856536Y308563D02*
Y307578D01*
G01X856349Y315748D02*
Y315944D01*
G01X855670Y307578D02*
Y308563D01*
G01X855611Y315944D02*
Y315748D01*
G01X855514Y311515D02*
Y312500D01*
G01X855364Y315944D02*
Y315748D01*
G01X871281Y311066D02*
X871286Y309279D01*
G01X871277Y309011D02*
X871272Y310799D01*
G01X868488Y315003D02*
X868493Y313216D01*
G01X868483Y312948D02*
X868478Y314736D01*
G01X863407Y311066D02*
X863412Y309279D01*
G01X863403Y309011D02*
X863398Y310799D01*
G01X860614Y315003D02*
X860619Y313216D01*
G01X860609Y312948D02*
X860604Y314736D01*
G01X855533Y311066D02*
X855538Y309279D01*
G01X855529Y309011D02*
X855524Y310799D01*
G01X871225Y306102D02*
X871216Y306692D01*
G01X871198D02*
X871223Y305191D01*
G01X867288Y306102D02*
X867279Y306692D01*
G01X867261D02*
X867286Y305191D01*
G01X863351Y306102D02*
X863342Y306692D01*
G01X863324D02*
X863349Y305191D01*
G01X859414Y306102D02*
X859405Y306692D01*
G01X859387D02*
X859412Y305191D01*
G01X855477Y306102D02*
X855468Y306692D01*
G01X855450D02*
X855475Y305191D01*
G01X868520Y306032D02*
X868507Y306692D01*
G01X868487D02*
X868517Y305104D01*
G01X864583Y306032D02*
X864570Y306692D01*
G01X864550D02*
X864580Y305104D01*
G01X860646Y306032D02*
X860633Y306692D01*
G01X860613D02*
X860643Y305104D01*
G01X856709Y306032D02*
X856696Y306692D01*
G01X856675D02*
X856706Y305104D01*
G01X868469Y316437D02*
X868347D01*
G01X860595D02*
X860473D01*
G01X860595D02*
X859484D01*
G01X868469D02*
X867358D01*
G01X859607D02*
X859484D01*
G01X867481D02*
X867358D01*
G01X859055Y315748D02*
X867914D01*
G01X860595Y315452D02*
X859484D01*
G01X868469D02*
X867358D01*
G01X867340Y315003D02*
X868488D01*
G01X859466D02*
X860614D01*
G01X860604Y314736D02*
X859475D01*
G01X868478D02*
X867349D01*
G01X860619Y313216D02*
X859461D01*
G01X868493D02*
X867335D01*
G01X867344Y312948D02*
X868483D01*
G01X859470D02*
X860609D01*
G01X856691Y312500D02*
X855514D01*
G01X860628D02*
X859451D01*
G01X864565D02*
X863388D01*
G01X868502D02*
X867325D01*
G01X872439D02*
X871262D01*
G01X856691Y311515D02*
X855514D01*
G01X860628D02*
X859451D01*
G01X864565D02*
X863388D01*
G01X868502D02*
X867325D01*
G01X872439D02*
X871262D01*
G01X856672Y311066D02*
X855533D01*
G01X864546D02*
X863407D01*
G01X872420D02*
X871281D01*
G01X871272Y310799D02*
X872430D01*
G01X863398D02*
X864556D01*
G01X855524D02*
X856682D01*
G01X871286Y309279D02*
X872415D01*
G01X863412D02*
X864541D01*
G01X855538D02*
X856667D01*
G01X856677Y309011D02*
X855529D01*
G01X864551D02*
X863403D01*
G01X872425D02*
X871277D01*
G01X856658Y308563D02*
X855547D01*
G01X864532D02*
X863421D01*
G01X872406D02*
X871295D01*
G01Y307578D02*
X871418D01*
G01X863421D02*
X863544D01*
G01X855547D02*
X855670D01*
G01X856658D02*
X855547D01*
G01X864532D02*
X863421D01*
G01X872406D02*
X871295D01*
G01X856536D02*
X856658D01*
G01X864410D02*
X864532D01*
G01X856728Y306102D02*
X855477D01*
G01X860665D02*
X859414D01*
G01X864602D02*
X863351D01*
G01X868539D02*
X867288D01*
G01X872476D02*
X871225D01*
G01X871245Y306032D02*
X872457D01*
G01X867308D02*
X868520D01*
G01X863371D02*
X864583D01*
G01X859434D02*
X860646D01*
G01X855497D02*
X856709D01*
G01X856718Y305806D02*
X855488D01*
G01X860655D02*
X859425D01*
G01X864592D02*
X863362D01*
G01X868529D02*
X867299D01*
G01X872466D02*
X871236D01*
G01X871223Y305191D02*
X872479D01*
G01X867286D02*
X868542D01*
G01X863349D02*
X864605D01*
G01X859412D02*
X860668D01*
G01X855475D02*
X856731D01*
G01X856706Y305104D02*
X855499D01*
G01X860643D02*
X859436D01*
G01X864580D02*
X863373D01*
G01X868517D02*
X867310D01*
G01X872454D02*
X871247D01*
G01X856718Y304822D02*
X855488D01*
G01X860655D02*
X859425D01*
G01X864592D02*
X863362D01*
G01X868529D02*
X867299D01*
G01X872466D02*
X871236D01*
G01X883662Y323228D02*
X868307D01*
G01X860525Y370429D02*
Y363031D01*
G01X859016D02*
Y370429D01*
G01X855696D02*
Y363031D01*
G01X860525D02*
X859016D01*
G01X856300Y371354D02*
X855998Y371046D01*
G01X855394Y371662D02*
X856300Y372587D01*
G01X855998Y371046D02*
X855696Y370429D01*
G01X859922Y371970D02*
X860525Y370429D01*
G01X859016D02*
X858714Y371046D01*
G01X859318Y372587D02*
X859922Y371970D01*
G01X858714Y371046D02*
X858413Y371354D01*
G01X856300Y372587D02*
X857205Y372895D01*
G01X856903Y371662D02*
X856300Y371354D01*
G01X858413D02*
X857809Y371662D01*
G01X858413Y372895D02*
X859318Y372587D01*
G01X857205Y372895D02*
X858413D01*
G01X857809Y371662D02*
X856903D01*
G01X859109Y988189D02*
G03Y996063I0J3937D01*
G01Y988189D02*
G03Y996063I0J3937D01*
G01X887628Y94030D02*
X888859Y94784D01*
G01X883691Y101067D02*
X882461Y100313D01*
G01X888120Y95789D02*
X887382Y95287D01*
G01X882953Y99056D02*
X883937Y99810D01*
G01X874587Y103580D02*
X873111Y101821D01*
G01Y103831D02*
X874587Y105590D01*
G01X882461Y100313D02*
Y104334D01*
G01X881231Y105590D02*
Y99056D01*
G01X879262Y95035D02*
Y93779D01*
G01X878032D02*
Y95035D01*
G01X876063Y105590D02*
Y93779D01*
G01X874587D02*
Y103580D01*
G01X873111Y101821D02*
Y103831D01*
G01X883199Y95789D02*
X882707Y96795D01*
G01X881231D02*
X881723Y95789D01*
G01D02*
X882461Y94784D01*
G01X887382Y99810D02*
X888120Y99308D01*
G01X883937Y95287D02*
X883199Y95789D01*
G01X888859Y100313D02*
X887628Y101067D01*
G01X882461Y94784D02*
X883691Y94030D01*
G01X886398Y100061D02*
X887382Y99810D01*
G01X884922Y95035D02*
X883937Y95287D01*
G01X887628Y101067D02*
X886398Y101318D01*
G01X883691Y94030D02*
X884922Y93779D01*
G01X874587Y105590D02*
X876063D01*
G01X889597D02*
X881231D01*
G01X882461Y104334D02*
X889597D01*
G01X886398Y101318D02*
X884922D01*
G01Y100061D02*
X886398D01*
G01X881231Y99056D02*
X882953D01*
G01X882707Y96795D02*
X881231D01*
G01X878032Y95035D02*
X879262D01*
G01X886398D02*
X884922D01*
G01Y93779D02*
X886398D01*
G01X876063D02*
X874587D01*
G01X879262D02*
X878032D01*
G01X884922Y101318D02*
X883691Y101067D01*
G01X886398Y93779D02*
X887628Y94030D01*
G01X883937Y99810D02*
X884922Y100061D01*
G01X887382Y95287D02*
X886398Y95035D01*
G01X884646Y228346D02*
Y988189D01*
G01X929922Y228346D02*
X884646D01*
G01X875985Y299606D02*
X877559Y298031D01*
G01X873721Y297565D02*
X873485Y297283D01*
G01Y297605D02*
X873721Y297886D01*
G01X875611Y299173D02*
X874981Y297283D01*
G01X875178Y298529D02*
X874824Y297444D01*
G01X875217Y298690D02*
X875375Y299173D01*
G01X872444Y299606D02*
X872457Y300266D01*
G01X872454Y301194D02*
X872424Y299606D01*
G01X883662Y323228D02*
Y288681D01*
G01X880118Y291830D02*
Y296161D01*
G01X877559Y298031D02*
Y308267D01*
G01X876181Y296161D02*
Y293799D01*
G01X875985Y306692D02*
Y299606D01*
G01X875788Y292618D02*
Y288681D01*
G01X875315Y296161D02*
Y291830D01*
G01X873721Y297886D02*
Y297565D01*
G01X873485Y299173D02*
Y297605D01*
G01X873249Y297283D02*
Y299173D01*
G01X872439Y294783D02*
Y293799D01*
G01X872284Y298720D02*
Y297736D01*
G01X872425Y297287D02*
X872430Y295500D01*
G01X872420Y295232D02*
X872416Y297019D01*
G01X872503Y299606D02*
X872479Y301107D01*
G01X872476Y300197D02*
X872486Y299606D01*
G01X874272Y299173D02*
X874430Y298690D01*
G01X874824Y297444D02*
X874469Y298529D01*
G01X874666Y297283D02*
X874036Y299173D01*
G01X873249D02*
X873485D01*
G01X874036D02*
X874272D01*
G01X875375D02*
X875611D01*
G01X872406Y298720D02*
X872284D01*
G01X874430Y298690D02*
X875217D01*
G01X874469Y298529D02*
X875178D01*
G01X873485Y297283D02*
X873249D01*
G01X874981D02*
X874666D01*
G01X875315Y296161D02*
X880118D01*
G01X876181Y293799D02*
X880118D01*
G01X883662Y292618D02*
X875788D01*
G01X880118Y291830D02*
X875315D01*
G01X875985Y306692D02*
X877559Y308267D01*
G01X872479Y305191D02*
X872503Y306692D01*
G01X872486D02*
X872476Y306102D01*
G01X872430Y310799D02*
X872425Y309011D01*
G01X872415Y309279D02*
X872420Y311066D01*
G01X880118Y314468D02*
Y310137D01*
G01X876181D02*
Y312500D01*
G01X875788Y317637D02*
Y313681D01*
G01X875315Y314468D02*
Y310137D01*
G01X872439Y312500D02*
Y311515D01*
G01X872284Y308563D02*
Y307578D01*
G01X872457Y306032D02*
X872444Y306692D01*
G01X872424D02*
X872454Y305104D01*
G01X883662Y317637D02*
X875788D01*
G01X880118Y314468D02*
X875315D01*
G01X875788Y313681D02*
X883662D01*
G01X880118Y312500D02*
X876181D01*
G01X880118Y310137D02*
X875315D01*
G01X872284Y307578D02*
X872406D01*
G01X884306Y996063D02*
G03Y988189I0J-3937D01*
G01Y996063D02*
G03Y988189I0J-3937D01*
G01X902166Y996063D02*
X884306D01*
G01X902166D02*
X884306D01*
G01X898209Y100815D02*
X897717Y100564D01*
G01Y101569D02*
X898455Y101821D01*
G01X894518Y100815D02*
X893780Y100564D01*
G01Y101569D02*
X894518Y101821D01*
G01X897717Y100564D02*
X897471Y100313D01*
G01X896979Y100815D02*
X897717Y101569D01*
G01X893780Y100564D02*
X893288Y100061D01*
G01Y101067D02*
X893780Y101569D01*
G01X888859Y94784D02*
X889597Y95789D01*
G01X888613Y96543D02*
X888120Y95789D01*
G01X897471Y100313D02*
X897225Y99810D01*
G01X889597Y95789D02*
X890089Y97046D01*
G01X888859Y97297D02*
X888613Y96543D01*
G01X903130Y93779D02*
Y101821D01*
G01X901162Y99810D02*
Y93779D01*
G01X899931D02*
Y99810D01*
G01X897225D02*
Y93779D01*
G01X895994D02*
Y99810D01*
G01X893288Y101821D02*
Y101067D01*
G01Y100061D02*
Y93779D01*
G01X892057D02*
Y101821D01*
G01X890089Y97046D02*
Y98051D01*
G01X889597Y104334D02*
Y105590D01*
G01X888859Y97800D02*
Y97297D01*
G01X888613Y98554D02*
X888859Y97800D01*
G01X900670Y101067D02*
X901162Y99810D01*
G01X890089Y98051D02*
X889597Y99308D01*
G01X899931Y99810D02*
X899685Y100313D01*
G01X895994Y99810D02*
X895748Y100313D01*
G01X888120Y99308D02*
X888613Y98554D01*
G01X889597Y99308D02*
X888859Y100313D01*
G01X900177Y101569D02*
X900670Y101067D01*
G01X899685Y100313D02*
X899439Y100564D01*
G01X896240Y101569D02*
X896979Y100815D01*
G01X895748Y100313D02*
X895502Y100564D01*
G01X899439D02*
X898947Y100815D01*
G01X895502Y100564D02*
X895010Y100815D01*
G01X899439Y101821D02*
X900177Y101569D01*
G01X895502Y101821D02*
X896240Y101569D01*
G01X903130Y101821D02*
X904361D01*
G01X898455D02*
X899439D01*
G01X892057D02*
X893288D01*
G01X894518D02*
X895502D01*
G01X895010Y100815D02*
X894518D01*
G01X898947D02*
X898209D01*
G01X893288Y93779D02*
X892057D01*
G01X897225D02*
X895994D01*
G01X904361D02*
X903130D01*
G01X901162D02*
X899931D01*
G01X904213Y475118D02*
Y476929D01*
G01D02*
X910070D01*
G01X918701Y475118D02*
X904213D01*
G01Y485380D02*
Y487191D01*
G01D02*
X918701D01*
G01X910070Y485380D02*
X904213D01*
G01Y502283D02*
X904521Y500472D01*
G01Y504094D02*
X904213Y502283D01*
G01X921850Y968503D02*
G03X902165Y988189I-19685J1D01*
G01X921851Y968503D02*
G03X902166Y988189I-19685J1D01*
G01X929725Y968504D02*
G03X902166Y996063I-27559J0D01*
G01D02*
X902195D01*
G01X929725Y968504D02*
G03X902166Y996063I-27559J0D01*
G01D02*
X902195D01*
G01X909282Y100815D02*
X908790Y100564D01*
G01Y101569D02*
X909528Y101821D01*
G01X905591Y100815D02*
X904853Y100564D01*
G01Y101569D02*
X905591Y101821D01*
G01X908790Y100564D02*
X908544Y100313D01*
G01X908051Y100815D02*
X908790Y101569D01*
G01X904853Y100564D02*
X904361Y100061D01*
G01Y101067D02*
X904853Y101569D01*
G01X908544Y100313D02*
X908298Y99810D01*
G01X912235D02*
Y93779D01*
G01X911004D02*
Y99810D01*
G01X908298D02*
Y93779D01*
G01X907067D02*
Y99810D01*
G01X904361Y101821D02*
Y101067D01*
G01Y100061D02*
Y93779D01*
G01X911742Y101067D02*
X912235Y99810D01*
G01X911004D02*
X910758Y100313D01*
G01X907067Y99810D02*
X906821Y100313D01*
G01X911250Y101569D02*
X911742Y101067D01*
G01X910758Y100313D02*
X910512Y100564D01*
G01X907313Y101569D02*
X908051Y100815D01*
G01X906821Y100313D02*
X906575Y100564D01*
G01X910512D02*
X910020Y100815D01*
G01X906575Y100564D02*
X906083Y100815D01*
G01X910512Y101821D02*
X911250Y101569D01*
G01X906575Y101821D02*
X907313Y101569D01*
G01X909528Y101821D02*
X910512D01*
G01X905591D02*
X906575D01*
G01X906083Y100815D02*
X905591D01*
G01X910020D02*
X909282D01*
G01X908298Y93779D02*
X907067D01*
G01X912235D02*
X911004D01*
G01X918701Y476929D02*
Y475118D01*
G01X911920Y485380D02*
Y476929D01*
G01X910070D02*
Y485380D01*
G01X911920Y476929D02*
X918701D01*
G01X904521Y500472D02*
X905446Y498963D01*
G01D02*
X906371Y498057D01*
G01X918701Y487191D02*
Y485380D01*
G01X913769Y494435D02*
Y489606D01*
G01X912536D02*
Y494435D01*
G01X910070D02*
Y489606D01*
G01X908837D02*
Y494435D01*
G01X906679Y499868D02*
X908529Y498661D01*
G01X906371Y498057D02*
X907604Y497453D01*
G01D02*
X908529Y497152D01*
G01X917468Y498963D02*
X918393Y500472D01*
G01X908529Y497152D02*
X910070Y496850D01*
G01X908529Y498661D02*
X910378Y498359D01*
G01D02*
X912536D01*
G01X910070Y496850D02*
X912844D01*
G01X916543Y498057D02*
X917468Y498963D01*
G01X912536Y494435D02*
X913769D01*
G01X908837D02*
X910070D01*
G01X913769Y489606D02*
X912536D01*
G01X910070D02*
X908837D01*
G01X918701Y485380D02*
X911920D01*
G01X912536Y498359D02*
X914385Y498661D01*
G01X912844Y496850D02*
X914385Y497152D01*
G01X915310Y497453D02*
X916543Y498057D01*
G01X914385Y498661D02*
X916235Y499868D01*
G01X914385Y497152D02*
X915310Y497453D01*
G01X918701Y502283D02*
X918393Y504094D01*
G01X917160Y502283D02*
X916851Y503792D01*
G01X905754Y502283D02*
X906063Y500774D01*
G01X910070Y513149D02*
X910378Y512244D01*
G01X909145D02*
X908837Y513149D01*
G01X918393Y504094D02*
X917468Y505603D01*
G01X916851Y503792D02*
X916235Y504698D01*
G01X906063Y500774D02*
X906679Y499868D01*
G01X917468Y505603D02*
X916543Y506509D01*
G01X910378Y512244D02*
X910995Y511640D01*
G01X909762D02*
X909145Y512244D01*
G01X916851Y500774D02*
X917160Y502283D01*
G01X918393Y500472D02*
X918701Y502283D01*
G01Y511640D02*
Y510131D01*
G01Y516469D02*
Y514960D01*
G01X910070Y513753D02*
Y513149D01*
G01X908837Y510131D02*
Y511640D01*
G01Y513149D02*
Y514357D01*
G01X916235Y504698D02*
X914385Y505905D01*
G01X916543Y506509D02*
X915310Y507113D01*
G01D02*
X914385Y507414D01*
G01X916235Y499868D02*
X916851Y500774D01*
G01X905446Y505603D02*
X904521Y504094D01*
G01X910378Y514357D02*
X910070Y513753D01*
G01X908837Y514357D02*
X909145Y515262D01*
G01X906063Y503792D02*
X905754Y502283D01*
G01X914385Y507414D02*
X912844Y507716D01*
G01X914385Y505905D02*
X912536Y506207D01*
G01X918701Y514960D02*
X911303D01*
G01X908837Y511640D02*
X909762D01*
G01X910995D02*
X918701D01*
G01Y510131D02*
X908837D01*
G01X912844Y507716D02*
X910070D01*
G01X912536Y506207D02*
X910378D01*
G01X906371Y506509D02*
X905446Y505603D01*
G01X910687Y514658D02*
X910378Y514357D01*
G01X909145Y515262D02*
X910070Y516168D01*
G01X906679Y504698D02*
X906063Y503792D01*
G01X910378Y506207D02*
X908529Y505905D01*
G01X910070Y507716D02*
X908529Y507414D01*
G01X907604Y507113D02*
X906371Y506509D01*
G01X911303Y514960D02*
X910687Y514658D01*
G01X908529Y505905D02*
X906679Y504698D01*
G01X908529Y507414D02*
X907604Y507113D01*
G01X909145Y530656D02*
X908837Y531561D01*
G01X910070Y526732D02*
X910378Y525826D01*
G01X909145D02*
X908837Y526732D01*
G01X909145Y517073D02*
X908837Y517979D01*
G01X910070Y531259D02*
X910378Y530656D01*
G01X910070Y517677D02*
X910378Y517073D01*
G01Y530656D02*
X910687Y530354D01*
G01X910070Y529750D02*
X909145Y530656D01*
G01X910378Y525826D02*
X910995Y525223D01*
G01X909762D02*
X909145Y525826D01*
G01X910378Y517073D02*
X910687Y516771D01*
G01X910070Y516168D02*
X909145Y517073D01*
G01X918701Y521299D02*
Y519790D01*
G01Y525223D02*
Y523713D01*
G01Y530052D02*
Y528543D01*
G01X910070Y518582D02*
Y517677D01*
G01Y527335D02*
Y526732D01*
G01Y532165D02*
Y531259D01*
G01X908837Y531561D02*
Y532768D01*
G01Y523713D02*
Y525223D01*
G01Y526732D02*
Y527939D01*
G01Y517979D02*
Y519186D01*
G01X910687Y530354D02*
X911303Y530052D01*
G01X910687Y516771D02*
X911303Y516469D01*
G01X910378Y519186D02*
X910070Y518582D01*
G01X910378Y527939D02*
X910070Y527335D01*
G01X910378Y532768D02*
X910070Y532165D01*
G01X908837Y519186D02*
X909145Y520091D01*
G01X908837Y527939D02*
X909145Y528845D01*
G01X911303Y530052D02*
X918701D01*
G01Y528543D02*
X911303D01*
G01X908837Y525223D02*
X909762D01*
G01X910995D02*
X918701D01*
G01Y523713D02*
X908837D01*
G01X911303Y521299D02*
X918701D01*
G01Y519790D02*
X911303D01*
G01Y516469D02*
X918701D01*
G01X910687Y519488D02*
X910378Y519186D01*
G01X909145Y520091D02*
X909762Y520695D01*
G01X910687Y528241D02*
X910378Y527939D01*
G01X909145Y528845D02*
X910070Y529750D01*
G01X909762Y520695D02*
X911303Y521299D01*
G01Y519790D02*
X910687Y519488D01*
G01X911303Y528543D02*
X910687Y528241D01*
G01X918701Y534881D02*
Y533372D01*
G01X908837Y532768D02*
X909145Y533674D01*
G01X911303Y534881D02*
X918701D01*
G01Y533372D02*
X911303D01*
G01X910687Y533070D02*
X910378Y532768D01*
G01X909145Y533674D02*
X909762Y534278D01*
G01D02*
X911303Y534881D01*
G01Y533372D02*
X910687Y533070D01*
G01X919134Y1038197D02*
X918335Y1038796D01*
X917936Y1039495D01*
X917803Y1040293D01*
X918069Y1041291D01*
X918735Y1041990D01*
X919533Y1042190D01*
X920332Y1042090D01*
X920997Y1041690D01*
X922328Y1039694D01*
X923259Y1038796D01*
X924591Y1038197D01*
X925788Y1037997D01*
Y1042190D01*
G01X924191Y1045883D02*
X925123Y1046481D01*
X925655Y1047280D01*
X925788Y1048178D01*
X925655Y1048977D01*
X924990Y1049775D01*
X924191Y1050274D01*
X923393Y1050374D01*
X922461Y1050175D01*
X921796Y1049476D01*
X921529Y1048777D01*
Y1047879D01*
G01Y1048777D02*
X921130Y1049376D01*
X920465Y1049875D01*
X919666Y1050075D01*
X918868Y1049875D01*
X918202Y1049376D01*
X917803Y1048478D01*
X917936Y1047579D01*
X918469Y1046681D01*
G01X925788Y1057261D02*
X917803D01*
X923526Y1053568D01*
Y1058559D01*
G01X926054Y1064048D02*
X925921Y1063849D01*
X925655D01*
X925522Y1064048D01*
X925655Y1064248D01*
X925921D01*
X926054Y1064048D01*
G01X925788Y1072033D02*
X917803D01*
X919400Y1070836D01*
G01X925788D02*
Y1073231D01*
G01X924591Y1077823D02*
X925256Y1078421D01*
X925655Y1079120D01*
X925788Y1080018D01*
X925522Y1080917D01*
X924990Y1081615D01*
X924058Y1082115D01*
X922993Y1082214D01*
X921929Y1082015D01*
X921263Y1081516D01*
X920731Y1080817D01*
X920598Y1080118D01*
X920731Y1079420D01*
X921263Y1078521D01*
X917803Y1078821D01*
Y1081516D01*
G01X929922Y771653D02*
Y228346D01*
G01X983859Y324212D02*
X929922D01*
G01X932107Y392401D02*
Y367598D01*
G01D02*
X981910D01*
G01Y392401D02*
X932107D01*
G01X929922Y429133D02*
X1400000D01*
G01X921850Y775590D02*
Y968503D01*
G01Y775590D02*
G03X925787Y771653I3937J0D01*
G01X984843D02*
X925787D01*
G01X921851Y775590D02*
G03X925788Y771653I3937J0D01*
G01D02*
X984843D01*
G01X921851Y968503D02*
Y775590D01*
G01X929725Y779527D02*
Y886881D01*
G01Y779527D02*
X980906D01*
G01X929725D02*
Y886881D01*
G01Y779527D02*
X980906D01*
G01X929725Y886881D02*
G03X921851I-3937J1D01*
G01X929725D02*
G03X921851I-3937J1D01*
G01Y912079D02*
G03X929725I3937J-1D01*
G01X921851D02*
G03X929725I3937J-1D01*
G01Y912078D02*
Y968504D01*
G01Y912078D02*
Y968504D01*
G01X921851Y968750D02*
Y1036744D01*
G01X929725Y968750D02*
Y1033910D01*
G01X934507Y1038197D02*
X933708Y1038796D01*
X933309Y1039495D01*
X933176Y1040293D01*
X933442Y1041291D01*
X934108Y1041990D01*
X934906Y1042190D01*
X935705Y1042090D01*
X936370Y1041690D01*
X937701Y1039694D01*
X938632Y1038796D01*
X939964Y1038197D01*
X941161Y1037997D01*
Y1042190D01*
G01X939564Y1045883D02*
X940496Y1046481D01*
X941028Y1047280D01*
X941161Y1048178D01*
X941028Y1048977D01*
X940363Y1049775D01*
X939564Y1050274D01*
X938766Y1050374D01*
X937834Y1050175D01*
X937169Y1049476D01*
X936902Y1048777D01*
Y1047879D01*
G01Y1048777D02*
X936503Y1049376D01*
X935838Y1049875D01*
X935039Y1050075D01*
X934241Y1049875D01*
X933575Y1049376D01*
X933176Y1048478D01*
X933309Y1047579D01*
X933842Y1046681D01*
G01X937834Y1054167D02*
X936902Y1054866D01*
X936370Y1055465D01*
X936104Y1056263D01*
X936370Y1056962D01*
X936902Y1057461D01*
X937701Y1057860D01*
X938632Y1057960D01*
X939431Y1057860D01*
X940230Y1057461D01*
X940895Y1056862D01*
X941161Y1056163D01*
X940895Y1055365D01*
X940097Y1054666D01*
X938899Y1054267D01*
X937568Y1054167D01*
X935838Y1054367D01*
X934906Y1054666D01*
X933975Y1055165D01*
X933309Y1055864D01*
X933176Y1056563D01*
X933442Y1057261D01*
X934108Y1057760D01*
G01X941427Y1064048D02*
X941294Y1063849D01*
X941028D01*
X940895Y1064048D01*
X941028Y1064248D01*
X941294D01*
X941427Y1064048D01*
G01X941161Y1072033D02*
X933176D01*
X934773Y1070836D01*
G01X941161D02*
Y1073231D01*
G01X939964Y1077823D02*
X940629Y1078421D01*
X941028Y1079120D01*
X941161Y1080018D01*
X940895Y1080917D01*
X940363Y1081615D01*
X939431Y1082115D01*
X938366Y1082214D01*
X937302Y1082015D01*
X936636Y1081516D01*
X936104Y1080817D01*
X935971Y1080118D01*
X936104Y1079420D01*
X936636Y1078521D01*
X933176Y1078821D01*
Y1081516D01*
G01X929725Y1033910D02*
X937224Y1035327D01*
G01X951772Y330590D02*
Y331491D01*
G01D02*
X954685D01*
G01X958977Y330590D02*
X951772D01*
G01X951925Y345450D02*
X952232Y346050D01*
G01X952692Y345150D02*
X952538Y344399D01*
G01X951772Y344549D02*
X951925Y345450D01*
G01Y342898D02*
X951772Y343949D01*
G01X952538Y343799D02*
X952692Y343048D01*
G01X953458Y345900D02*
X952998Y345600D01*
G01X952232Y346050D02*
X952845Y346651D01*
G01X952998Y345600D02*
X952692Y345150D01*
G01X953458Y342298D02*
Y341547D01*
G01X952538Y344399D02*
Y343799D01*
G01X951772Y343949D02*
Y344549D01*
G01Y335694D02*
Y336594D01*
G01X952232Y342298D02*
X951925Y342898D01*
G01X952692Y343048D02*
X952998Y342598D01*
G01X952845Y341698D02*
X952232Y342298D01*
G01X952998Y342598D02*
X953458Y342298D01*
G01Y341547D02*
X952845Y341698D01*
G01X953458Y346801D02*
X953765D01*
G01Y345900D02*
X953458D01*
G01X951772Y336594D02*
X958977D01*
G01X954685Y335694D02*
X951772D01*
G01X952845Y346651D02*
X953458Y346801D01*
G01X950906Y366614D02*
Y376456D01*
G01X947363D02*
Y366614D01*
G01X943032D02*
Y376456D01*
G01X939488D02*
Y366614D01*
G01X947363D02*
X950906D01*
G01X939488D02*
X943032D01*
G01X950906Y393385D02*
Y383543D01*
G01X947363D02*
Y393385D01*
G01X943032D02*
Y383543D01*
G01X939488D02*
Y393385D01*
G01X943032Y383543D02*
X939488D01*
G01X950906D02*
X947363D01*
G01X943032Y376456D02*
X939488D01*
G01X950906D02*
X947363D01*
G01Y393385D02*
X950906D01*
G01X939488D02*
X943032D01*
G01X959606Y850829D02*
G03X951024I-4291J0D01*
G01D02*
G03X959606I4291J0D01*
G01X937224Y1035327D02*
Y1036744D01*
G01X958977Y331491D02*
Y330590D01*
G01X955604Y335694D02*
Y331491D01*
G01X954685D02*
Y335694D01*
G01X955604Y331491D02*
X958977D01*
G01X954838Y350103D02*
X954685Y349803D01*
G01X954072Y350103D02*
X954225Y350553D01*
G01X958977Y336594D02*
Y335694D01*
G01Y348752D02*
Y348002D01*
G01Y346801D02*
Y341397D01*
G01Y351153D02*
Y350403D01*
G01X958210Y342598D02*
Y346801D01*
G01X956524Y340196D02*
Y337795D01*
G01X955911D02*
Y340196D01*
G01X954225Y351454D02*
X954072Y351904D01*
G01X954685Y349503D02*
X954838Y349052D01*
G01X954225D02*
X954072Y349503D01*
G01X954685Y351754D02*
X954838Y351454D01*
G01X954991Y350253D02*
X954838Y350103D01*
G01X954225Y350553D02*
X954685Y351003D01*
G01Y340196D02*
Y337795D01*
G01Y349803D02*
Y349503D01*
G01Y352204D02*
Y351754D01*
G01X954072Y351904D02*
Y352505D01*
G01Y348002D02*
Y348752D01*
G01Y349503D02*
Y350103D01*
G01Y337795D02*
Y340196D01*
G01X954838Y346350D02*
X958210Y342598D01*
G01Y341397D02*
X954378Y345600D01*
G01X955298Y350403D02*
X954991Y350253D01*
G01X954838Y351454D02*
X954991Y351304D01*
G01X954685Y351003D02*
X954225Y351454D01*
G01X954838Y349052D02*
X955144Y348752D01*
G01X954531D02*
X954225Y349052D01*
G01X954378Y346651D02*
X954838Y346350D01*
G01X954991Y351304D02*
X955298Y351153D01*
G01X954378Y345600D02*
X953765Y345900D01*
G01Y346801D02*
X954378Y346651D01*
G01X955298Y351153D02*
X958977D01*
G01Y350403D02*
X955298D01*
G01X954072Y348752D02*
X954531D01*
G01X955144D02*
X958977D01*
G01Y348002D02*
X954072D01*
G01X958210Y346801D02*
X958977D01*
G01Y341397D02*
X958210D01*
G01X955911Y340196D02*
X956524D01*
G01X954072D02*
X954685D01*
G01Y337795D02*
X954072D01*
G01X956524D02*
X955911D01*
G01X958977Y335694D02*
X955604D01*
G01X954838Y352505D02*
X954685Y352204D01*
G01X954838Y356857D02*
X954685Y356557D01*
G01X954838Y359259D02*
X954685Y358959D01*
G01X954072Y352505D02*
X954225Y352955D01*
G01X954072Y356857D02*
X954225Y357308D01*
G01X954072Y359259D02*
X954225Y359709D01*
G01X966654Y366614D02*
Y376456D01*
G01X963111D02*
Y366614D01*
G01X958977Y355507D02*
Y354756D01*
G01Y353555D02*
Y352805D01*
G01Y360310D02*
Y359559D01*
G01Y357908D02*
Y357157D01*
G01X958780Y366614D02*
Y376456D01*
G01X955237D02*
Y366614D01*
G01X954225Y358208D02*
X954072Y358659D01*
G01X954685Y356257D02*
X954838Y355807D01*
G01X954225D02*
X954072Y356257D01*
G01X954685Y358509D02*
X954838Y358208D01*
G01X954991Y352655D02*
X954838Y352505D01*
G01X954225Y352955D02*
X954531Y353255D01*
G01X954991Y357007D02*
X954838Y356857D01*
G01X954225Y357308D02*
X954685Y357758D01*
G01X954991Y359409D02*
X954838Y359259D01*
G01X954225Y359709D02*
X954531Y360009D01*
G01X954685Y358959D02*
Y358509D01*
G01Y356557D02*
Y356257D01*
G01X954072D02*
Y356857D01*
G01Y358659D02*
Y359259D01*
G01Y354756D02*
Y355507D01*
G01X954531Y353255D02*
X955298Y353555D01*
G01X954531Y360009D02*
X955298Y360310D01*
G01Y352805D02*
X954991Y352655D01*
G01X955298Y357157D02*
X954991Y357007D01*
G01X955298Y359559D02*
X954991Y359409D01*
G01X954838Y358208D02*
X954991Y358058D01*
G01X954685Y357758D02*
X954225Y358208D01*
G01X954838Y355807D02*
X955144Y355507D01*
G01X954531D02*
X954225Y355807D01*
G01X954991Y358058D02*
X955298Y357908D01*
G01X963111Y366614D02*
X966654D01*
G01X955237D02*
X958780D01*
G01X955298Y360310D02*
X958977D01*
G01Y359559D02*
X955298D01*
G01Y357908D02*
X958977D01*
G01Y357157D02*
X955298D01*
G01X954072Y355507D02*
X954531D01*
G01X955144D02*
X958977D01*
G01Y354756D02*
X954072D01*
G01X955298Y353555D02*
X958977D01*
G01Y352805D02*
X955298D01*
G01X966654Y393385D02*
Y383543D01*
G01X963111D02*
Y393385D01*
G01X958780D02*
Y383543D01*
G01X955237D02*
Y393385D01*
G01X958780Y383543D02*
X955237D01*
G01X966654D02*
X963111D01*
G01X958780Y376456D02*
X955237D01*
G01X966654D02*
X963111D01*
G01Y393385D02*
X966654D01*
G01X955237D02*
X958780D01*
G01X984201Y-7874D02*
G03Y0I0J3937D01*
G01Y-7874D02*
G03Y0I0J3937D01*
G01X983859Y192519D02*
Y429133D01*
G01Y192519D02*
X1023229D01*
G01X983859Y265354D02*
X1251575D01*
G01X981910Y367598D02*
Y392401D01*
G01X974528Y366614D02*
Y376456D01*
G01X973501Y365169D02*
Y359618D01*
G01X972807D02*
Y364224D01*
G01X972114Y363397D02*
Y364342D01*
G01X970985Y376456D02*
Y366614D01*
G01X972807Y364224D02*
X972114Y363397D01*
G01Y364342D02*
X972807Y365169D01*
G01X970985Y366614D02*
X974528D01*
G01X972807Y365169D02*
X973501D01*
G01Y359618D02*
X972807D01*
G01X974528Y393385D02*
Y383543D01*
G01X970985D02*
Y393385D01*
G01X974528Y383543D02*
X970985D01*
G01X974528Y376456D02*
X970985D01*
G01Y393385D02*
X974528D01*
G01X984843Y771653D02*
G03X988780Y775590I0J3937D01*
G01X984843Y771653D02*
G03X988780Y775590I0J3937D01*
G01X980907Y886881D02*
X980906Y779527D01*
G01X980907Y886881D02*
X980906Y779527D01*
G01X988781Y886881D02*
G03X980907I-3937J1D01*
G01X988781D02*
G03X980907I-3937J1D01*
G01Y912079D02*
G03X988781I3937J-1D01*
G01X980907D02*
G03X988781I3937J-1D01*
G01X980907D02*
X980906Y968504D01*
G01X980907Y912079D02*
X980906Y968504D01*
G01X1008465Y996063D02*
G03X980906Y968504I0J-27559D01*
G01Y968750D02*
Y1036067D01*
G01X1008465Y996063D02*
G03X980906Y968504I0J-27559D01*
G01X978189Y1037519D02*
X977390Y1038118D01*
X976991Y1038817D01*
X976858Y1039615D01*
X977124Y1040613D01*
X977790Y1041312D01*
X978588Y1041512D01*
X979387Y1041412D01*
X980052Y1041012D01*
X981383Y1039016D01*
X982314Y1038118D01*
X983646Y1037519D01*
X984843Y1037319D01*
Y1041512D01*
G01Y1048598D02*
X976858D01*
X982581Y1044905D01*
Y1049896D01*
G01X983912Y1053689D02*
X984577Y1054387D01*
X984843Y1055186D01*
X984577Y1055984D01*
X983779Y1056683D01*
X982581Y1057182D01*
X981383Y1057382D01*
X979919D01*
X978721Y1057182D01*
X977657Y1056683D01*
X977124Y1056084D01*
X976858Y1055385D01*
X977124Y1054587D01*
X977657Y1053988D01*
X978455Y1053589D01*
X979520Y1053389D01*
X980451Y1053589D01*
X981383Y1054088D01*
X981915Y1054687D01*
X982048Y1055385D01*
X981782Y1056184D01*
X981117Y1056783D01*
X979919Y1057382D01*
G01X985109Y1063370D02*
X984976Y1063171D01*
X984710D01*
X984577Y1063370D01*
X984710Y1063570D01*
X984976D01*
X985109Y1063370D01*
G01X984843Y1071355D02*
X976858D01*
X978455Y1070158D01*
G01X984843D02*
Y1072553D01*
G01X983646Y1077145D02*
X984311Y1077743D01*
X984710Y1078442D01*
X984843Y1079340D01*
X984577Y1080239D01*
X984045Y1080937D01*
X983113Y1081437D01*
X982048Y1081536D01*
X980984Y1081337D01*
X980318Y1080838D01*
X979786Y1080139D01*
X979653Y1079440D01*
X979786Y1078742D01*
X980318Y1077843D01*
X976858Y1078143D01*
Y1080838D01*
G01X1025440Y244094D02*
G03I-17323J0D01*
G01X1005118Y250393D02*
G03Y237795I0J-6299D01*
G01X1025440Y411417D02*
G03I-17323J0D01*
G01X1005118Y417716D02*
G03Y405118I0J-6299D01*
G01X988780Y968503D02*
Y775590D01*
G01D02*
Y968503D01*
G01Y968750D02*
Y1037059D01*
G01X1008465Y988189D02*
G03X988780Y968503I0J-19685D01*
G01X1008465Y988189D02*
G03X988780Y968503I0J-19685D01*
G01X993460Y1041346D02*
X992661Y1041945D01*
X992262Y1042644D01*
X992129Y1043442D01*
X992395Y1044440D01*
X993061Y1045139D01*
X993859Y1045339D01*
X994658Y1045239D01*
X995323Y1044839D01*
X996654Y1042843D01*
X997585Y1041945D01*
X998917Y1041346D01*
X1000114Y1041146D01*
Y1045339D01*
G01X998917Y1049032D02*
X999582Y1049630D01*
X999981Y1050329D01*
X1000114Y1051227D01*
X999848Y1052126D01*
X999316Y1052824D01*
X998384Y1053324D01*
X997319Y1053423D01*
X996255Y1053224D01*
X995589Y1052725D01*
X995057Y1052026D01*
X994924Y1051327D01*
X995057Y1050629D01*
X995589Y1049730D01*
X992129Y1050030D01*
Y1052725D01*
G01X1000114Y1059212D02*
X992129D01*
X993726Y1058015D01*
G01X1000114D02*
Y1060410D01*
G01X1000380Y1067197D02*
X1000247Y1066998D01*
X999981D01*
X999848Y1067197D01*
X999981Y1067397D01*
X1000247D01*
X1000380Y1067197D01*
G01X1000114Y1075182D02*
X992129D01*
X993726Y1073985D01*
G01X1000114D02*
Y1076380D01*
G01X998917Y1080972D02*
X999582Y1081570D01*
X999981Y1082269D01*
X1000114Y1083167D01*
X999848Y1084066D01*
X999316Y1084764D01*
X998384Y1085264D01*
X997319Y1085363D01*
X996255Y1085164D01*
X995589Y1084665D01*
X995057Y1083966D01*
X994924Y1083267D01*
X995057Y1082569D01*
X995589Y1081670D01*
X992129Y1081970D01*
Y1084665D01*
G01X996177Y1038476D02*
Y1039894D01*
G01X988780Y1037059D02*
X996177Y1038476D01*
G01X1009398Y-7874D02*
X1108229D01*
G01X1009398Y0D02*
G03Y-7874I-1J-3937D01*
G01D02*
X1108229D01*
G01X1009398Y0D02*
G03Y-7874I-1J-3937D01*
G01X1011418Y237795D02*
G03Y250393I0J6299D01*
G01D02*
X1005118D01*
G01Y237795D02*
X1011418D01*
G01Y405118D02*
G03Y417716I0J6299D01*
G01X1005118Y405118D02*
X1011418D01*
G01Y417716D02*
X1005118D01*
G01X1380315Y988189D02*
X1008465D01*
G01X1380315D02*
X1008465D01*
G01X1380315D02*
X1008465D01*
G01X1070592Y996063D02*
X1008466D01*
G01X1070592D02*
X1008466D01*
G01X1023229Y192519D02*
Y49212D01*
G01X1045473Y-6300D02*
G03X1046260Y-5512I0J787D01*
G01X1045473Y-7874D02*
G03X1047835Y-5512I0J2362D01*
G01X1049803Y-4567D02*
Y45039D01*
G01X1048622Y-5355D02*
Y-7874D01*
G01Y-5355D02*
Y-5512D01*
G01X1047835Y-5355D02*
Y45039D01*
G01Y-5512D02*
Y45039D01*
G01X1046260Y-5512D02*
Y52204D01*
G01D02*
Y-5355D01*
G01X1042520Y-7874D02*
Y-6300D01*
G01X1050591Y-5355D02*
X1049803Y-4567D01*
G01X1046260Y189D02*
X1047835D01*
G01X1046260Y151D02*
X1047835D01*
G01X1046260Y136D02*
X1047835D01*
G01Y-27D02*
X1046260D01*
G01X1091929Y-4567D02*
X1049803D01*
G01X1047835Y-5355D02*
X1095473D01*
G01X1046260D02*
X1095473D01*
G01X1048622Y-5512D02*
X1093111D01*
G01X1048622Y-6300D02*
X1093111D01*
G01X1042520D02*
X1045473D01*
G01X1048622Y-7874D02*
X1093111D01*
G01X1045473D02*
X1042520D01*
G01X1047835Y20302D02*
X1046260D01*
G01Y19590D02*
X1047835D01*
G01Y19514D02*
X1046260D01*
G01Y18802D02*
X1047835D01*
G01X1049528Y32598D02*
G03I-4528J0D01*
G01X1047048D02*
X1046260Y30575D01*
G01X1050040Y37126D02*
Y28070D01*
G01X1047048Y34880D02*
Y32598D01*
G01X1039961Y28070D02*
Y37126D01*
G01X1047048Y34880D02*
X1046260Y36480D01*
G01X1039961Y37126D02*
X1050040D01*
G01Y28070D02*
X1039961D01*
G01X1095473Y52204D02*
X1046260D01*
G01X1093898Y45039D02*
X1047835D01*
G01X1056214Y-2919D02*
G03X1057393Y-4016I1178J84D01*
G01X1059624D02*
G03X1060802Y-2919I0J1181D01*
G01X1060355Y-4804D02*
G03X1061533Y-3707I0J1181D01*
G01X1055483D02*
G03X1056662Y-4804I1178J84D01*
G01X1063409Y22544D02*
X1061533Y-3707D01*
G01X1062623Y22573D02*
X1060802Y-2919D01*
G01X1054394Y22573D02*
X1056214Y-2919D01*
G01X1053609Y22544D02*
X1055483Y-3707D01*
G01X1059624Y-4016D02*
X1057393D01*
G01X1060355Y-4804D02*
X1056662D01*
G01X1054394Y22573D02*
G03X1054198Y22755I-196J-15D01*
G01X1062820D02*
G03X1062623Y22573I-1J-197D01*
G01X1063409Y22544D02*
G03X1063212Y22755I-196J14D01*
G01X1053805D02*
G03X1053609Y22544I0J-197D01*
G01X1054198Y22755D02*
X1053805D01*
G01X1063212D02*
X1062820D01*
G01X1065283Y33171D02*
X1065151Y33104D01*
G01X1064429Y34545D02*
X1064561Y34612D01*
G01X1065217Y33372D02*
X1065118Y33305D01*
G01X1064495Y34344D02*
X1064594Y34411D01*
G01X1065414Y33305D02*
X1065283Y33171D01*
G01X1064298Y34411D02*
X1064429Y34545D01*
G01X1065283Y33472D02*
X1065217Y33372D01*
G01X1064429Y34243D02*
X1064495Y34344D01*
G01X1065479Y33439D02*
X1065414Y33305D01*
G01X1064233Y34277D02*
X1064298Y34411D01*
G01X1063740Y34310D02*
X1063281Y33070D01*
G01X1063150Y33238D02*
X1063642Y34645D01*
G01X1065315Y33607D02*
X1065283Y33472D01*
G01X1064397Y34109D02*
X1064429Y34243D01*
G01X1065512Y33607D02*
X1065479Y33439D01*
G01X1064200Y34109D02*
X1064233Y34277D01*
G01X1068399Y33272D02*
Y33070D01*
G01Y34645D02*
Y34444D01*
G01X1068268Y34009D02*
Y33807D01*
G01X1067415Y34444D02*
Y34009D01*
G01Y33807D02*
Y33272D01*
G01X1067218Y33070D02*
Y34645D01*
G01X1066956Y33272D02*
Y33070D01*
G01X1065972Y34645D02*
Y33272D01*
G01X1065775Y33070D02*
Y34645D01*
G01X1065512Y34109D02*
Y33607D01*
G01X1065315Y34109D02*
Y33607D01*
G01X1064397D02*
Y34109D01*
G01X1064200Y33607D02*
Y34109D01*
G01X1063937Y34645D02*
Y33070D01*
G01X1063740D02*
Y34310D01*
G01X1062559D02*
Y33070D01*
G01X1062363D02*
Y34645D01*
G01X1065479Y34277D02*
X1065512Y34109D01*
G01X1064233Y33439D02*
X1064200Y33607D01*
G01X1065283Y34243D02*
X1065315Y34109D01*
G01X1064429Y33472D02*
X1064397Y33607D01*
G01X1062658Y34645D02*
X1063150Y33238D01*
G01X1063019Y33070D02*
X1062559Y34310D01*
G01X1065414Y34411D02*
X1065479Y34277D01*
G01X1064298Y33305D02*
X1064233Y33439D01*
G01X1065217Y34344D02*
X1065283Y34243D01*
G01X1064495Y33372D02*
X1064429Y33472D01*
G01X1065283Y34545D02*
X1065414Y34411D01*
G01X1064429Y33171D02*
X1064298Y33305D01*
G01X1065118Y34411D02*
X1065217Y34344D01*
G01X1064594Y33305D02*
X1064495Y33372D01*
G01X1065151Y34612D02*
X1065283Y34545D01*
G01X1064561Y33104D02*
X1064429Y33171D01*
G01X1064987Y34444D02*
X1065118Y34411D01*
G01X1064725Y33272D02*
X1064594Y33305D01*
G01X1064987Y34645D02*
X1065151Y34612D01*
G01X1064725Y33070D02*
X1064561Y33104D01*
G01X1067218Y34645D02*
X1068399D01*
G01X1065775D02*
X1065972D01*
G01X1064725D02*
X1064987D01*
G01X1063642D02*
X1063937D01*
G01X1062363D02*
X1062658D01*
G01X1064725Y34444D02*
X1064987D01*
G01X1068399D02*
X1067415D01*
G01Y34009D02*
X1068268D01*
G01Y33807D02*
X1067415D01*
G01Y33272D02*
X1068399D01*
G01X1065972D02*
X1066956D01*
G01X1064987D02*
X1064725D01*
G01X1063281Y33070D02*
X1063019D01*
G01X1062559D02*
X1062363D01*
G01X1068399D02*
X1067218D01*
G01X1066956D02*
X1065775D01*
G01X1064987D02*
X1064725D01*
G01X1063937D02*
X1063740D01*
G01X1064561Y34612D02*
X1064725Y34645D01*
G01X1065151Y33104D02*
X1064987Y33070D01*
G01X1064594Y34411D02*
X1064725Y34444D01*
G01X1065118Y33305D02*
X1064987Y33272D01*
G01X1056031Y49495D02*
G03Y48511I0J-492D01*
G01X1062786D02*
G03Y49495I0J492D01*
G01X1054063Y50184D02*
G03Y47822I-1J-1181D01*
G01X1064755D02*
G03Y50184I0J1181D01*
G01X1058662Y43267D02*
G03I-1575J0D01*
G01X1068504D02*
G03I-1575J0D01*
G01X1068800D02*
G03I-1871J0D01*
G01X1058957D02*
G03I-1870J0D01*
G01X1066565Y43880D02*
X1066690Y43944D01*
G01X1066721Y43785D02*
X1066627Y43721D01*
G01X1067407Y43339D02*
X1066627Y42639D01*
G01X1066378D02*
X1067251Y43435D01*
G01X1066440Y43753D02*
X1066565Y43880D01*
G01X1056998Y43721D02*
X1056811Y43498D01*
G01Y43753D02*
X1056998Y43976D01*
G01X1067469Y43435D02*
X1067407Y43339D01*
G01X1066627Y43721D02*
X1066565Y43626D01*
G01X1062786Y49495D02*
X1064755Y50184D01*
G01X1056031Y48511D02*
X1054063Y47822D01*
G01X1067251Y43435D02*
X1067313Y43562D01*
G01X1067500D02*
X1067469Y43435D01*
G01X1066409Y43626D02*
X1066440Y43753D01*
G01X1067500Y43626D02*
Y43562D01*
G01Y42639D02*
Y42480D01*
G01X1067313Y43562D02*
Y43626D01*
G01X1066378Y42480D02*
Y42639D01*
G01X1057185Y43976D02*
Y42480D01*
G01X1056998D02*
Y43721D01*
G01X1056811Y43498D02*
Y43753D01*
G01X1067469D02*
X1067500Y43626D01*
G01X1067313D02*
X1067251Y43721D01*
G01X1067344Y43880D02*
X1067469Y43753D01*
G01X1067251Y43721D02*
X1067157Y43785D01*
G01X1067220Y43944D02*
X1067344Y43880D01*
G01X1062786Y48511D02*
X1064755Y47822D01*
G01X1056031Y49495D02*
X1054063Y50184D01*
G01X1067157Y43785D02*
X1067001Y43817D01*
G01X1067033Y43976D02*
X1067220Y43944D01*
G01X1054063Y50184D02*
X1064755D01*
G01X1056031Y49495D02*
X1062786D01*
G01Y48511D02*
X1056031D01*
G01X1064755Y47822D02*
X1054063D01*
G01X1066908Y43976D02*
X1067033D01*
G01X1056998D02*
X1057185D01*
G01X1067001Y43817D02*
X1066877D01*
G01X1066565Y43626D02*
X1066409D01*
G01X1066627Y42639D02*
X1067500D01*
G01X1057185Y42480D02*
X1056998D01*
G01X1067500D02*
X1066378D01*
G01X1066690Y43944D02*
X1066908Y43976D01*
G01X1066877Y43817D02*
X1066721Y43785D01*
G01X1067284Y232322D02*
Y244133D01*
G01X1068760Y232322D02*
X1067284D01*
G01Y244133D02*
X1068760D01*
G01X1064469Y346434D02*
Y340905D01*
G01Y352716D02*
Y347941D01*
G01X1062992Y340905D02*
Y352716D01*
G01X1064469Y347941D02*
X1071359D01*
G01Y346434D02*
X1064469D01*
G01Y340905D02*
X1062992D01*
G01Y352716D02*
X1064469D01*
G01X1080931Y-2919D02*
G03X1082109Y-4016I1178J84D01*
G01X1084340D02*
G03X1085518Y-2919I0J1181D01*
G01X1080200Y-3707D02*
G03X1081377Y-4804I1178J84D01*
G01X1079110Y22573D02*
X1080931Y-2919D01*
G01X1080200Y-3707D02*
X1078324Y22544D01*
G01X1082109Y-4016D02*
X1084340D01*
G01X1085071Y-4804D02*
X1081377D01*
G01X1078521Y22755D02*
G03X1078324Y22544I-1J-197D01*
G01X1079110Y22573D02*
G03X1078914Y22755I-196J-15D01*
G01X1078521D02*
X1078914D01*
G01X1080866Y33171D02*
X1080735Y33104D01*
G01Y33272D02*
X1080801Y33305D01*
G01X1078701Y33171D02*
X1078570Y33104D01*
G01Y33272D02*
X1078635Y33305D01*
G01X1080079Y34545D02*
X1080210Y34612D01*
G01X1077914Y34545D02*
X1078045Y34612D01*
G01X1082146Y33104D02*
X1082310Y33204D01*
G01X1081654Y34612D02*
X1081490Y34511D01*
G01X1075551Y33104D02*
X1075716Y33204D01*
G01X1072664Y33104D02*
X1072828Y33204D01*
G01X1075059Y34612D02*
X1074895Y34511D01*
G01X1072172Y34612D02*
X1072008Y34511D01*
G01X1082212Y33339D02*
X1082113Y33272D01*
G01X1082146Y33674D02*
X1082343Y33807D01*
G01X1082113Y33841D02*
X1082212Y33908D01*
G01X1080965Y33238D02*
X1080866Y33171D01*
G01X1081687Y34444D02*
X1081588Y34377D01*
G01X1078800Y33238D02*
X1078701Y33171D01*
G01X1080243Y34444D02*
X1080145Y34377D01*
G01X1078078Y34444D02*
X1077979Y34377D01*
G01X1075519Y33272D02*
X1075617Y33339D01*
G01X1075092Y33875D02*
X1074994Y33807D01*
G01X1075059Y34042D02*
X1074863Y33908D01*
G01X1074994Y34377D02*
X1075092Y34444D01*
G01X1072631Y33272D02*
X1072730Y33339D01*
G01X1072205Y33875D02*
X1072107Y33807D01*
G01X1072172Y34042D02*
X1071975Y33908D01*
G01X1072107Y34377D02*
X1072205Y34444D01*
G01X1080932Y33975D02*
X1080801Y33875D01*
G01X1078767Y33975D02*
X1078635Y33875D01*
G01X1080801Y33305D02*
X1080866Y33372D01*
G01X1080735Y34009D02*
X1080801Y34076D01*
G01X1079948Y34411D02*
X1080079Y34545D01*
G01X1078635Y33305D02*
X1078701Y33372D01*
G01X1078570Y34009D02*
X1078635Y34076D01*
G01X1077783Y34411D02*
X1077914Y34545D01*
G01X1074994Y33807D02*
X1074928Y33740D01*
G01X1072107Y33807D02*
X1072041Y33740D01*
G01X1076372D02*
X1076929Y34377D01*
G01X1076142Y33740D02*
X1076929Y34645D01*
G01X1083622Y34377D02*
X1083425Y34142D01*
G01Y34411D02*
X1083622Y34645D01*
G01X1082966Y34377D02*
X1082769Y34142D01*
G01Y34411D02*
X1082966Y34645D01*
G01X1082310Y33204D02*
X1082409Y33339D01*
G01X1081490Y34511D02*
X1081391Y34377D01*
G01X1075716Y33204D02*
X1075814Y33339D01*
G01X1074895Y34511D02*
X1074797Y34377D01*
G01X1072828Y33204D02*
X1072927Y33339D01*
G01X1072008Y34511D02*
X1071910Y34377D01*
G01X1069974Y34645D02*
X1069416Y33875D01*
G01X1069318Y33707D02*
X1068859Y33070D01*
G01X1069318Y34009D02*
X1069777Y34645D01*
G01X1068662Y33070D02*
X1069220Y33875D01*
G01X1082277Y33439D02*
X1082212Y33339D01*
G01Y33908D02*
X1082277Y34009D01*
G01X1081031Y33339D02*
X1080965Y33238D01*
G01X1081588Y34377D02*
X1081523Y34277D01*
G01X1080998Y34076D02*
X1080932Y33975D01*
G01X1080145Y34377D02*
X1080079Y34277D01*
G01X1078865Y33339D02*
X1078800Y33238D01*
G01X1078832Y34076D02*
X1078767Y33975D01*
G01X1077979Y34377D02*
X1077914Y34277D01*
G01X1075617Y33339D02*
X1075683Y33439D01*
G01X1074928Y34277D02*
X1074994Y34377D01*
G01X1072730Y33339D02*
X1072796Y33439D01*
G01X1072041Y34277D02*
X1072107Y34377D01*
G01X1080866Y33372D02*
X1080899Y33439D01*
G01X1080801Y34076D02*
X1080866Y34210D01*
G01X1078701Y33372D02*
X1078734Y33439D01*
G01X1078635Y34076D02*
X1078701Y34210D01*
G01X1074436Y34477D02*
X1073780Y33070D01*
G01X1073583D02*
X1074239Y34477D01*
G01X1082113Y33272D02*
X1082015Y33238D01*
G01Y33807D02*
X1082113Y33841D01*
G01X1080538Y33942D02*
X1080735Y34009D01*
G01X1081785Y34477D02*
X1081687Y34444D01*
G01X1078373Y33942D02*
X1078570Y34009D01*
G01X1075420Y33238D02*
X1075519Y33272D01*
G01X1075190Y33908D02*
X1075092Y33875D01*
G01X1072533Y33238D02*
X1072631Y33272D01*
G01X1075092Y34444D02*
X1075190Y34477D01*
G01X1072303Y33908D02*
X1072205Y33875D01*
G01Y34444D02*
X1072303Y34477D01*
G01X1082409Y33339D02*
X1082474Y33506D01*
G01X1081391Y34377D02*
X1081326Y34210D01*
G01X1075814Y33339D02*
X1075879Y33506D01*
G01X1074797Y34377D02*
X1074731Y34210D01*
G01X1072927Y33339D02*
X1072992Y33506D01*
G01X1071910Y34377D02*
X1071844Y34210D01*
G01X1082310Y33539D02*
X1082277Y33439D01*
G01Y34009D02*
X1082310Y34109D01*
G01X1081523Y34277D02*
X1081490Y34176D01*
G01X1081063Y33439D02*
X1081031Y33339D01*
G01X1078898Y33439D02*
X1078865Y33339D01*
G01X1075683Y33439D02*
X1075716Y33539D01*
G01X1074928Y33740D02*
X1074895Y33640D01*
G01Y34176D02*
X1074928Y34277D01*
G01X1072796Y33439D02*
X1072828Y33539D01*
G01X1072041Y33740D02*
X1072008Y33640D01*
G01Y34176D02*
X1072041Y34277D01*
G01X1081031Y34210D02*
X1080998Y34076D01*
G01X1079915Y34277D02*
X1079948Y34411D01*
G01X1078865Y34210D02*
X1078832Y34076D01*
G01X1077750Y34277D02*
X1077783Y34411D01*
G01X1082343Y33740D02*
X1082310Y33539D01*
G01X1074863Y33975D02*
X1074895Y34176D01*
G01X1071975Y33975D02*
X1072008Y34176D01*
G01X1082474Y33506D02*
X1082507Y33740D01*
G01X1074731Y34210D02*
X1074698Y33975D01*
G01X1071844Y34210D02*
X1071811Y33975D01*
G01X1083819Y34645D02*
Y33070D01*
G01X1083622D02*
Y34377D01*
G01X1083425Y34142D02*
Y34411D01*
G01X1083163Y34645D02*
Y33070D01*
G01X1082966D02*
Y34377D01*
G01X1082769Y34142D02*
Y34411D01*
G01X1082507Y33740D02*
Y33975D01*
G01X1082343Y33807D02*
Y33740D01*
G01X1082310Y34109D02*
Y34176D01*
G01X1081490D02*
Y34109D01*
G01X1081326Y34210D02*
Y34076D01*
G01X1081063Y33573D02*
Y33439D01*
G01X1081031Y34277D02*
Y34210D01*
G01X1080899Y33439D02*
Y33573D01*
G01X1080866Y34210D02*
Y34277D01*
G01X1080407Y33807D02*
Y33942D01*
G01X1079620Y33807D02*
Y33640D01*
G01X1079161D02*
Y33807D01*
G01X1078898Y33573D02*
Y33439D01*
G01X1078865Y34277D02*
Y34210D01*
G01X1078734Y33439D02*
Y33573D01*
G01X1078701Y34210D02*
Y34277D01*
G01X1082507Y33975D02*
X1082474Y34210D01*
G01X1078242Y33807D02*
Y33942D01*
G01X1077454Y33740D02*
Y33539D01*
G01X1077126Y34645D02*
Y33740D01*
G01Y33539D02*
Y33070D01*
G01X1076929D02*
Y33539D01*
G01Y34377D02*
Y33740D01*
G01X1076142Y33539D02*
Y33740D01*
G01X1075879Y33506D02*
Y33674D01*
G01X1075716Y33539D02*
Y33640D01*
G01X1074895D02*
Y33539D01*
G01X1074863Y33908D02*
Y33975D01*
G01X1074698D02*
Y33740D01*
G01X1074436Y34645D02*
Y34477D01*
G01X1073255D02*
Y34645D01*
G01X1072992Y33506D02*
Y33674D01*
G01X1072828Y33539D02*
Y33640D01*
G01X1072008D02*
Y33539D01*
G01X1071975Y33908D02*
Y33975D01*
G01X1071811D02*
Y33740D01*
G01X1074698D02*
X1074731Y33506D01*
G01X1071811Y33740D02*
X1071844Y33506D01*
G01X1080998Y34411D02*
X1081031Y34277D01*
G01Y33707D02*
X1081063Y33573D01*
G01X1078832Y34411D02*
X1078865Y34277D01*
G01Y33707D02*
X1078898Y33573D01*
G01X1082310Y34176D02*
X1082277Y34277D01*
G01X1081490Y34109D02*
X1081523Y34009D01*
G01X1081391Y33439D02*
X1081424Y33339D01*
G01X1079915D02*
X1079882Y33439D01*
G01X1077750Y33339D02*
X1077717Y33439D01*
G01X1075814Y34277D02*
X1075781Y34377D01*
G01X1075716Y33640D02*
X1075683Y33740D01*
G01X1074895Y33539D02*
X1074928Y33439D01*
G01X1072927Y34277D02*
X1072894Y34377D01*
G01X1072828Y33640D02*
X1072796Y33740D01*
G01X1072008Y33539D02*
X1072041Y33439D01*
G01X1082474Y34210D02*
X1082409Y34377D01*
G01X1081326Y34076D02*
X1081391Y33908D01*
G01X1075879Y33674D02*
X1075814Y33841D01*
G01X1074731Y33506D02*
X1074797Y33339D01*
G01X1072992Y33674D02*
X1072927Y33841D01*
G01X1071844Y33506D02*
X1071910Y33339D01*
G01X1080899Y33573D02*
X1080834Y33707D01*
G01X1080046Y33439D02*
X1080079Y33372D01*
G01X1078734Y33573D02*
X1078668Y33707D01*
G01X1077881Y33439D02*
X1077914Y33372D01*
G01X1082277Y34277D02*
X1082212Y34377D01*
G01X1081523Y34009D02*
X1081588Y33908D01*
G01X1081621Y33339D02*
X1081555Y33439D01*
G01X1080866Y34277D02*
X1080801Y34377D01*
G01X1080965Y33807D02*
X1081031Y33707D01*
G01X1079981Y33238D02*
X1079915Y33339D01*
G01X1078701Y34277D02*
X1078635Y34377D01*
G01X1078800Y33807D02*
X1078865Y33707D01*
G01X1077815Y33238D02*
X1077750Y33339D01*
G01X1075584Y34377D02*
X1075650Y34277D01*
G01X1074928Y33439D02*
X1074994Y33339D01*
G01X1072697Y34377D02*
X1072763Y34277D01*
G01X1072041Y33439D02*
X1072107Y33339D01*
G01X1069416Y33875D02*
X1069974Y33070D01*
G01X1068859Y34645D02*
X1069318Y34009D01*
G01X1069777Y33070D02*
X1069318Y33707D01*
G01X1082409Y34377D02*
X1082310Y34511D01*
G01X1081391Y33908D02*
X1081490Y33774D01*
G01X1081424Y33339D02*
X1081523Y33204D01*
G01X1075781Y34377D02*
X1075683Y34511D01*
G01X1074797Y33339D02*
X1074895Y33204D01*
G01X1069220Y33875D02*
X1068662Y34645D01*
G01X1072894Y34377D02*
X1072796Y34511D01*
G01X1071910Y33339D02*
X1072008Y33204D01*
G01X1080866Y34545D02*
X1080998Y34411D01*
G01X1080079Y33372D02*
X1080145Y33305D01*
G01X1078701Y34545D02*
X1078832Y34411D01*
G01X1077914Y33372D02*
X1077979Y33305D01*
G01X1075814Y33841D02*
X1075716Y33942D01*
G01X1075683Y33740D02*
X1075617Y33807D01*
G01X1072927Y33841D02*
X1072828Y33942D01*
G01X1072796Y33740D02*
X1072730Y33807D01*
G01X1082212Y34377D02*
X1082113Y34444D01*
G01X1081588Y33908D02*
X1081687Y33841D01*
G01X1080801Y34377D02*
X1080702Y34444D01*
G01X1081720Y33272D02*
X1081621Y33339D01*
G01X1080834Y33707D02*
X1080735Y33774D01*
G01X1078635Y34377D02*
X1078537Y34444D01*
G01X1080079Y33171D02*
X1079981Y33238D01*
G01X1078668Y33707D02*
X1078570Y33774D01*
G01X1077914Y33171D02*
X1077815Y33238D01*
G01X1075486Y34444D02*
X1075584Y34377D01*
G01X1075617Y33807D02*
X1075519Y33875D01*
G01X1074994Y33339D02*
X1075092Y33272D01*
G01X1072599Y34444D02*
X1072697Y34377D01*
G01X1072730Y33807D02*
X1072631Y33875D01*
G01X1072107Y33339D02*
X1072205Y33272D01*
G01X1082310Y34511D02*
X1082146Y34612D01*
G01X1081490Y33774D02*
X1081654Y33674D01*
G01X1081523Y33204D02*
X1081687Y33104D01*
G01X1075683Y34511D02*
X1075519Y34612D01*
G01X1075716Y33942D02*
X1075551Y34042D01*
G01X1072796Y34511D02*
X1072631Y34612D01*
G01X1074895Y33204D02*
X1075059Y33104D01*
G01X1072828Y33942D02*
X1072664Y34042D01*
G01X1072008Y33204D02*
X1072172Y33104D01*
G01X1080735Y34612D02*
X1080866Y34545D01*
G01X1078570Y34612D02*
X1078701Y34545D01*
G01X1080145Y33305D02*
X1080210Y33272D01*
G01Y33104D02*
X1080079Y33171D01*
G01X1077979Y33305D02*
X1078045Y33272D01*
G01Y33104D02*
X1077914Y33171D01*
G01X1080801Y33875D02*
X1080965Y33807D01*
G01X1078635Y33875D02*
X1078800Y33807D01*
G01X1082113Y34444D02*
X1082015Y34477D01*
G01X1081687Y33841D02*
X1081785Y33807D01*
G01X1081818Y33238D02*
X1081720Y33272D01*
G01X1075387Y34477D02*
X1075486Y34444D01*
G01X1075519Y33875D02*
X1075420Y33908D01*
G01X1072500Y34477D02*
X1072599Y34444D01*
G01X1075092Y33272D02*
X1075190Y33238D01*
G01X1072631Y33875D02*
X1072533Y33908D01*
G01X1072205Y33272D02*
X1072303Y33238D01*
G01X1080342Y33070D02*
X1080210Y33104D01*
G01X1078176Y33070D02*
X1078045Y33104D01*
G01X1082146Y34612D02*
X1081982Y34645D01*
G01X1080702Y34444D02*
X1080538Y34477D01*
G01X1078537Y34444D02*
X1078373Y34477D01*
G01X1081654Y33674D02*
X1081818Y33640D01*
G01X1075519Y34612D02*
X1075355Y34645D01*
G01X1081687Y33104D02*
X1081851Y33070D01*
G01X1080210Y33272D02*
X1080374Y33238D01*
G01X1075551Y34042D02*
X1075387Y34076D01*
G01X1072631Y34612D02*
X1072468Y34645D01*
G01X1078045Y33272D02*
X1078209Y33238D01*
G01X1072664Y34042D02*
X1072500Y34076D01*
G01X1075059Y33104D02*
X1075224Y33070D01*
G01X1072172Y33104D02*
X1072336Y33070D01*
G01X1080735Y33774D02*
X1080538Y33807D01*
G01X1078570Y33774D02*
X1078373Y33807D01*
G01X1080505Y34645D02*
X1080735Y34612D01*
G01X1078340Y34645D02*
X1078570Y34612D01*
G01X1083622Y34645D02*
X1083819D01*
G01X1082966D02*
X1083163D01*
G01X1080440D02*
X1080505D01*
G01X1078275D02*
X1078340D01*
G01X1076929D02*
X1077126D01*
G01X1073255D02*
X1074436D01*
G01X1068662D02*
X1068859D01*
G01X1069777D02*
X1069974D01*
G01X1072468D02*
X1072336D01*
G01X1075355D02*
X1075224D01*
G01X1081982D02*
X1081818D01*
G01X1075190Y34477D02*
X1075387D01*
G01X1072303D02*
X1072500D01*
G01X1074239D02*
X1073255D01*
G01X1082015D02*
X1081785D01*
G01X1080538D02*
X1080407D01*
G01X1078373D02*
X1078242D01*
G01X1075650Y34277D02*
X1075814D01*
G01X1072763D02*
X1072927D01*
G01X1080079D02*
X1079915D01*
G01X1077914D02*
X1077750D01*
G01X1072500Y34076D02*
X1072336D01*
G01X1075387D02*
X1075224D01*
G01X1080407Y33942D02*
X1080538D01*
G01X1078242D02*
X1078373D01*
G01X1072533Y33908D02*
X1072303D01*
G01X1075420D02*
X1075190D01*
G01X1081785Y33807D02*
X1082015D01*
G01X1079161D02*
X1079620D01*
G01X1080538D02*
X1080407D01*
G01X1078373D02*
X1078242D01*
G01X1077126Y33740D02*
X1077454D01*
G01X1076929D02*
X1076372D01*
G01X1081818Y33640D02*
X1081982D01*
G01X1079620D02*
X1079161D01*
G01X1076929Y33539D02*
X1076142D01*
G01X1077454D02*
X1077126D01*
G01X1079882Y33439D02*
X1080046D01*
G01X1077717D02*
X1077881D01*
G01X1081555D02*
X1081391D01*
G01X1080374Y33238D02*
X1080571D01*
G01X1078209D02*
X1078406D01*
G01X1075190D02*
X1075420D01*
G01X1072303D02*
X1072533D01*
G01X1082015D02*
X1081818D01*
G01X1081851Y33070D02*
X1081982D01*
G01X1075224D02*
X1075387D01*
G01X1072336D02*
X1072500D01*
G01X1068859D02*
X1068662D01*
G01X1069974D02*
X1069777D01*
G01X1077126D02*
X1076929D01*
G01X1073780D02*
X1073583D01*
G01X1080604D02*
X1080342D01*
G01X1078438D02*
X1078176D01*
G01X1083819D02*
X1083622D01*
G01X1083163D02*
X1082966D01*
G01X1078045Y34612D02*
X1078275Y34645D01*
G01X1080210Y34612D02*
X1080440Y34645D01*
G01X1072336D02*
X1072172Y34612D01*
G01X1072336Y34076D02*
X1072172Y34042D01*
G01X1075224Y34645D02*
X1075059Y34612D01*
G01X1075224Y34076D02*
X1075059Y34042D01*
G01X1078242Y34477D02*
X1078078Y34444D01*
G01X1072500Y33070D02*
X1072664Y33104D01*
G01X1080407Y34477D02*
X1080243Y34444D01*
G01X1081818Y34645D02*
X1081654Y34612D01*
G01X1075387Y33070D02*
X1075551Y33104D01*
G01X1078406Y33238D02*
X1078570Y33272D01*
G01X1081982Y33640D02*
X1082146Y33674D01*
G01X1080571Y33238D02*
X1080735Y33272D01*
G01X1081982Y33070D02*
X1082146Y33104D01*
G01X1078570D02*
X1078438Y33070D01*
G01X1080735Y33104D02*
X1080604Y33070D01*
G01X1078947Y49495D02*
G03Y48511I0J-492D01*
G01X1076978Y50184D02*
G03Y47822I0J-1181D01*
G01X1086221Y43267D02*
G03I-1575J0D01*
G01X1086516D02*
G03I-1870J0D01*
G01X1076378D02*
G03I-1575J0D01*
G01X1076674D02*
G03I-1871J0D01*
G01X1078947Y48511D02*
X1076978Y47822D01*
G01X1078947Y49495D02*
X1076978Y50184D01*
G01X1087670D02*
X1076978D01*
G01X1085702Y49495D02*
X1078947D01*
G01Y48511D02*
X1085702D01*
G01X1076978Y47822D02*
X1087670D01*
G01X1083032Y237348D02*
Y236343D01*
G01X1079095D02*
Y237348D01*
G01X1077126Y244133D02*
Y232322D01*
G01X1075650D02*
Y237851D01*
G01X1068760D02*
Y232322D01*
G01X1083032Y236343D02*
X1079095D01*
G01X1077126Y232322D02*
X1075650D01*
G01X1083032Y240364D02*
Y239359D01*
G01X1079095D02*
Y240364D01*
G01X1075650Y239359D02*
Y244133D01*
G01X1068760D02*
Y239359D01*
G01X1075650Y244133D02*
X1077126D01*
G01X1079095Y240364D02*
X1083032D01*
G01X1068760Y239359D02*
X1075650D01*
G01X1083032D02*
X1079095D01*
G01X1075650Y237851D02*
X1068760D01*
G01X1079095Y237348D02*
X1083032D01*
G01X1083662Y352716D02*
Y340905D01*
G01X1082185D02*
Y350706D01*
G01X1080709Y348947D02*
Y350957D01*
G01X1078740Y345931D02*
Y344926D01*
G01Y348947D02*
Y347941D01*
G01X1082185Y350706D02*
X1080709Y348947D01*
G01Y350957D02*
X1082185Y352716D01*
G01X1074803Y347941D02*
Y348947D01*
G01Y344926D02*
Y345931D01*
G01X1072835Y352716D02*
Y340905D01*
G01X1071359Y347941D02*
Y352716D01*
G01Y340905D02*
Y346434D01*
G01X1074803Y348947D02*
X1078740D01*
G01Y347941D02*
X1074803D01*
G01Y345931D02*
X1078740D01*
G01Y344926D02*
X1074803D01*
G01X1072835Y340905D02*
X1071359D01*
G01X1083662D02*
X1082185D01*
G01Y352716D02*
X1083662D01*
G01X1071359D02*
X1072835D01*
G01X1074803Y641490D02*
Y630433D01*
G01X1071851D02*
Y654055D01*
G01X1074803Y630433D02*
X1071851D01*
G01X1074803Y654055D02*
Y644505D01*
G01D02*
X1088583D01*
G01Y641490D02*
X1074803D01*
G01X1071851Y654055D02*
X1074803D01*
G01X1070592Y988189D02*
G03Y996063I0J3937D01*
G01Y988189D02*
G03Y996063I0J3937D01*
G01X1095473Y-5512D02*
G03X1096260Y-6300I787J-1D01*
G01X1085071Y-4804D02*
G03X1086250Y-3707I1J1181D01*
G01X1093898Y-5512D02*
G03X1096260Y-7874I2362J0D01*
G01X1091142Y-5355D02*
X1091929Y-4567D01*
G01X1088125Y22544D02*
X1086250Y-3707D01*
G01X1085518Y-2919D02*
X1087339Y22573D01*
G01X1099213Y-7874D02*
Y-6300D01*
G01X1095473Y-5355D02*
Y52204D01*
G01Y-5355D02*
Y52204D01*
G01Y-5512D02*
Y-5355D01*
G01X1093898Y-5512D02*
Y45039D01*
G01Y20302D02*
Y-27D01*
G01X1093111Y-5355D02*
Y-7874D01*
G01Y-5355D02*
Y-5512D01*
G01X1091929Y-4567D02*
Y45039D01*
G01X1095473Y189D02*
X1093898D01*
G01X1095473Y151D02*
X1093898D01*
G01X1095473Y136D02*
X1093898D01*
G01X1095473Y-27D02*
X1093898D01*
G01X1099213Y-6300D02*
X1096260D01*
G01Y-7874D02*
X1099213D01*
G01X1087535Y22755D02*
G03X1087339Y22573I0J-197D01*
G01X1088125Y22544D02*
G03X1087928Y22755I-196J14D01*
G01X1087535D02*
X1087928D01*
G01X1095473Y20302D02*
X1093898D01*
G01X1095473Y19590D02*
X1093898D01*
G01X1095473Y19514D02*
X1093898D01*
G01X1095473Y18802D02*
X1093898D01*
G01X1101260Y32598D02*
G03I-4527J0D01*
G01X1094685Y34880D02*
X1095473Y36480D01*
G01X1094685Y34880D02*
Y32598D01*
G01X1091693Y28070D02*
Y37126D01*
G01X1094685Y32598D02*
X1095473Y30575D01*
G01X1091693Y37126D02*
X1101772D01*
G01Y28070D02*
X1091693D01*
G01X1085702Y48511D02*
G03Y49495I0J492D01*
G01X1087670Y47822D02*
G03Y50184I1J1181D01*
G01X1085702Y49495D02*
X1087670Y50184D01*
G01X1085702Y48511D02*
X1087670Y47822D01*
G01X1100748Y232322D02*
Y238353D01*
G01X1098042Y238605D02*
Y232322D01*
G01X1096811D02*
Y240364D01*
G01X1094843Y237348D02*
Y235840D01*
G01X1092382D02*
Y232322D01*
G01X1090906D02*
Y235840D01*
G01X1085000D02*
Y237348D01*
G01X1090906Y235840D02*
X1085000D01*
G01X1094843D02*
X1092382D01*
G01Y232322D02*
X1090906D01*
G01X1098042D02*
X1096811D01*
G01X1101979D02*
X1100748D01*
G01X1098534Y239107D02*
X1098042Y238605D01*
G01Y239610D02*
X1098534Y240113D01*
G01X1086723Y237348D02*
X1090906Y242123D01*
G01X1085000Y237348D02*
X1090906Y244133D01*
G01X1098042Y240364D02*
Y239610D01*
G01X1092382Y244133D02*
Y237348D01*
G01X1090906Y242123D02*
Y237348D01*
G01X1100748Y238353D02*
X1100502Y238856D01*
G01X1099272Y239359D02*
X1098534Y239107D01*
G01Y240113D02*
X1099272Y240364D01*
G01X1100994Y240113D02*
X1101733Y239359D01*
G01X1100502Y238856D02*
X1100256Y239107D01*
G01D02*
X1099764Y239359D01*
G01X1100256Y240364D02*
X1100994Y240113D01*
G01X1090906Y244133D02*
X1092382D01*
G01X1096811Y240364D02*
X1098042D01*
G01X1099272D02*
X1100256D01*
G01X1099764Y239359D02*
X1099272D01*
G01X1092382Y237348D02*
X1094843D01*
G01X1090906D02*
X1086723D01*
G01X1095719Y348444D02*
X1096211Y349449D01*
G01X1097687D02*
X1097441Y348444D01*
G01X1089075Y349952D02*
X1089321Y350957D01*
G01X1100886Y348947D02*
Y348193D01*
G01Y347187D02*
Y340905D01*
G01X1099656D02*
Y348947D01*
G01X1097687Y342161D02*
Y340905D01*
G01Y349952D02*
Y349449D01*
G01X1096211D02*
Y349952D01*
G01X1088829Y340905D02*
Y342161D01*
G01X1086861D02*
Y340905D01*
G01X1085630D02*
Y342161D01*
G01X1097441Y350957D02*
X1097687Y349952D01*
G01X1096949Y347690D02*
X1090798Y342161D01*
G01X1088829D02*
X1095719Y348444D01*
G01X1101378Y347690D02*
X1100886Y347187D01*
G01Y348193D02*
X1101378Y348695D01*
G01X1089321Y350957D02*
X1090305Y351962D01*
G01X1097441Y348444D02*
X1096949Y347690D01*
G01X1090798Y350706D02*
X1090305Y349952D01*
G01X1096211D02*
X1095719Y350706D01*
G01X1091536Y351208D02*
X1090798Y350706D01*
G01X1096457Y351962D02*
X1097441Y350957D01*
G01X1095719Y350706D02*
X1094981Y351208D01*
G01D02*
X1093750Y351460D01*
G01D02*
X1092766D01*
G01X1090305Y349952D02*
X1089075D01*
G01X1099656Y348947D02*
X1100886D01*
G01X1090798Y342161D02*
X1097687D01*
G01X1085630D02*
X1086861D01*
G01Y340905D02*
X1085630D01*
G01X1097687D02*
X1088829D01*
G01X1100886D02*
X1099656D01*
G01X1092766Y351460D02*
X1091536Y351208D01*
G01X1090305Y351962D02*
X1091290Y352465D01*
G01X1095473D02*
X1096457Y351962D01*
G01X1093996Y352716D02*
X1095473Y352465D01*
G01X1093012Y352716D02*
X1093996D01*
G01X1091290Y352465D02*
X1093012Y352716D01*
G01X1091536Y654055D02*
Y630433D01*
G01X1088583D02*
Y641490D01*
G01X1091536Y630433D02*
X1088583D01*
G01X1095473Y644505D02*
Y646516D01*
G01Y638474D02*
Y640485D01*
G01X1088583Y644505D02*
Y654055D01*
G01X1095473Y646516D02*
X1103347D01*
G01Y644505D02*
X1095473D01*
G01Y640485D02*
X1103347D01*
G01Y638474D02*
X1095473D01*
G01X1088583Y654055D02*
X1091536D01*
G01X1095789Y996063D02*
G03Y988189I0J-3937D01*
G01Y996063D02*
G03Y988189I0J-3937D01*
G01X1325399Y996063D02*
X1095789D01*
G01X1325399D02*
X1095789D01*
G01X1108208Y-7874D02*
G03X1120020Y3938I1J11811D01*
G01X1108208Y-7874D02*
G03X1120020Y3938I1J11811D01*
G01X1112146Y3937D02*
Y210629D01*
G01X1108209Y0D02*
G03X1112146Y3937I0J3937D01*
G01X1108209Y0D02*
G03X1112146Y3937I0J3937D01*
G01Y210629D02*
Y3937D01*
G01X1101772Y37126D02*
Y28070D01*
G01X1120020Y99950D02*
G03X1112146I-3937J0D01*
G01X1120020D02*
G03X1112146I-3937J0D01*
G01Y125147D02*
G03X1120020I3937J0D01*
G01X1112146D02*
G03X1120020I3937J0D01*
G01X1116083Y214566D02*
X1194824D01*
G01X1116083D02*
G03X1112146Y210629I0J-3937D01*
G01X1116083Y214566D02*
G03X1112146Y210629I0J-3937D01*
G01X1194823Y214566D02*
X1116083D01*
G01X1116988Y238353D02*
Y232322D01*
G01X1115758D02*
Y238353D01*
G01X1113051D02*
Y232322D01*
G01X1111821D02*
Y238353D01*
G01X1109114Y238605D02*
Y232322D01*
G01X1107884D02*
Y240364D01*
G01X1105916Y238353D02*
Y232322D01*
G01X1104685D02*
Y238353D01*
G01X1101979D02*
Y232322D01*
G01X1105916D02*
X1104685D01*
G01X1109114D02*
X1107884D01*
G01X1113051D02*
X1111821D01*
G01X1116988D02*
X1115758D01*
G01X1113298Y238856D02*
X1113051Y238353D01*
G01X1102225Y238856D02*
X1101979Y238353D01*
G01X1113544Y239107D02*
X1113298Y238856D01*
G01X1112805Y239359D02*
X1113544Y240113D01*
G01X1109607Y239107D02*
X1109114Y238605D01*
G01Y239610D02*
X1109607Y240113D01*
G01X1102471Y239107D02*
X1102225Y238856D01*
G01X1101733Y239359D02*
X1102471Y240113D01*
G01X1109114Y240364D02*
Y239610D01*
G01X1116496D02*
X1116988Y238353D01*
G01X1114036Y239359D02*
X1113544Y239107D01*
G01X1102963Y239359D02*
X1102471Y239107D01*
G01X1105424Y239610D02*
X1105916Y238353D01*
G01X1115758D02*
X1115512Y238856D01*
G01X1111821Y238353D02*
X1111575Y238856D01*
G01X1104685Y238353D02*
X1104439Y238856D01*
G01X1113544Y240113D02*
X1114282Y240364D01*
G01X1110345Y239359D02*
X1109607Y239107D01*
G01Y240113D02*
X1110345Y240364D01*
G01X1102471Y240113D02*
X1103209Y240364D01*
G01X1116004Y240113D02*
X1116496Y239610D01*
G01X1115512Y238856D02*
X1115266Y239107D01*
G01X1112067Y240113D02*
X1112805Y239359D01*
G01X1111575Y238856D02*
X1111329Y239107D01*
G01X1104931Y240113D02*
X1105424Y239610D01*
G01X1104439Y238856D02*
X1104193Y239107D01*
G01X1115266D02*
X1114774Y239359D01*
G01X1111329Y239107D02*
X1110837Y239359D01*
G01X1104193Y239107D02*
X1103701Y239359D01*
G01X1115266Y240364D02*
X1116004Y240113D01*
G01X1111329Y240364D02*
X1112067Y240113D01*
G01X1104193Y240364D02*
X1104931Y240113D01*
G01X1110345Y240364D02*
X1111329D01*
G01X1114282D02*
X1115266D01*
G01X1107884D02*
X1109114D01*
G01X1103209D02*
X1104193D01*
G01X1103701Y239359D02*
X1102963D01*
G01X1114774D02*
X1114036D01*
G01X1110837D02*
X1110345D01*
G01X1116142Y347439D02*
X1115896Y346936D01*
G01X1105069Y347439D02*
X1104823Y346936D01*
G01X1115896D02*
Y340905D01*
G01X1114666D02*
Y346936D01*
G01X1111959Y348947D02*
Y348193D01*
G01Y347187D02*
Y340905D01*
G01X1110729D02*
Y348947D01*
G01X1108760Y346936D02*
Y340905D01*
G01X1107530D02*
Y346936D01*
G01X1104823D02*
Y340905D01*
G01X1103593D02*
Y346936D01*
G01X1108268Y348193D02*
X1108760Y346936D01*
G01X1114666D02*
X1114420Y347439D01*
G01X1107530Y346936D02*
X1107284Y347439D01*
G01X1103593Y346936D02*
X1103347Y347439D01*
G01X1116388Y347690D02*
X1116142Y347439D01*
G01X1115650Y347941D02*
X1116388Y348695D01*
G01X1112451Y347690D02*
X1111959Y347187D01*
G01Y348193D02*
X1112451Y348695D01*
G01X1105315Y347690D02*
X1105069Y347439D01*
G01X1104577Y347941D02*
X1105315Y348695D01*
G01X1116880Y347941D02*
X1116388Y347690D01*
G01X1114912Y348695D02*
X1115650Y347941D01*
G01X1114420Y347439D02*
X1114174Y347690D01*
G01X1107776Y348695D02*
X1108268Y348193D01*
G01X1107284Y347439D02*
X1107038Y347690D01*
G01X1103839Y348695D02*
X1104577Y347941D01*
G01X1103347Y347439D02*
X1103101Y347690D01*
G01X1116388Y348695D02*
X1117126Y348947D01*
G01X1113189Y347941D02*
X1112451Y347690D01*
G01Y348695D02*
X1113189Y348947D01*
G01X1105315Y348695D02*
X1106053Y348947D01*
G01X1102116Y347941D02*
X1101378Y347690D01*
G01Y348695D02*
X1102116Y348947D01*
G01X1105807Y347941D02*
X1105315Y347690D01*
G01X1118111D02*
X1117618Y347941D01*
G01X1114174Y347690D02*
X1113681Y347941D01*
G01X1107038Y347690D02*
X1106546Y347941D01*
G01X1103101Y347690D02*
X1102609Y347941D01*
G01X1114174Y348947D02*
X1114912Y348695D01*
G01X1107038Y348947D02*
X1107776Y348695D01*
G01X1103101Y348947D02*
X1103839Y348695D01*
G01X1117126Y348947D02*
X1118111D01*
G01X1110729D02*
X1111959D01*
G01X1113189D02*
X1114174D01*
G01X1106053D02*
X1107038D01*
G01X1102116D02*
X1103101D01*
G01X1102609Y347941D02*
X1102116D01*
G01X1106546D02*
X1105807D01*
G01X1113681D02*
X1113189D01*
G01X1117618D02*
X1116880D01*
G01X1104823Y340905D02*
X1103593D01*
G01X1108760D02*
X1107530D01*
G01X1111959D02*
X1110729D01*
G01X1115896D02*
X1114666D01*
G01X1107284Y630433D02*
Y632946D01*
G01X1125000Y630433D02*
X1107284D01*
G01X1103347Y640485D02*
Y638474D01*
G01Y646516D02*
Y644505D01*
G01X1111221Y632946D02*
X1125000D01*
G01X1123524Y644003D02*
X1111221Y632946D01*
G01X1107284D02*
X1121063Y645511D01*
G01X1107776Y648526D02*
X1108268Y650537D01*
G01X1119587Y651039D02*
X1117126Y651542D01*
G01X1117618Y654055D02*
X1120571Y653552D01*
G01X1115650Y654055D02*
X1117618D01*
G01X1117126Y651542D02*
X1115158D01*
G01X1110237Y648526D02*
X1107776D01*
G01X1111221Y650034D02*
X1110237Y648526D01*
G01X1112205Y653552D02*
X1115650Y654055D01*
G01X1115158Y651542D02*
X1112697Y651039D01*
G01X1108268Y650537D02*
X1110237Y652547D01*
G01X1112697Y651039D02*
X1111221Y650034D01*
G01X1110237Y652547D02*
X1112205Y653552D01*
G01X1120020Y99950D02*
Y3938D01*
G01Y99950D02*
Y3938D01*
G01Y125147D02*
Y206693D01*
G01Y125147D02*
Y206693D01*
G01X1120021D02*
X1190887D01*
G01X1120021D02*
X1190887D01*
G01X1119833Y346936D02*
Y340905D01*
G01X1118603D02*
Y346936D01*
G01X1119341Y348193D02*
X1119833Y346936D01*
G01X1118603D02*
X1118357Y347439D01*
G01X1118849Y348695D02*
X1119341Y348193D01*
G01X1118357Y347439D02*
X1118111Y347690D01*
G01Y348947D02*
X1118849Y348695D01*
G01X1119833Y340905D02*
X1118603D01*
G01X1131398Y632946D02*
Y630433D01*
G01X1128937D02*
Y632946D01*
G01X1125000D02*
Y630433D01*
G01X1131398D02*
X1128937D01*
G01X1125000Y647521D02*
X1124508Y645511D01*
G01X1121063D02*
X1122048Y647521D01*
G01X1128937Y632946D02*
X1131398D01*
G01X1124508Y645511D02*
X1123524Y644003D01*
G01X1124508Y650537D02*
X1125000Y648526D01*
G01X1122048D02*
X1121063Y650034D01*
G01X1122540Y652547D02*
X1124508Y650537D01*
G01X1121063Y650034D02*
X1119587Y651039D01*
G01X1120571Y653552D02*
X1122540Y652547D01*
G01X1125000Y648526D02*
Y647521D01*
G01X1122048D02*
Y648526D01*
G01X1148130Y630433D02*
Y650034D01*
G01X1141240Y654055D02*
Y630433D01*
G01X1138288D02*
Y650034D01*
G01X1141240Y630433D02*
X1138288D01*
G01X1151083D02*
X1148130D01*
G01X1145177Y646516D02*
Y650537D01*
G01X1135335Y646516D02*
Y650537D01*
G01X1148130Y650034D02*
X1145177Y646516D01*
G01X1138288Y650034D02*
X1135335Y646516D01*
G01X1148130Y654055D02*
X1151083D01*
G01X1138288D02*
X1141240D01*
G01X1145177Y650537D02*
X1148130Y654055D01*
G01X1135335Y650537D02*
X1138288Y654055D01*
G01X1161386Y128841D02*
G03X1152804I-4291J0D01*
G01D02*
G03X1161386I4291J0D01*
G01X1165355Y642495D02*
Y630433D01*
G01X1162894D02*
Y642495D01*
G01X1157481Y642998D02*
Y630433D01*
G01X1155020D02*
Y646516D01*
G01X1151083Y654055D02*
Y630433D01*
G01X1157481D02*
X1155020D01*
G01X1165355D02*
X1162894D01*
G01Y642495D02*
X1162402Y643500D01*
G01X1163386Y646013D02*
X1164863Y644505D01*
G01X1162402Y643500D02*
X1161910Y644003D01*
G01X1157481Y646516D02*
Y645008D01*
G01X1161910Y644003D02*
X1160925Y644505D01*
G01X1161910Y646516D02*
X1163386Y646013D01*
G01X1165847Y643500D02*
X1165355Y642495D01*
G01X1159941Y646516D02*
X1161910D01*
G01X1155020D02*
X1157481D01*
G01X1160925Y644505D02*
X1159941D01*
G01X1166339Y644003D02*
X1165847Y643500D01*
G01X1164863Y644505D02*
X1166339Y646013D01*
G01X1158465Y644003D02*
X1157481Y642998D01*
G01Y645008D02*
X1158465Y646013D01*
G01X1167323Y644505D02*
X1166339Y644003D01*
G01Y646013D02*
X1167815Y646516D01*
G01X1159941Y644505D02*
X1158465Y644003D01*
G01Y646013D02*
X1159941Y646516D01*
G01X1179626Y642998D02*
Y630433D01*
G01X1177166D02*
Y646516D01*
G01X1173229Y642495D02*
Y630433D01*
G01X1170768D02*
Y642495D01*
G01X1173229Y630433D02*
X1170768D01*
G01X1179626D02*
X1177166D01*
G01X1172244Y645008D02*
X1173229Y642495D01*
G01X1170768D02*
X1170276Y643500D01*
G01X1171260Y646013D02*
X1172244Y645008D01*
G01X1170276Y643500D02*
X1169784Y644003D01*
G01X1179626Y646516D02*
Y645008D01*
G01X1184055Y644003D02*
X1183071Y644505D01*
G01X1169784Y644003D02*
X1168800Y644505D01*
G01X1169784Y646516D02*
X1171260Y646013D01*
G01X1182087Y646516D02*
X1184055D01*
G01X1177166D02*
X1179626D01*
G01X1167815D02*
X1169784D01*
G01X1168800Y644505D02*
X1167323D01*
G01X1183071D02*
X1182087D01*
G01X1180611Y644003D02*
X1179626Y642998D01*
G01Y645008D02*
X1180611Y646013D01*
G01X1182087Y644505D02*
X1180611Y644003D01*
G01Y646013D02*
X1182087Y646516D01*
G01X1198760Y3937D02*
G03X1210571Y-7874I11811J0D01*
G01X1198760Y3937D02*
G03X1210571Y-7874I11811J0D01*
G01X1198761Y97100D02*
X1198760Y3937D01*
G01X1198761Y97100D02*
X1198760Y3937D01*
G01X1206635Y97100D02*
G03X1198761I-3937J0D01*
G01X1206635D02*
G03X1198761I-3937J0D01*
G01Y122297D02*
G03X1206635I3937J0D01*
G01X1198761D02*
G03X1206635I3937J0D01*
G01X1198761D02*
Y168002D01*
G01Y122297D02*
Y168002D01*
G01X1190887Y179134D02*
G03X1198761Y167998I11811J0D01*
G01X1190887Y179134D02*
G03X1198761Y167998I11811J0D01*
G01X1190887Y206693D02*
Y179134D01*
G01Y206693D02*
Y179134D01*
G01X1198760Y179133D02*
G03X1202697Y175196I3937J0D01*
G01X1198760Y210629D02*
Y179133D01*
G01D02*
G03X1202697Y175196I3937J0D01*
G01X1198760Y179133D02*
Y210629D01*
G01D02*
G03X1194824Y214566I-3937J0D01*
G01X1198760Y210629D02*
G03X1194823Y214566I-3937J0D01*
G01X1195374Y642495D02*
Y630433D01*
G01X1192914D02*
Y642495D01*
G01X1187500D02*
Y630433D01*
G01X1185040D02*
Y642495D01*
G01X1187500Y630433D02*
X1185040D01*
G01X1195374D02*
X1192914D01*
G01X1194390Y645008D02*
X1195374Y642495D01*
G01X1192914D02*
X1192422Y643500D01*
G01X1185040Y642495D02*
X1184548Y643500D01*
G01X1193406Y646013D02*
X1194390Y645008D01*
G01X1192422Y643500D02*
X1191929Y644003D01*
G01X1185532Y646013D02*
X1187008Y644505D01*
G01X1184548Y643500D02*
X1184055Y644003D01*
G01X1191929D02*
X1190945Y644505D01*
G01X1191929Y646516D02*
X1193406Y646013D01*
G01X1184055Y646516D02*
X1185532Y646013D01*
G01X1187992Y643500D02*
X1187500Y642495D01*
G01X1189961Y646516D02*
X1191929D01*
G01X1190945Y644505D02*
X1189469D01*
G01X1188485Y644003D02*
X1187992Y643500D01*
G01X1187008Y644505D02*
X1188485Y646013D01*
G01X1189469Y644505D02*
X1188485Y644003D01*
G01Y646013D02*
X1189961Y646516D01*
G01X1210552Y-7874D02*
X1210572D01*
G01D02*
G03Y0I0J3937D01*
G01X1210552Y-7874D02*
X1210572D01*
G01D02*
G03Y0I0J3937D01*
G01X1210571D02*
X1396063D01*
G01X1206634Y3937D02*
G03X1210571Y0I3937J0D01*
G01X1206634Y171259D02*
Y3937D01*
G01D02*
G03X1210571Y0I3937J0D01*
G01X1206634Y171259D02*
Y3937D01*
G01X1210571Y0D02*
X1396063D01*
G01X1237664Y169291D02*
G03Y141732I-10498J-13780D01*
G01X1206634Y171259D02*
G03X1202697Y175196I-3937J0D01*
G01X1206634Y171259D02*
G03X1202697Y175196I-3937J0D01*
G01X1212205Y179527D02*
G03X1214174Y177559I1968J0D01*
G01X1212205Y179527D02*
Y186909D01*
G01X1217520D02*
X1212205D01*
G01X1235827Y185334D02*
X1212205D01*
G01X1220079Y177559D02*
X1214174D01*
G01X1213189Y189960D02*
Y191141D01*
G01Y194291D02*
Y193110D01*
G01Y197440D02*
Y196259D01*
G01Y200590D02*
Y199409D01*
G01Y203740D02*
Y202559D01*
G01X1221063Y203740D02*
X1213189D01*
G01Y202559D02*
X1221063D01*
G01Y200590D02*
X1213189D01*
G01Y199409D02*
X1221063D01*
G01Y197440D02*
X1213189D01*
G01Y196259D02*
X1221063D01*
G01Y194291D02*
X1213189D01*
G01Y193110D02*
X1221063D01*
G01Y191141D02*
X1213189D01*
G01X1221063Y189960D02*
X1213189D01*
G01Y206889D02*
Y205708D01*
G01Y210039D02*
Y208858D01*
G01Y213189D02*
Y212007D01*
G01Y216338D02*
Y215157D01*
G01Y219488D02*
Y218307D01*
G01X1221063Y219488D02*
X1213189D01*
G01Y218307D02*
X1221063D01*
G01Y216338D02*
X1213189D01*
G01Y215157D02*
X1221063D01*
G01Y213189D02*
X1213189D01*
G01Y212007D02*
X1221063D01*
G01Y210039D02*
X1213189D01*
G01Y208858D02*
X1221063D01*
G01Y206889D02*
X1213189D01*
G01Y205708D02*
X1221063D01*
G01X1213189Y222637D02*
Y221456D01*
G01Y225787D02*
Y224606D01*
G01Y228937D02*
Y227755D01*
G01Y232086D02*
Y230905D01*
G01Y235236D02*
Y234055D01*
G01X1221063Y235236D02*
X1213189D01*
G01Y234055D02*
X1221063D01*
G01Y232086D02*
X1213189D01*
G01Y230905D02*
X1221063D01*
G01Y228937D02*
X1213189D01*
G01Y227755D02*
X1221063D01*
G01Y225787D02*
X1213189D01*
G01Y224606D02*
X1221063D01*
G01Y222637D02*
X1213189D01*
G01Y221456D02*
X1221063D01*
G01X1213189Y238385D02*
Y237204D01*
G01Y241535D02*
Y240354D01*
G01Y244685D02*
Y243503D01*
G01Y247834D02*
Y246653D01*
G01Y250984D02*
Y249803D01*
G01Y254133D02*
Y252952D01*
G01D02*
X1221063D01*
G01Y250984D02*
X1213189D01*
G01Y249803D02*
X1221063D01*
G01Y247834D02*
X1213189D01*
G01Y246653D02*
X1221063D01*
G01Y244685D02*
X1213189D01*
G01Y243503D02*
X1221063D01*
G01Y241535D02*
X1213189D01*
G01Y240354D02*
X1221063D01*
G01Y238385D02*
X1213189D01*
G01Y237204D02*
X1221063D01*
G01X1213189Y257283D02*
Y256102D01*
G01Y260433D02*
Y259252D01*
G01Y263582D02*
Y262401D01*
G01Y266732D02*
Y265551D01*
G01Y269881D02*
Y268700D01*
G01D02*
X1221063D01*
G01Y266732D02*
X1213189D01*
G01Y265551D02*
X1221063D01*
G01Y263582D02*
X1213189D01*
G01Y262401D02*
X1221063D01*
G01Y260433D02*
X1213189D01*
G01Y259252D02*
X1221063D01*
G01Y257283D02*
X1213189D01*
G01Y256102D02*
X1221063D01*
G01Y254133D02*
X1213189D01*
G01Y273031D02*
Y271850D01*
G01Y276181D02*
Y275000D01*
G01Y279330D02*
Y278149D01*
G01Y282480D02*
Y281299D01*
G01Y285629D02*
Y284448D01*
G01X1221063Y285629D02*
X1213189D01*
G01Y284448D02*
X1221063D01*
G01Y282480D02*
X1213189D01*
G01Y281299D02*
X1221063D01*
G01Y279330D02*
X1213189D01*
G01Y278149D02*
X1221063D01*
G01Y276181D02*
X1213189D01*
G01Y275000D02*
X1221063D01*
G01Y273031D02*
X1213189D01*
G01Y271850D02*
X1221063D01*
G01Y269881D02*
X1213189D01*
G01Y288779D02*
Y287598D01*
G01Y291929D02*
Y290748D01*
G01Y295078D02*
Y293897D01*
G01Y298228D02*
Y297047D01*
G01Y301377D02*
Y300196D01*
G01X1221063Y301377D02*
X1213189D01*
G01Y300196D02*
X1221063D01*
G01Y298228D02*
X1213189D01*
G01Y297047D02*
X1221063D01*
G01Y295078D02*
X1213189D01*
G01Y293897D02*
X1221063D01*
G01Y291929D02*
X1213189D01*
G01Y290748D02*
X1221063D01*
G01Y288779D02*
X1213189D01*
G01Y287598D02*
X1221063D01*
G01X1213189Y304527D02*
Y303346D01*
G01Y307677D02*
Y306496D01*
G01Y310826D02*
Y309645D01*
G01Y313976D02*
Y312795D01*
G01Y317126D02*
Y315944D01*
G01Y320275D02*
Y319094D01*
G01D02*
X1221063D01*
G01Y317126D02*
X1213189D01*
G01Y315944D02*
X1221063D01*
G01Y313976D02*
X1213189D01*
G01Y312795D02*
X1221063D01*
G01Y310826D02*
X1213189D01*
G01Y309645D02*
X1221063D01*
G01Y307677D02*
X1213189D01*
G01Y306496D02*
X1221063D01*
G01Y304527D02*
X1213189D01*
G01Y303346D02*
X1221063D01*
G01X1213189Y323425D02*
Y322244D01*
G01Y326574D02*
Y325393D01*
G01Y329724D02*
Y328543D01*
G01Y332874D02*
Y331692D01*
G01Y336023D02*
Y334842D01*
G01D02*
X1221063D01*
G01Y332874D02*
X1213189D01*
G01Y331692D02*
X1221063D01*
G01Y329724D02*
X1213189D01*
G01Y328543D02*
X1221063D01*
G01Y326574D02*
X1213189D01*
G01Y325393D02*
X1221063D01*
G01Y323425D02*
X1213189D01*
G01Y322244D02*
X1221063D01*
G01Y320275D02*
X1213189D01*
G01Y339173D02*
Y337992D01*
G01Y342322D02*
Y341141D01*
G01Y345472D02*
Y344291D01*
G01Y348622D02*
Y347440D01*
G01Y351771D02*
Y350590D01*
G01X1221063Y351771D02*
X1213189D01*
G01Y350590D02*
X1221063D01*
G01Y348622D02*
X1213189D01*
G01Y347440D02*
X1221063D01*
G01Y345472D02*
X1213189D01*
G01Y344291D02*
X1221063D01*
G01Y342322D02*
X1213189D01*
G01Y341141D02*
X1221063D01*
G01Y339173D02*
X1213189D01*
G01Y337992D02*
X1221063D01*
G01Y336023D02*
X1213189D01*
G01Y354921D02*
Y353740D01*
G01Y358070D02*
Y356889D01*
G01Y361220D02*
Y360039D01*
G01Y364370D02*
Y363189D01*
G01Y367519D02*
Y366338D01*
G01X1221063Y367519D02*
X1213189D01*
G01Y366338D02*
X1221063D01*
G01Y364370D02*
X1213189D01*
G01Y363189D02*
X1221063D01*
G01Y361220D02*
X1213189D01*
G01Y360039D02*
X1221063D01*
G01Y358070D02*
X1213189D01*
G01Y356889D02*
X1221063D01*
G01Y354921D02*
X1213189D01*
G01Y353740D02*
X1221063D01*
G01X1213189Y375787D02*
Y376968D01*
G01Y370669D02*
Y369488D01*
G01Y373818D02*
Y372637D01*
G01X1212205Y380019D02*
Y387401D01*
G01X1235827Y381594D02*
X1212205D01*
G01X1217520Y380019D02*
X1212205D01*
G01X1221063Y376968D02*
X1213189D01*
G01Y375787D02*
X1221063D01*
G01Y373818D02*
X1213189D01*
G01Y372637D02*
X1221063D01*
G01Y370669D02*
X1213189D01*
G01Y369488D02*
X1221063D01*
G01X1214174Y389370D02*
G03X1212205Y387401I0J-1969D01*
G01X1237664Y425196D02*
G03Y397637I-10498J-13780D01*
G01X1220079Y389370D02*
X1214174D01*
G01X1226320Y-7874D02*
X1380317D01*
G01X1226320Y0D02*
G03Y-7874I0J-3937D01*
G01D02*
X1380317D01*
G01X1226320Y0D02*
G03Y-7874I0J-3937D01*
G01X1230315Y149212D02*
G03Y161811I0J6300D01*
G01X1224016D02*
G03Y149212I0J-6299D01*
G01D02*
X1230315D01*
G01Y161811D02*
X1224016D01*
G01X1221772Y186555D02*
X1220985Y185767D01*
G01X1227048D02*
X1226260Y186555D01*
G01X1229725Y184330D02*
G03X1230512Y185118I0J787D01*
G01X1225394Y183543D02*
G03X1224213Y182370I0J-1181D01*
G01X1229725Y183543D02*
G03X1231300Y185118I0J1575D01*
G01X1225394Y184330D02*
G03X1223425Y182376I0J-1969D01*
G01X1217520Y182381D02*
G03X1218307Y181594I787J0D01*
G01X1222638D02*
G03X1223425Y182376I0J787D01*
G01X1224858Y180708D02*
G03I-842J0D01*
G01X1216733Y182381D02*
G03X1218307Y180807I1575J1D01*
G01X1222638D02*
G03X1224213Y182370I0J1575D01*
G01X1226035Y180708D02*
G03I-2019J0D01*
G01X1226181D02*
G03I-2165J0D01*
G01X1231890Y183070D02*
Y179921D01*
G01X1231300Y381811D02*
Y185118D01*
G01X1230512Y381811D02*
Y185118D01*
G01X1229725Y183543D02*
Y184330D01*
G01X1227953Y178346D02*
Y177559D01*
G01X1227048Y381161D02*
Y185767D01*
G01X1226260Y380374D02*
Y186555D01*
G01X1225394Y183543D02*
Y184330D01*
G01X1222638Y180807D02*
Y181594D01*
G01X1221772Y380374D02*
Y186555D01*
G01X1220985Y185767D02*
Y381161D01*
G01X1220079Y178346D02*
Y177559D01*
G01X1218307Y181594D02*
Y180807D01*
G01X1217520Y182381D02*
Y384547D01*
G01X1216733D02*
Y182381D01*
G01X1235827Y186909D02*
X1230512D01*
G01X1226260Y186555D02*
X1221772D01*
G01X1223425Y182376D02*
X1224213Y182370D01*
G01X1227048Y185767D02*
X1220985D01*
G01X1230512Y185118D02*
X1231300D01*
G01X1229725Y184330D02*
X1225394D01*
G01X1229725Y183543D02*
X1225394D01*
G01X1235040Y183070D02*
X1231890D01*
G01X1216733Y182381D02*
X1217520D01*
G01X1222638Y181594D02*
X1218307D01*
G01X1222638Y180807D02*
X1218307D01*
G01X1235040Y179921D02*
X1231890D01*
G01X1227953Y178346D02*
X1220079D01*
G01X1233859Y177559D02*
X1227953D01*
G01X1226969Y191141D02*
Y189960D01*
G01Y194291D02*
Y193110D01*
G01Y200590D02*
Y199409D01*
G01Y197440D02*
Y196259D01*
G01Y203740D02*
Y202559D01*
G01X1221063D02*
Y203740D01*
G01Y196259D02*
Y197440D01*
G01Y199409D02*
Y200590D01*
G01Y193110D02*
Y194291D01*
G01Y189960D02*
Y191141D01*
G01X1234843Y203740D02*
X1226969D01*
G01Y202559D02*
X1234843D01*
G01Y200590D02*
X1226969D01*
G01Y199409D02*
X1234843D01*
G01Y197440D02*
X1226969D01*
G01Y196259D02*
X1234843D01*
G01Y194291D02*
X1226969D01*
G01Y193110D02*
X1234843D01*
G01Y191141D02*
X1226969D01*
G01Y189960D02*
X1234843D01*
G01X1226969Y210039D02*
Y208858D01*
G01Y206889D02*
Y205708D01*
G01Y213189D02*
Y212007D01*
G01Y219488D02*
Y218307D01*
G01Y216338D02*
Y215157D01*
G01X1221063D02*
Y216338D01*
G01Y218307D02*
Y219488D01*
G01Y212007D02*
Y213189D01*
G01Y205708D02*
Y206889D01*
G01Y208858D02*
Y210039D01*
G01X1234843Y219488D02*
X1226969D01*
G01Y218307D02*
X1234843D01*
G01Y216338D02*
X1226969D01*
G01Y215157D02*
X1234843D01*
G01Y213189D02*
X1226969D01*
G01Y212007D02*
X1234843D01*
G01Y210039D02*
X1226969D01*
G01Y208858D02*
X1234843D01*
G01Y206889D02*
X1226969D01*
G01Y205708D02*
X1234843D01*
G01X1226969Y222637D02*
Y221456D01*
G01Y228937D02*
Y227755D01*
G01Y225787D02*
Y224606D01*
G01Y232086D02*
Y230905D01*
G01Y235236D02*
Y234055D01*
G01X1221063D02*
Y235236D01*
G01Y230905D02*
Y232086D01*
G01Y224606D02*
Y225787D01*
G01Y227755D02*
Y228937D01*
G01Y221456D02*
Y222637D01*
G01X1234843Y235236D02*
X1226969D01*
G01Y234055D02*
X1234843D01*
G01Y232086D02*
X1226969D01*
G01Y230905D02*
X1234843D01*
G01Y228937D02*
X1226969D01*
G01Y227755D02*
X1234843D01*
G01Y225787D02*
X1226969D01*
G01Y224606D02*
X1234843D01*
G01Y222637D02*
X1226969D01*
G01Y221456D02*
X1234843D01*
G01X1226969Y238385D02*
Y237204D01*
G01Y241535D02*
Y240354D01*
G01Y247834D02*
Y246653D01*
G01Y244685D02*
Y243503D01*
G01Y250984D02*
Y249803D01*
G01Y254133D02*
Y252952D01*
G01X1221063D02*
Y254133D01*
G01Y249803D02*
Y250984D01*
G01Y243503D02*
Y244685D01*
G01Y246653D02*
Y247834D01*
G01Y240354D02*
Y241535D01*
G01Y237204D02*
Y238385D01*
G01X1226969Y252952D02*
X1234843D01*
G01Y250984D02*
X1226969D01*
G01X1230512Y250393D02*
X1231300D01*
G01X1217520D02*
X1216733D01*
G01X1226969Y249803D02*
X1234843D01*
G01Y247834D02*
X1226969D01*
G01Y246653D02*
X1234843D01*
G01Y244685D02*
X1226969D01*
G01X1216733Y244094D02*
X1217520D01*
G01X1231300D02*
X1230512D01*
G01X1226969Y243503D02*
X1234843D01*
G01Y241535D02*
X1226969D01*
G01Y240354D02*
X1234843D01*
G01Y238385D02*
X1226969D01*
G01Y237204D02*
X1234843D01*
G01X1226969Y257283D02*
Y256102D01*
G01Y260433D02*
Y259252D01*
G01Y266732D02*
Y265551D01*
G01Y263582D02*
Y262401D01*
G01Y269881D02*
Y268700D01*
G01X1221063D02*
Y269881D01*
G01Y262401D02*
Y263582D01*
G01Y265551D02*
Y266732D01*
G01Y259252D02*
Y260433D01*
G01Y256102D02*
Y257283D01*
G01X1226969Y268700D02*
X1234843D01*
G01Y266732D02*
X1226969D01*
G01X1230512Y266141D02*
X1231300D01*
G01X1217520D02*
X1216733D01*
G01X1226969Y265551D02*
X1234843D01*
G01Y263582D02*
X1226969D01*
G01Y262401D02*
X1234843D01*
G01Y260433D02*
X1226969D01*
G01X1216733Y259842D02*
X1217520D01*
G01X1231300D02*
X1230512D01*
G01X1226969Y259252D02*
X1234843D01*
G01Y257283D02*
X1226969D01*
G01Y256102D02*
X1234843D01*
G01Y254133D02*
X1226969D01*
G01Y276181D02*
Y275000D01*
G01Y273031D02*
Y271850D01*
G01Y279330D02*
Y278149D01*
G01Y282480D02*
Y281299D01*
G01Y285629D02*
Y284448D01*
G01X1221063D02*
Y285629D01*
G01Y281299D02*
Y282480D01*
G01Y278149D02*
Y279330D01*
G01Y271850D02*
Y273031D01*
G01Y275000D02*
Y276181D01*
G01X1217559Y284137D02*
Y279498D01*
G01Y278547D02*
Y277833D01*
G01Y289370D02*
Y285088D01*
G01X1234843Y285629D02*
X1226969D01*
G01X1217520Y285564D02*
X1217559D01*
G01X1217520Y285088D02*
X1217559D01*
G01X1226969Y284448D02*
X1234843D01*
G01X1217520Y284137D02*
X1217559D01*
G01X1217520Y284018D02*
X1217559D01*
G01X1217520Y283780D02*
X1217559D01*
G01X1217520Y283423D02*
X1217559D01*
G01X1217520Y283304D02*
X1217559D01*
G01X1217520Y283066D02*
X1217559D01*
G01X1217520Y282828D02*
X1217559D01*
G01X1217520Y282709D02*
X1217559D01*
G01X1234843Y282480D02*
X1226969D01*
G01X1217559Y282234D02*
X1217520D01*
G01X1226969Y281299D02*
X1234843D01*
G01X1217520Y281163D02*
X1217559D01*
G01X1217520Y280688D02*
X1217559D01*
G01X1217520Y280569D02*
X1217559D01*
G01X1217520Y280331D02*
X1217559D01*
G01X1217520Y280212D02*
X1217559D01*
G01X1217520Y280093D02*
X1217559D01*
G01X1217520Y279617D02*
X1217559D01*
G01X1217520Y279498D02*
X1217559D01*
G01X1234843Y279330D02*
X1226969D01*
G01X1217559Y278547D02*
X1217520D01*
G01X1226969Y278149D02*
X1234843D01*
G01X1217520Y277833D02*
X1217559D01*
G01X1234843Y276181D02*
X1226969D01*
G01Y275000D02*
X1234843D01*
G01Y273031D02*
X1226969D01*
G01Y271850D02*
X1234843D01*
G01Y269881D02*
X1226969D01*
G01Y288779D02*
Y287598D01*
G01Y291929D02*
Y290748D01*
G01Y298228D02*
Y297047D01*
G01Y295078D02*
Y293897D01*
G01Y301377D02*
Y300196D01*
G01X1221063D02*
Y301377D01*
G01Y293897D02*
Y295078D01*
G01Y297047D02*
Y298228D01*
G01Y290748D02*
Y291929D01*
G01Y287598D02*
Y288779D01*
G01X1234843Y301377D02*
X1226969D01*
G01X1216733Y300787D02*
X1217520D01*
G01X1231300D02*
X1230512D01*
G01X1226969Y300196D02*
X1234843D01*
G01Y298228D02*
X1226969D01*
G01Y297047D02*
X1234843D01*
G01Y295078D02*
X1226969D01*
G01Y293897D02*
X1234843D01*
G01Y291929D02*
X1226969D01*
G01Y290748D02*
X1234843D01*
G01X1217559Y289370D02*
X1217520D01*
G01X1234843Y288779D02*
X1226969D01*
G01X1217559Y288656D02*
X1217520D01*
G01X1226969Y287598D02*
X1234843D01*
G01X1226969Y307677D02*
Y306496D01*
G01Y304527D02*
Y303346D01*
G01Y310826D02*
Y309645D01*
G01Y317126D02*
Y315944D01*
G01Y313976D02*
Y312795D01*
G01Y320275D02*
Y319094D01*
G01X1221063D02*
Y320275D01*
G01Y312795D02*
Y313976D01*
G01Y315944D02*
Y317126D01*
G01Y309645D02*
Y310826D01*
G01Y303346D02*
Y304527D01*
G01Y306496D02*
Y307677D01*
G01X1226969Y319094D02*
X1234843D01*
G01Y317126D02*
X1226969D01*
G01X1216733Y316535D02*
X1217520D01*
G01X1231300D02*
X1230512D01*
G01X1226969Y315944D02*
X1234843D01*
G01Y313976D02*
X1226969D01*
G01Y312795D02*
X1234843D01*
G01Y310826D02*
X1226969D01*
G01Y309645D02*
X1234843D01*
G01Y307677D02*
X1226969D01*
G01X1217520Y307086D02*
X1216733D01*
G01X1231300D02*
X1230512D01*
G01X1226969Y306496D02*
X1234843D01*
G01Y304527D02*
X1226969D01*
G01Y303346D02*
X1234843D01*
G01X1226969Y326574D02*
Y325393D01*
G01Y323425D02*
Y322244D01*
G01Y329724D02*
Y328543D01*
G01Y336023D02*
Y334842D01*
G01Y332874D02*
Y331692D01*
G01X1221063D02*
Y332874D01*
G01Y334842D02*
Y336023D01*
G01Y328543D02*
Y329724D01*
G01Y322244D02*
Y323425D01*
G01Y325393D02*
Y326574D01*
G01X1226969Y334842D02*
X1234843D01*
G01Y332874D02*
X1226969D01*
G01Y331692D02*
X1234843D01*
G01Y329724D02*
X1226969D01*
G01Y328543D02*
X1234843D01*
G01Y326574D02*
X1226969D01*
G01Y325393D02*
X1234843D01*
G01Y323425D02*
X1226969D01*
G01X1217520Y322834D02*
X1216733D01*
G01X1231300D02*
X1230512D01*
G01X1226969Y322244D02*
X1234843D01*
G01Y320275D02*
X1226969D01*
G01Y339173D02*
Y337992D01*
G01Y345472D02*
Y344291D01*
G01Y342322D02*
Y341141D01*
G01Y348622D02*
Y347440D01*
G01Y351771D02*
Y350590D01*
G01X1221063D02*
Y351771D01*
G01Y347440D02*
Y348622D01*
G01Y341141D02*
Y342322D01*
G01Y344291D02*
Y345472D01*
G01Y337992D02*
Y339173D01*
G01X1234843Y351771D02*
X1226969D01*
G01Y350590D02*
X1234843D01*
G01Y348622D02*
X1226969D01*
G01Y347440D02*
X1234843D01*
G01Y345472D02*
X1226969D01*
G01Y344291D02*
X1234843D01*
G01Y342322D02*
X1226969D01*
G01Y341141D02*
X1234843D01*
G01Y339173D02*
X1226969D01*
G01Y337992D02*
X1234843D01*
G01Y336023D02*
X1226969D01*
G01Y354921D02*
Y353740D01*
G01Y358070D02*
Y356889D01*
G01Y364370D02*
Y363189D01*
G01Y361220D02*
Y360039D01*
G01Y367519D02*
Y366338D01*
G01X1221063D02*
Y367519D01*
G01Y360039D02*
Y361220D01*
G01Y363189D02*
Y364370D01*
G01Y356889D02*
Y358070D01*
G01Y353740D02*
Y354921D01*
G01X1234843Y367519D02*
X1226969D01*
G01Y366338D02*
X1234843D01*
G01Y364370D02*
X1226969D01*
G01Y363189D02*
X1234843D01*
G01Y361220D02*
X1226969D01*
G01Y360039D02*
X1234843D01*
G01Y358070D02*
X1226969D01*
G01Y356889D02*
X1234843D01*
G01Y354921D02*
X1226969D01*
G01Y353740D02*
X1234843D01*
G01X1220985Y381161D02*
X1221772Y380374D01*
G01X1226260D02*
X1227048Y381161D01*
G01X1230512Y381811D02*
G03X1229725Y382598I-787J0D01*
G01X1218307Y385334D02*
G03X1217520Y384547I0J-787D01*
G01X1223425Y384552D02*
G03X1222638Y385334I-787J-5D01*
G01X1224213Y384558D02*
G03X1225394Y383385I1181J8D01*
G01X1218307Y386122D02*
G03X1216733Y384547I1J-1575D01*
G01X1224213Y384558D02*
G03X1222638Y386122I-1575J-11D01*
G01X1231300Y381811D02*
G03X1229725Y383385I-1575J-1D01*
G01X1223425Y384552D02*
G03X1225394Y382598I1969J15D01*
G01X1225985Y386220D02*
G03I-1969J0D01*
G01X1229725Y382598D02*
Y383385D01*
G01X1226969Y373818D02*
Y372637D01*
G01Y370669D02*
Y369488D01*
G01Y376968D02*
Y375787D01*
G01X1225394Y382598D02*
Y383385D01*
G01X1221063Y375787D02*
Y376968D01*
G01Y369488D02*
Y370669D01*
G01Y372637D02*
Y373818D01*
G01X1217520Y384547D02*
X1216733D01*
G01X1229725Y383385D02*
X1225394D01*
G01Y382598D02*
X1229725D01*
G01X1231300Y381811D02*
X1230512D01*
G01X1220985Y381161D02*
X1227048D01*
G01X1226260Y380374D02*
X1221772D01*
G01X1235827Y380019D02*
X1230512D01*
G01X1234843Y376968D02*
X1226969D01*
G01X1234843Y375787D02*
X1226969D01*
G01X1234843Y373818D02*
X1226969D01*
G01Y372637D02*
X1234843D01*
G01X1224213Y384558D02*
X1223425Y384552D01*
G01X1234843Y370669D02*
X1226969D01*
G01Y369488D02*
X1234843D01*
G01X1225233Y386220D02*
G03I-1217J0D01*
G01X1225394D02*
G03I-1378J0D01*
G01X1227953Y389370D02*
Y388582D01*
G01X1222638Y385334D02*
Y386122D01*
G01X1220079Y389370D02*
Y388582D01*
G01X1218307Y386122D02*
Y385334D01*
G01X1233859Y389370D02*
X1227953D01*
G01Y388582D02*
X1220079D01*
G01X1222638Y386122D02*
X1218307D01*
G01Y385334D02*
X1222638D01*
G01X1224016Y417716D02*
G03Y405118I0J-6299D01*
G01X1230315D02*
G03Y417716I0J6299D01*
G01X1224016Y405118D02*
X1230315D01*
G01Y417716D02*
X1224016D01*
G01X1237664Y141732D02*
X1284646D01*
G01X1237664Y169291D02*
X1284646D01*
G01X1233859Y177559D02*
G03X1235827Y179527I0J1968D01*
G01Y186909D02*
Y179527D01*
G01X1235040Y183070D02*
Y179921D01*
G01X1234252Y182330D02*
Y180511D01*
G01Y182330D02*
X1232677Y181420D01*
G01X1234252Y180511D02*
X1232677Y181420D01*
G01X1238075Y191088D02*
Y190720D01*
G01X1235138D02*
Y191088D01*
G01X1234843Y202559D02*
Y203740D01*
G01Y199409D02*
Y200590D01*
G01Y196259D02*
Y197440D01*
G01Y193110D02*
Y194291D01*
G01Y189960D02*
Y191141D01*
G01X1235637Y190720D02*
X1236075Y190353D01*
G01X1235575D02*
X1235138Y190720D01*
G01Y191088D02*
X1238075D01*
G01Y190720D02*
X1235637D01*
G01X1236075Y190353D02*
X1235575D01*
G01X1234843Y218307D02*
Y219488D01*
G01Y215157D02*
Y216338D01*
G01Y212007D02*
Y213189D01*
G01Y208858D02*
Y210039D01*
G01Y205708D02*
Y206889D01*
G01Y234055D02*
Y235236D01*
G01Y230905D02*
Y232086D01*
G01Y227755D02*
Y228937D01*
G01Y224606D02*
Y225787D01*
G01Y221456D02*
Y222637D01*
G01Y252952D02*
Y254133D01*
G01Y249803D02*
Y250984D01*
G01Y246653D02*
Y247834D01*
G01Y243503D02*
Y244685D01*
G01Y240354D02*
Y241535D01*
G01Y237204D02*
Y238385D01*
G01Y268700D02*
Y269881D01*
G01Y265551D02*
Y266732D01*
G01Y262401D02*
Y263582D01*
G01Y259252D02*
Y260433D01*
G01Y256102D02*
Y257283D01*
G01Y284448D02*
Y285629D01*
G01Y281299D02*
Y282480D01*
G01Y278149D02*
Y279330D01*
G01Y275000D02*
Y276181D01*
G01Y271850D02*
Y273031D01*
G01Y300196D02*
Y301377D01*
G01Y297047D02*
Y298228D01*
G01Y293897D02*
Y295078D01*
G01Y290748D02*
Y291929D01*
G01Y287598D02*
Y288779D01*
G01Y319094D02*
Y320275D01*
G01Y315944D02*
Y317126D01*
G01Y312795D02*
Y313976D01*
G01Y309645D02*
Y310826D01*
G01Y306496D02*
Y307677D01*
G01Y303346D02*
Y304527D01*
G01Y334842D02*
Y336023D01*
G01Y331692D02*
Y332874D01*
G01Y328543D02*
Y329724D01*
G01Y325393D02*
Y326574D01*
G01Y322244D02*
Y323425D01*
G01Y350590D02*
Y351771D01*
G01Y347440D02*
Y348622D01*
G01Y344291D02*
Y345472D01*
G01Y341141D02*
Y342322D01*
G01Y337992D02*
Y339173D01*
G01Y366338D02*
Y367519D01*
G01Y363189D02*
Y364370D01*
G01Y360039D02*
Y361220D01*
G01Y356889D02*
Y358070D01*
G01Y353740D02*
Y354921D01*
G01X1235827Y387401D02*
Y380019D01*
G01X1234843Y375787D02*
Y376968D01*
G01Y372637D02*
Y373818D01*
G01Y369488D02*
Y370669D01*
G01X1235827Y387401D02*
G03X1233859Y389370I-1969J0D01*
G01X1237664Y397637D02*
X1286221D01*
G01X1237664Y425196D02*
X1286221D01*
G01X1251575Y0D02*
Y141732D01*
G01Y169291D02*
Y397637D01*
G01X1254174Y307090D02*
G03X1258111Y303153I3937J0D01*
G01X1260079Y309059D02*
Y305279D01*
G01X1259685Y330118D02*
Y310590D01*
G01X1259292Y313389D02*
Y309452D01*
G01Y309059D02*
Y306066D01*
G01X1258898Y306220D02*
Y341102D01*
G01X1258701Y326011D02*
Y313019D01*
G01X1258111Y319043D02*
Y306066D01*
G01Y319987D02*
Y319043D01*
G01X1257914Y326798D02*
Y312231D01*
G01X1257323Y308665D02*
Y305279D01*
G01X1255748Y308665D02*
Y320673D01*
G01X1254174Y307090D02*
Y390948D01*
G01X1257323Y305279D02*
X1258111Y306066D01*
G01X1260079Y305279D02*
X1259292Y306066D01*
G01X1258111Y319043D02*
X1257914D01*
G01X1258111Y318924D02*
X1257914D01*
G01X1258898Y315066D02*
X1258701D01*
G01X1258111Y314312D02*
X1257914D01*
G01X1258111Y314278D02*
X1257914D01*
G01Y314200D02*
X1258111D01*
G01X1258701Y313413D02*
X1258898D01*
G01X1259292Y313389D02*
X1254174D01*
G01X1258701Y313019D02*
X1258898D01*
G01X1257914Y312231D02*
X1258111D01*
G01X1268951Y310590D02*
X1258111D01*
G01X1258898Y309842D02*
X1258111D01*
G01Y309803D02*
X1258898D01*
G01X1259292Y309452D02*
X1271890D01*
G01X1266533Y309059D02*
X1259292D01*
G01X1255748Y308665D02*
X1258111D01*
G01Y307480D02*
X1258898D01*
G01Y306889D02*
X1258111D01*
G01X1258898Y306810D02*
X1258111D01*
G01X1258898Y306692D02*
X1258111D01*
G01Y306456D02*
X1258898D01*
G01Y306299D02*
X1258111D01*
G01X1258898Y306220D02*
X1258111D01*
G01X1259292Y306066D02*
X1258111D01*
G01X1260079Y305279D02*
X1257323D01*
G01X1273071Y303153D02*
X1258111D01*
G01X1260486Y328346D02*
G03X1260879Y328903I-197J556D01*
G01X1259698Y328740D02*
G03X1260092Y329296I-196J557D01*
G01Y329364D02*
G03X1259698Y329921I-591J0D01*
G01X1260879Y329758D02*
G03X1260486Y330315I-591J0D01*
G01X1258898Y328346D02*
G03X1259292Y328903I-197J557D01*
G01X1258111Y328740D02*
G03X1258504Y329296I-197J556D01*
G01X1259292Y329758D02*
G03X1258898Y330315I-591J0D01*
G01X1258504Y329364D02*
G03X1258111Y329921I-591J0D01*
G01X1260473Y329330D02*
G03I-1969J0D01*
G01X1261300Y328897D02*
Y329645D01*
G01X1260879Y328903D02*
Y329758D01*
G01X1260486Y328346D02*
Y327952D01*
G01Y330708D02*
Y330315D01*
G01X1260381Y328903D02*
Y329758D01*
G01X1260092Y329364D02*
Y329296D01*
G01X1260059Y328346D02*
Y327952D01*
G01Y330708D02*
Y330315D01*
G01X1259736Y329296D02*
Y329364D01*
G01X1259704Y329758D02*
Y328903D01*
G01X1259698Y330708D02*
Y329921D01*
G01Y328740D02*
Y327952D01*
G01X1259627Y329758D02*
Y328903D01*
G01X1259479Y327952D02*
Y328346D01*
G01Y330315D02*
Y330708D01*
G01X1259414D02*
Y329921D01*
G01Y328740D02*
Y327952D01*
G01X1259401D02*
Y328346D01*
G01Y330315D02*
Y330708D01*
G01X1259292Y328903D02*
Y329758D01*
G01X1259253Y329364D02*
Y329296D01*
G01X1259176Y329364D02*
Y329296D01*
G01X1259155Y327952D02*
Y330708D01*
G01X1259027Y329921D02*
Y330708D01*
G01Y327952D02*
Y328740D01*
G01X1258950Y329921D02*
Y330708D01*
G01Y327952D02*
Y328740D01*
G01X1258942Y328166D02*
Y330495D01*
G01X1258510Y327952D02*
Y330708D01*
G01X1258504Y329364D02*
Y329296D01*
G01X1258154Y328166D02*
Y330495D01*
G01X1258111Y319987D02*
Y391972D01*
G01X1266265Y329645D02*
X1265374Y330393D01*
G01X1258898Y333897D02*
X1258111D01*
G01X1273071Y333862D02*
X1258111D01*
G01Y333374D02*
X1258898D01*
G01Y332616D02*
X1258111D01*
G01Y330737D02*
X1258898D01*
G01X1260486Y330708D02*
X1258111D01*
G01X1265374Y330393D02*
X1266392D01*
G01X1258898Y330315D02*
X1260486D01*
G01X1267307Y330118D02*
X1258111D01*
G01X1259698Y329921D02*
X1258111D01*
G01X1259292Y329758D02*
X1260879D01*
G01X1261300Y329645D02*
X1266265D01*
G01X1260092Y329364D02*
X1258504D01*
G01X1260092Y329296D02*
X1258504D01*
G01X1260879Y328903D02*
X1259292D01*
G01X1267284Y328897D02*
X1261300D01*
G01X1258111Y328740D02*
X1259698D01*
G01X1258154Y328543D02*
X1258942D01*
G01X1258898Y328346D02*
X1260486D01*
G01Y327952D02*
X1258111D01*
G01X1258898Y327847D02*
X1258111D01*
G01X1258032Y327129D02*
X1258111D01*
G01X1257914Y326798D02*
X1258111D01*
G01Y326589D02*
X1258898D01*
G01X1258701Y326011D02*
X1258898D01*
G01Y325907D02*
X1258111D01*
G01X1258701Y325617D02*
X1258898D01*
G01X1258111Y324790D02*
X1257914D01*
G01Y324718D02*
X1258111D01*
G01X1258898Y324515D02*
X1258701D01*
G01X1254174Y322563D02*
X1256006D01*
G01X1255748Y320673D02*
X1254174D01*
G01X1258111Y320656D02*
X1257914D01*
G01X1258111Y319987D02*
X1257914D01*
G01X1258898Y319869D02*
X1258701D01*
G01X1258898Y319711D02*
X1258701D01*
G01X1258243Y341518D02*
X1258255Y341523D01*
G01X1258230Y341514D02*
X1258243Y341518D01*
G01X1258217Y341510D02*
X1258230Y341514D01*
G01X1258204Y341507D02*
X1258217Y341510D01*
G01X1261317Y341401D02*
X1261338Y341535D01*
G01X1261255Y341281D02*
X1261317Y341401D01*
G01X1261160Y341185D02*
X1261255Y341281D01*
G01X1261038Y341123D02*
X1261160Y341185D01*
G01X1260905Y341102D02*
X1261038Y341123D01*
G01X1258121Y341496D02*
X1258111D01*
G01X1258135D02*
X1258121D01*
G01X1258150Y341498D02*
X1258135Y341496D01*
G01X1258165Y341500D02*
X1258150Y341498D01*
G01X1259358Y341429D02*
X1259370Y341529D01*
G01X1259321Y341333D02*
X1259358Y341429D01*
G01X1259263Y341249D02*
X1259321Y341333D01*
G01X1259190Y341183D02*
X1259263Y341249D01*
G01X1259105Y341136D02*
X1259190Y341183D01*
G01X1259018Y341110D02*
X1259105Y341136D01*
G01X1258940Y341102D02*
X1259018Y341110D01*
G01X1258474Y342433D02*
X1258504Y342283D01*
G01X1258389Y342561D02*
X1258474Y342433D01*
G01X1258262Y342646D02*
X1258389Y342561D01*
G01X1258111Y342677D02*
X1258262Y342646D01*
G01X1258181Y341502D02*
X1258111Y341496D01*
G01X1258256Y341524D02*
X1258181Y341502D01*
G01X1258460Y341708D02*
X1258476Y341742D01*
G01X1258440Y341675D02*
X1258460Y341708D01*
G01X1258418Y341644D02*
X1258440Y341675D01*
G01X1258393Y341615D02*
X1258418Y341644D01*
G01X1258488Y341777D02*
X1258476Y341742D01*
G01X1258497Y341815D02*
X1258488Y341777D01*
G01X1261038Y343049D02*
X1260905Y343070D01*
G01X1261160Y342987D02*
X1261038Y343049D01*
G01X1261255Y342891D02*
X1261160Y342987D01*
G01X1261317Y342771D02*
X1261255Y342891D01*
G01X1261338Y342637D02*
X1261317Y342771D01*
G01X1259017Y343063D02*
X1258940Y343070D01*
G01X1259105Y343037D02*
X1259017Y343063D01*
G01X1259190Y342989D02*
X1259105Y343037D01*
G01X1259263Y342923D02*
X1259190Y342989D01*
G01X1259321Y342840D02*
X1259263Y342923D01*
G01X1259358Y342743D02*
X1259321Y342840D01*
G01X1259370Y342643D02*
X1259358Y342743D01*
G01X1258262Y341526D02*
X1258111Y341496D01*
G01X1258389Y341611D02*
X1258262Y341526D01*
G01X1258474Y341739D02*
X1258389Y341611D01*
G01X1258504Y341889D02*
X1258474Y341739D01*
G01X1258903Y341102D02*
X1258937D01*
G01Y343070D02*
X1258903D01*
G01X1258898Y345237D02*
X1258899Y345236D01*
G01Y350275D02*
X1258898Y350274D01*
G01X1260048Y341496D02*
G03X1260442Y341889I0J394D01*
G01Y342283D02*
G03X1260048Y342677I-394J0D01*
G01X1260905Y341102D02*
G03X1261338Y341535I0J433D01*
G01Y342637D02*
G03X1260905Y343070I-433J0D01*
G01X1258504Y342283D02*
G03X1258111Y342677I-394J0D01*
G01Y341496D02*
G03X1258504Y341889I0J393D01*
G01X1258937Y341102D02*
G03X1259370Y341535I0J433D01*
G01Y342637D02*
G03X1258937Y343070I-433J0D01*
G01X1258503Y341853D02*
X1258497Y341815D01*
G01X1258476Y341743D02*
X1258488Y341778D01*
G01X1258504Y341892D02*
X1258502Y341853D01*
G01X1261338Y342637D02*
Y341535D01*
G01X1261331Y342637D02*
Y341535D01*
G01X1260948D02*
Y342637D01*
G01X1260442Y342283D02*
Y341889D01*
G01X1260436Y342283D02*
Y341889D01*
G01X1260116D02*
Y342283D01*
G01X1259382Y341535D02*
Y342637D01*
G01X1259370D02*
Y341535D01*
G01X1258922Y343070D02*
Y341102D01*
G01X1258910Y350275D02*
Y356574D01*
G01Y338543D02*
Y345236D01*
G01X1258898Y343070D02*
Y352440D01*
G01Y341102D02*
Y343070D01*
G01X1258516Y342283D02*
Y341889D01*
G01X1258504Y342283D02*
Y341889D01*
G01Y355984D02*
Y342047D01*
G01X1258135Y350275D02*
Y352834D01*
G01Y342677D02*
Y345236D01*
G01Y338543D02*
Y341496D01*
G01X1258363Y341587D02*
X1258392Y341615D01*
G01D02*
X1258393D01*
G01X1258363Y341587D02*
X1258329Y341562D01*
G01X1258393Y341615D02*
X1258363Y341587D01*
G01X1258330Y341563D02*
X1258293Y341540D01*
G01X1258113Y350275D02*
X1258111Y350274D01*
G01X1258255Y341523D02*
X1258254D01*
G01X1258294Y341541D02*
X1258255Y341523D01*
G01X1258111Y345237D02*
X1258113Y345236D01*
G01X1258940Y343070D02*
X1258914D01*
G01X1258130Y342677D02*
X1258129D01*
G01X1258111Y351345D02*
X1258898D01*
G01Y351202D02*
X1258111D01*
G01X1258898Y351175D02*
X1258111D01*
G01X1262113Y350275D02*
X1258113D01*
G01X1258898Y350274D02*
X1258111D01*
G01X1265729Y349015D02*
X1251280D01*
G01X1258898Y346856D02*
X1258111D01*
G01Y346829D02*
X1258898D01*
G01Y346686D02*
X1258111D01*
G01X1258898Y346068D02*
X1258111D01*
G01Y345237D02*
X1258898D01*
G01X1258113Y345236D02*
X1262113D01*
G01X1260905Y343070D02*
X1258937D01*
G01D02*
X1258898D01*
G01X1260048Y342677D02*
X1258111D01*
G01X1258129D02*
X1258110D01*
G01X1259370Y342637D02*
X1261338D01*
G01X1258111Y342322D02*
X1258898D01*
G01X1258516Y342283D02*
X1258522D01*
G01D02*
X1260442D01*
G01X1258111D02*
X1258516D01*
G01X1258111Y341889D02*
X1258516D01*
G01X1260442D02*
X1258522D01*
G01D02*
X1258516D01*
G01X1261338Y341535D02*
X1259370D01*
G01X1258110Y341496D02*
X1258129D01*
G01X1258111D02*
X1260048D01*
G01X1258129D02*
X1258135D01*
G01X1258937Y341102D02*
X1260905D01*
G01X1258937D02*
X1258898D01*
G01X1262113Y338543D02*
X1258111D01*
G01X1258913Y341102D02*
X1258940D01*
G01X1258243Y352857D02*
X1258255Y352862D01*
G01X1258230Y352853D02*
X1258243Y352857D01*
G01X1258217Y352849D02*
X1258230Y352853D01*
G01X1258204Y352846D02*
X1258217Y352849D01*
G01X1258121Y352834D02*
X1258111D01*
G01X1258134Y352835D02*
X1258121Y352834D01*
G01X1258150Y352836D02*
X1258134Y352835D01*
G01X1258165Y352838D02*
X1258150Y352836D01*
G01X1259358Y352768D02*
X1259370Y352868D01*
G01X1259321Y352672D02*
X1259358Y352768D01*
G01X1259263Y352588D02*
X1259321Y352672D01*
G01X1259190Y352522D02*
X1259263Y352588D01*
G01X1259105Y352474D02*
X1259190Y352522D01*
G01X1259018Y352448D02*
X1259105Y352474D01*
G01X1258940Y352440D02*
X1259018Y352448D01*
G01X1258474Y353772D02*
X1258504Y353622D01*
G01X1258389Y353900D02*
X1258474Y353772D01*
G01X1258262Y353985D02*
X1258389Y353900D01*
G01X1258111Y354015D02*
X1258262Y353985D01*
G01X1258181Y352840D02*
X1258111Y352834D01*
G01X1258256Y352862D02*
X1258181Y352840D01*
G01X1258460Y353046D02*
X1258476Y353081D01*
G01X1258440Y353013D02*
X1258460Y353046D01*
G01X1258418Y352982D02*
X1258440Y353013D01*
G01X1258393Y352953D02*
X1258418Y352982D01*
G01X1258262Y352865D02*
X1258111Y352834D01*
G01X1258389Y352950D02*
X1258262Y352865D01*
G01X1258474Y353077D02*
X1258389Y352950D01*
G01X1258504Y353228D02*
X1258474Y353077D01*
G01X1259017Y354401D02*
X1258940Y354409D01*
G01X1259105Y354375D02*
X1259017Y354401D01*
G01X1259190Y354327D02*
X1259105Y354375D01*
G01X1259263Y354262D02*
X1259190Y354327D01*
G01X1259321Y354178D02*
X1259263Y354262D01*
G01X1259358Y354081D02*
X1259321Y354178D01*
G01X1259370Y353981D02*
X1259358Y354081D01*
G01X1258903Y352440D02*
X1258937D01*
G01Y354409D02*
X1258903D01*
G01X1258898Y356575D02*
X1258899Y356574D01*
G01X1260486Y367716D02*
G03X1260879Y368273I-197J556D01*
G01X1258898Y367716D02*
G03X1259292Y368273I-197J557D01*
G01X1258111Y368110D02*
G03X1258504Y368666I-197J556D01*
G01X1259698Y368110D02*
G03X1260092Y368666I-196J557D01*
G01X1260473Y368700D02*
G03I-1969J0D01*
G01X1259722Y368272D02*
G03X1259940Y368275I56J3846D01*
G01X1260048Y352834D02*
G03X1260442Y353228I0J394D01*
G01Y353622D02*
G03X1260048Y354015I-394J-1D01*
G01X1260905Y352440D02*
G03X1261338Y352874I0J433D01*
G01Y353976D02*
G03X1260905Y354409I-433J0D01*
G01X1258504Y353622D02*
G03X1258111Y354015I-394J-1D01*
G01Y352834D02*
G03X1258504Y353228I-1J394D01*
G01X1259370Y353976D02*
G03X1258937Y354409I-433J0D01*
G01Y352440D02*
G03X1259370Y352874I0J433D01*
G01X1258476Y353081D02*
X1258488Y353117D01*
G01X1258497Y353154D02*
X1258488Y353116D01*
G01X1258503Y353192D02*
X1258497Y353153D01*
G01X1258504Y353231D02*
X1258502Y353192D01*
G01X1261338Y352874D02*
Y353976D01*
G01X1261331D02*
Y352874D01*
G01X1260948D02*
Y353976D01*
G01X1260879Y369128D02*
Y368273D01*
G01X1260486Y367716D02*
Y367322D01*
G01X1260442Y353228D02*
Y353622D01*
G01X1260436D02*
Y353228D01*
G01X1260381Y368273D02*
Y369128D01*
G01X1260116Y353228D02*
Y353622D01*
G01X1260059Y367716D02*
Y367322D01*
G01X1259940Y369128D02*
Y368273D01*
G01X1259698Y368110D02*
Y367322D01*
G01X1259479D02*
Y367716D01*
G01X1259414Y368110D02*
Y367322D01*
G01X1259401D02*
Y367716D01*
G01X1259382Y353976D02*
Y352874D01*
G01X1259370Y353976D02*
Y352874D01*
G01X1259292Y369128D02*
Y368273D01*
G01X1259155Y367322D02*
Y370078D01*
G01X1259027Y367322D02*
Y368110D01*
G01X1258950Y367322D02*
Y368110D01*
G01X1258942Y367536D02*
Y369865D01*
G01X1258922Y354409D02*
Y352440D01*
G01X1258898Y354409D02*
Y391185D01*
G01Y352440D02*
Y354409D01*
G01X1258516Y353622D02*
Y353228D01*
G01X1258510Y367322D02*
Y370078D01*
G01X1258504Y353228D02*
Y353622D01*
G01X1258154Y367536D02*
Y369865D01*
G01X1258135Y354015D02*
Y356574D01*
G01X1258392Y352953D02*
X1258393Y352954D01*
G01X1258363Y352926D02*
X1258329Y352900D01*
G01X1258392Y352953D02*
X1258362Y352925D01*
G01X1258330Y352901D02*
X1258293Y352879D01*
G01X1258255Y352862D02*
X1258254Y352861D01*
G01X1258294Y352880D02*
X1258255Y352862D01*
G01X1258111Y356575D02*
X1258113Y356574D01*
G01X1259722Y368271D02*
X1259638Y368273D01*
G01X1258940Y354409D02*
X1258914D01*
G01X1258130Y354015D02*
X1258129D01*
G01X1259638Y368273D02*
X1259292D01*
G01X1260879D02*
X1259940D01*
G01X1258111Y368110D02*
X1259698D01*
G01X1258942Y367913D02*
X1258154D01*
G01X1258898Y367716D02*
X1260486D01*
G01Y367322D02*
X1258111D01*
G01X1258898Y367294D02*
X1258111D01*
G01Y365415D02*
X1258898D01*
G01Y364656D02*
X1258111D01*
G01X1273071Y364177D02*
X1258111D01*
G01X1258898Y361614D02*
X1258111D01*
G01Y357834D02*
X1258898D01*
G01X1258111Y356575D02*
X1258898D01*
G01X1258113Y356574D02*
X1262113D01*
G01X1258898Y354409D02*
X1258937D01*
G01X1260905D02*
X1258937D01*
G01X1260048Y354015D02*
X1258111D01*
G01X1258129D02*
X1258110D01*
G01X1259370Y353976D02*
X1261338D01*
G01X1258516Y353622D02*
X1258522D01*
G01D02*
X1260442D01*
G01X1258111D02*
X1258516D01*
G01X1258522Y353228D02*
X1260442D01*
G01X1258516D02*
X1258111D01*
G01X1258522D02*
X1258516D01*
G01X1261338Y352874D02*
X1259370D01*
G01X1258110Y352834D02*
X1258129D01*
G01X1258111D02*
X1260048D01*
G01X1258129D02*
X1258135D01*
G01X1258898Y352440D02*
X1258937D01*
G01X1260905D02*
X1258937D01*
G01X1258111Y351962D02*
X1258898D01*
G01X1258913Y352440D02*
X1258940D01*
G01X1260879Y369128D02*
G03X1260486Y369685I-591J0D01*
G01X1258504Y368734D02*
G03X1258111Y369291I-591J0D01*
G01X1260092Y368734D02*
G03X1259698Y369291I-591J0D01*
G01X1259292Y369128D02*
G03X1258898Y369685I-591J0D01*
G01X1259940Y369127D02*
G03X1259722Y369129I-144J-3862D01*
G01X1260486Y370078D02*
Y369685D01*
G01X1260092Y368666D02*
Y368734D01*
G01X1260059Y370078D02*
Y369685D01*
G01X1259736Y368666D02*
Y368734D01*
G01X1259698Y370078D02*
Y369291D01*
G01X1259479Y369685D02*
Y370078D01*
G01X1259414D02*
Y369291D01*
G01X1259401Y369685D02*
Y370078D01*
G01X1259292Y388586D02*
Y384649D01*
G01X1259253Y368734D02*
Y368666D01*
G01X1259176Y368734D02*
Y368666D01*
G01X1259027Y369291D02*
Y370078D01*
G01X1258950Y369291D02*
Y370078D01*
G01X1258504Y368666D02*
Y368734D01*
G01X1254174Y384649D02*
X1259292D01*
G01X1258898Y379488D02*
X1258111D01*
G01X1254174Y377759D02*
X1258111D01*
G01Y375476D02*
X1254174D01*
G01X1258898Y373189D02*
X1258111D01*
G01Y372124D02*
X1258898D01*
G01Y371442D02*
X1258111D01*
G01Y370184D02*
X1258898D01*
G01X1260486Y370078D02*
X1258111D01*
G01X1258898Y369685D02*
X1260486D01*
G01X1258154Y369488D02*
X1258942D01*
G01X1258111Y369291D02*
X1259698D01*
G01X1259940Y369128D02*
X1260879D01*
G01X1259292D02*
X1259627D01*
G01X1260092Y368734D02*
X1258504D01*
G01X1260092Y368666D02*
X1258504D01*
G01X1259627Y369127D02*
X1259722Y369129D01*
G01X1258111Y394885D02*
G03X1254174Y390948I0J-3937D01*
G01X1265038Y394964D02*
Y394885D01*
G01X1264919D02*
Y394964D01*
G01X1264741D02*
Y394885D01*
G01X1264681D02*
Y394964D01*
G01X1264622D02*
Y394885D01*
G01X1264385Y394964D02*
Y394885D01*
G01X1264266Y394964D02*
Y394885D01*
G01X1263435Y394964D02*
Y394885D01*
G01X1260076Y388972D02*
Y391972D01*
G01X1259288Y391185D02*
Y388972D01*
G01Y391185D02*
X1260076Y391972D01*
G01X1267234Y394964D02*
X1263435D01*
G01X1258111Y394885D02*
X1273071D01*
G01X1260076Y391972D02*
X1258111D01*
G01X1259288Y391185D02*
X1258111D01*
G01X1258898Y391141D02*
X1258111D01*
G01X1258898Y389370D02*
X1258111D01*
G01X1259288Y388972D02*
X1266533D01*
G01X1259292Y388586D02*
X1271890D01*
G01X1258898Y388189D02*
X1258111D01*
G01X1251575Y425196D02*
Y429133D01*
G01X1274016Y7086D02*
G03I-1575J0D01*
G01X1274213D02*
G03I-1772J0D01*
G01X1280906Y-7678D02*
X1281890Y-5973D01*
G01X1278937Y-7678D02*
X1279922Y-5973D01*
G01X1278347Y-6655D02*
Y196D01*
G01X1277953Y-5973D02*
Y4921D01*
G01X1267126Y13976D02*
Y196D01*
G01X1279922Y-5973D02*
X1280906Y-7678D01*
G01X1277953Y-5973D02*
X1278937Y-7678D01*
G01X1293701Y4921D02*
X1277953D01*
G01X1304528Y196D02*
X1267126D01*
G01X1275983Y18365D02*
X1275737Y18072D01*
G01Y18407D02*
X1275983Y18700D01*
G01X1278347Y22834D02*
Y12992D01*
G01X1277166Y21850D02*
Y13976D01*
G01X1276229Y18700D02*
Y16732D01*
G01X1275983D02*
Y18365D01*
G01X1275737Y18072D02*
Y18407D01*
G01X1274803Y13976D02*
Y21850D01*
G01X1273622Y12992D02*
Y22834D01*
G01D02*
X1278347D01*
G01X1277166Y21850D02*
X1274803D01*
G01X1275983Y18700D02*
X1276229D01*
G01Y16732D02*
X1275983D01*
G01X1304528Y13976D02*
X1267126D01*
G01X1278347Y12992D02*
X1273622D01*
G01X1267717Y37598D02*
G03Y39566I0J984D01*
G01X1280315D02*
G03Y37598I0J-984D01*
G01X1280020Y38535D02*
X1279659Y38149D01*
G01X1279528D02*
X1279823Y38468D01*
G01X1273908Y38330D02*
X1273888Y38307D01*
G01Y38333D02*
X1273908Y38357D01*
G01X1273481Y38330D02*
X1273462Y38307D01*
G01Y38333D02*
X1273481Y38357D01*
G01X1274761Y38380D02*
X1274751Y38367D01*
G01X1273740Y38451D02*
X1273731Y38437D01*
G01X1272943Y38380D02*
X1272933Y38367D01*
G01X1272425Y38451D02*
X1272415Y38437D01*
G01X1271388Y38380D02*
X1271378Y38367D01*
G01X1271319Y38400D02*
X1271329Y38414D01*
G01X1271253Y38437D02*
X1271244Y38424D01*
G01X1274498Y38337D02*
X1274505Y38347D01*
G01X1273744Y38427D02*
X1273750Y38437D01*
G01X1273600Y38333D02*
X1273606Y38344D01*
G01X1273511Y38364D02*
X1273517Y38374D01*
G01X1273242Y38424D02*
X1273248Y38434D01*
G01X1273101Y38424D02*
X1273107Y38434D01*
G01X1272871Y38337D02*
X1272877Y38347D01*
G01X1272572Y38424D02*
X1272579Y38434D01*
G01X1272428Y38427D02*
X1272435Y38437D01*
G01X1272356Y38333D02*
X1272363Y38344D01*
G01X1272271Y38364D02*
X1272277Y38374D01*
G01X1272205Y38333D02*
X1272218Y38353D01*
G01X1272267Y38437D02*
X1272274Y38447D01*
G01X1272153Y38437D02*
X1272139Y38417D01*
G01X1271838Y38333D02*
X1271844Y38344D01*
G01X1271752Y38364D02*
X1271759Y38374D01*
G01X1271749Y38437D02*
X1271755Y38447D01*
G01X1271319Y38337D02*
X1271326Y38347D01*
G01X1271253Y38364D02*
X1271247Y38353D01*
G01X1273809Y38367D02*
X1273826Y38377D01*
G01X1273757Y38461D02*
X1273740Y38451D01*
G01X1272494Y38367D02*
X1272510Y38377D01*
G01X1272198Y38310D02*
X1272215Y38320D01*
G01X1272441Y38461D02*
X1272425Y38451D01*
G01X1272159Y38461D02*
X1272143Y38451D01*
G01X1271309Y38310D02*
X1271326Y38320D01*
G01X1271260Y38461D02*
X1271244Y38451D01*
G01X1274488Y38330D02*
X1274498Y38337D01*
G01X1274433Y38440D02*
X1274423Y38434D01*
G01X1273590Y38327D02*
X1273600Y38333D01*
G01X1273750Y38437D02*
X1273760Y38444D01*
G01X1273311Y38337D02*
X1273301Y38330D01*
G01X1273248Y38434D02*
X1273258Y38440D01*
G01X1273107Y38434D02*
X1273117Y38440D01*
G01X1272861Y38330D02*
X1272871Y38337D01*
G01X1272805Y38440D02*
X1272796Y38434D01*
G01X1272641Y38337D02*
X1272631Y38330D01*
G01X1272579Y38434D02*
X1272589Y38440D01*
G01X1272346Y38327D02*
X1272356Y38333D01*
G01X1272435Y38437D02*
X1272444Y38444D01*
G01X1272195Y38327D02*
X1272205Y38333D01*
G01X1272274Y38447D02*
X1272284Y38454D01*
G01X1272163Y38444D02*
X1272153Y38437D01*
G01X1271828Y38327D02*
X1271838Y38333D01*
G01X1271755Y38447D02*
X1271765Y38454D01*
G01X1273819Y38394D02*
X1273806Y38384D01*
G01X1272503Y38394D02*
X1272490Y38384D01*
G01X1272277Y38374D02*
X1272290Y38384D01*
G01X1271759Y38374D02*
X1271772Y38384D01*
G01X1271306Y38327D02*
X1271319Y38337D01*
G01X1271326Y38387D02*
X1271339Y38397D01*
G01X1271267Y38374D02*
X1271253Y38364D01*
G01X1273517Y38374D02*
X1273600Y38447D01*
G01X1273625D02*
X1273534Y38364D01*
G01X1279905Y38551D02*
X1280020Y38668D01*
G01X1274777Y38370D02*
X1274771Y38364D01*
G01X1274518Y38330D02*
X1274505Y38317D01*
G01X1274403Y38440D02*
X1274416Y38454D01*
G01X1273619Y38330D02*
X1273606Y38317D01*
G01X1273317D02*
X1273330Y38330D01*
G01X1273242Y38454D02*
X1273229Y38440D01*
G01X1273101Y38454D02*
X1273088Y38440D01*
G01X1272960Y38370D02*
X1272953Y38364D01*
G01X1272891Y38330D02*
X1272877Y38317D01*
G01X1272776Y38440D02*
X1272789Y38454D01*
G01X1272648Y38317D02*
X1272661Y38330D01*
G01X1272572Y38454D02*
X1272559Y38440D01*
G01X1272375Y38330D02*
X1272363Y38317D01*
G01X1272297Y38370D02*
X1272290Y38364D01*
G01X1272215Y38320D02*
X1272225Y38330D01*
G01X1272290Y38440D02*
X1272284Y38434D01*
G01X1272143Y38451D02*
X1272133Y38440D01*
G01X1271857Y38330D02*
X1271844Y38317D01*
G01X1271779Y38370D02*
X1271772Y38364D01*
G01Y38440D02*
X1271765Y38434D01*
G01X1271405Y38370D02*
X1271398Y38364D01*
G01X1271326Y38320D02*
X1271336Y38330D01*
G01X1271247Y38380D02*
X1271237Y38370D01*
G01X1271244Y38451D02*
X1271234Y38440D01*
G01X1274525Y38344D02*
X1274518Y38330D01*
G01X1273534Y38364D02*
X1273527Y38350D01*
G01X1273229Y38440D02*
X1273222Y38427D01*
G01X1273088Y38440D02*
X1273081Y38427D01*
G01X1272897Y38344D02*
X1272891Y38330D01*
G01X1272559Y38440D02*
X1272553Y38427D01*
G01X1272290Y38364D02*
X1272284Y38350D01*
G01Y38434D02*
X1272281Y38427D01*
G01X1272225Y38330D02*
X1272231Y38344D01*
G01X1272133Y38440D02*
X1272126Y38427D01*
G01X1271772Y38364D02*
X1271765Y38350D01*
G01Y38434D02*
X1271762Y38427D01*
G01X1271237Y38370D02*
X1271231Y38357D01*
G01X1273731Y38437D02*
X1273724Y38420D01*
G01X1272415Y38437D02*
X1272409Y38420D01*
G01X1271336Y38330D02*
X1271342Y38347D01*
G01X1271339Y38397D02*
X1271346Y38414D01*
G01X1271234Y38440D02*
X1271227Y38424D01*
G01X1275105Y38444D02*
X1275059Y38307D01*
G01X1275040D02*
X1275092Y38464D01*
G01X1272021D02*
X1271969Y38307D01*
G01X1268386Y38974D02*
X1268124Y38187D01*
G01X1274771Y38364D02*
X1274767Y38353D01*
G01X1274751Y38367D02*
X1274748Y38357D01*
G01X1274423Y38434D02*
X1274420Y38424D01*
G01X1273740Y38417D02*
X1273744Y38427D01*
G01X1273314Y38347D02*
X1273311Y38337D01*
G01X1272953Y38364D02*
X1272950Y38353D01*
G01X1272933Y38367D02*
X1272930Y38357D01*
G01X1272796Y38434D02*
X1272792Y38424D01*
G01X1272645Y38347D02*
X1272641Y38337D01*
G01X1272425Y38417D02*
X1272428Y38427D01*
G01X1272264D02*
X1272267Y38437D01*
G01X1272231Y38344D02*
X1272235Y38353D01*
G01X1272126Y38427D02*
X1272123Y38417D01*
G01X1271985Y38411D02*
X1271956Y38320D01*
G01X1271988Y38424D02*
X1272001Y38464D01*
G01X1271746Y38427D02*
X1271749Y38437D01*
G01X1271398Y38364D02*
X1271395Y38353D01*
G01X1271378Y38367D02*
X1271375Y38357D01*
G01X1268206Y38706D02*
X1268058Y38254D01*
G01X1268222Y38774D02*
X1268288Y38974D01*
G01X1274505Y38347D02*
X1274508Y38360D01*
G01X1274400Y38427D02*
X1274403Y38440D01*
G01X1273622Y38344D02*
X1273619Y38330D01*
G01X1273507Y38350D02*
X1273511Y38364D01*
G01X1273330Y38330D02*
X1273334Y38344D01*
G01X1273098Y38411D02*
X1273101Y38424D01*
G01X1272877Y38347D02*
X1272881Y38360D01*
G01X1272661Y38330D02*
X1272664Y38344D01*
G01X1272379D02*
X1272375Y38330D01*
G01X1272267Y38350D02*
X1272271Y38364D01*
G01X1271861Y38344D02*
X1271857Y38330D01*
G01X1271749Y38350D02*
X1271752Y38364D01*
G01X1274528Y38360D02*
X1274525Y38344D01*
G01X1273081Y38427D02*
X1273078Y38411D01*
G01X1272901Y38360D02*
X1272897Y38344D01*
G01X1272773Y38424D02*
X1272776Y38440D01*
G01X1272235Y38353D02*
X1272238Y38370D01*
G01X1272123Y38417D02*
X1272120Y38400D01*
G01X1272218Y38353D02*
X1272222Y38374D01*
G01X1272139Y38417D02*
X1272136Y38397D01*
G01X1274774Y38387D02*
X1274761Y38380D01*
G01X1274505Y38317D02*
X1274492Y38310D01*
G01X1274416Y38454D02*
X1274429Y38461D01*
G01X1273606Y38317D02*
X1273593Y38310D01*
G01X1273304D02*
X1273317Y38317D01*
G01X1273255Y38461D02*
X1273242Y38454D01*
G01X1272877Y38317D02*
X1272864Y38310D01*
G01X1273114Y38461D02*
X1273101Y38454D01*
G01X1272956Y38387D02*
X1272943Y38380D01*
G01X1272635Y38310D02*
X1272648Y38317D01*
G01X1272789Y38454D02*
X1272802Y38461D01*
G01X1272363Y38317D02*
X1272350Y38310D01*
G01X1272586Y38461D02*
X1272572Y38454D01*
G01X1272297Y38444D02*
X1272290Y38440D01*
G01X1272284Y38454D02*
X1272297Y38461D01*
G01X1271844Y38317D02*
X1271831Y38310D01*
G01X1271779Y38444D02*
X1271772Y38440D01*
G01X1271765Y38454D02*
X1271779Y38461D01*
G01X1271401Y38387D02*
X1271388Y38380D01*
G01X1271319Y38384D02*
X1271326Y38387D01*
G01X1271306Y38394D02*
X1271319Y38400D01*
G01X1271253Y38384D02*
X1271247Y38380D01*
G01X1271267Y38444D02*
X1271253Y38437D01*
G01X1280315Y39566D02*
Y41535D01*
G01Y35629D02*
Y37598D01*
G01X1280118Y38937D02*
Y38149D01*
G01X1280020D02*
Y38535D01*
G01Y38668D02*
Y38937D01*
G01X1277953Y41535D02*
Y35629D01*
G01X1277789D02*
Y41535D01*
G01X1275315Y38464D02*
Y38307D01*
G01X1275296Y38327D02*
Y38370D01*
G01Y38390D02*
Y38444D01*
G01X1275210Y38370D02*
Y38390D01*
G01X1275197Y38444D02*
Y38464D01*
G01Y38307D02*
Y38327D01*
G01X1275013Y38464D02*
Y38307D01*
G01X1274994Y38327D02*
Y38370D01*
G01Y38390D02*
Y38444D01*
G01X1274909Y38370D02*
Y38390D01*
G01X1274895Y38444D02*
Y38464D01*
G01Y38307D02*
Y38327D01*
G01X1274869Y38307D02*
Y38464D01*
G01X1274850Y38324D02*
Y38374D01*
G01Y38464D02*
Y38394D01*
G01X1274767Y38353D02*
Y38344D01*
G01X1274748Y38357D02*
Y38344D01*
G01X1274718Y38464D02*
Y38307D01*
G01X1274698D02*
Y38444D01*
G01X1274600D02*
Y38464D01*
G01X1274574D02*
Y38307D01*
G01X1274554D02*
Y38464D01*
G01X1274528Y38411D02*
Y38360D01*
G01X1274508D02*
Y38411D01*
G01X1274449Y38397D02*
Y38377D01*
G01X1274420Y38424D02*
Y38397D01*
G01X1274400Y38377D02*
Y38427D01*
G01X1274374Y38464D02*
Y38307D01*
G01X1274354D02*
Y38370D01*
G01Y38390D02*
Y38464D01*
G01X1274262Y38370D02*
Y38307D01*
G01Y38464D02*
Y38390D01*
G01X1274242Y38307D02*
Y38464D01*
G01X1274216Y38324D02*
Y38307D01*
G01X1274164Y38464D02*
Y38324D01*
G01X1274144D02*
Y38464D01*
G01X1274092Y38307D02*
Y38324D01*
G01X1273908Y38357D02*
Y38330D01*
G01X1273888Y38464D02*
Y38333D01*
G01X1273868Y38307D02*
Y38464D01*
G01X1273842Y38307D02*
Y38394D01*
G01X1273826Y38377D02*
Y38324D01*
G01X1273740Y38411D02*
Y38417D01*
G01X1273731Y38324D02*
Y38307D01*
G01X1273724Y38420D02*
Y38407D01*
G01X1273698D02*
Y38390D01*
G01X1273652D02*
Y38407D01*
G01X1273625Y38464D02*
Y38447D01*
G01X1273527Y38350D02*
Y38344D01*
G01X1273507D02*
Y38350D01*
G01Y38447D02*
Y38464D01*
G01X1273481Y38357D02*
Y38330D01*
G01X1273462Y38464D02*
Y38333D01*
G01X1273442Y38307D02*
Y38464D01*
G01X1273416Y38407D02*
Y38390D01*
G01X1273370D02*
Y38407D01*
G01X1273334Y38344D02*
Y38357D01*
G01X1273314Y38353D02*
Y38347D01*
G01X1273242Y38414D02*
Y38424D01*
G01X1273222Y38427D02*
Y38411D01*
G01X1273196Y38307D02*
Y38411D01*
G01X1273176D02*
Y38307D01*
G01X1273098D02*
Y38411D01*
G01X1273078D02*
Y38307D01*
G01X1273051D02*
Y38464D01*
G01X1273032Y38324D02*
Y38374D01*
G01Y38464D02*
Y38394D01*
G01X1272950Y38353D02*
Y38344D01*
G01X1272930Y38357D02*
Y38344D01*
G01X1272901Y38411D02*
Y38360D01*
G01X1272881D02*
Y38411D01*
G01X1272746Y38407D02*
Y38390D01*
G01X1272700D02*
Y38407D01*
G01X1272664Y38344D02*
Y38357D01*
G01X1272645Y38353D02*
Y38347D01*
G01X1272572Y38414D02*
Y38424D01*
G01X1272553Y38427D02*
Y38411D01*
G01X1272527Y38307D02*
Y38394D01*
G01X1272510Y38377D02*
Y38324D01*
G01X1272425Y38411D02*
Y38417D01*
G01X1272415Y38324D02*
Y38307D01*
G01X1272409Y38420D02*
Y38407D01*
G01X1272330Y38390D02*
Y38377D01*
G01X1272284Y38350D02*
Y38344D01*
G01X1272281Y38427D02*
Y38414D01*
G01X1272267Y38344D02*
Y38350D01*
G01X1272264Y38414D02*
Y38427D01*
G01X1272238Y38370D02*
Y38400D01*
G01X1272222Y38374D02*
Y38397D01*
G01X1272136D02*
Y38374D01*
G01X1272120Y38400D02*
Y38370D01*
G01X1272094Y38407D02*
Y38390D01*
G01X1272048D02*
Y38407D01*
G01X1271811Y38390D02*
Y38377D01*
G01X1271765Y38350D02*
Y38344D01*
G01X1271762Y38427D02*
Y38414D01*
G01X1271749Y38344D02*
Y38350D01*
G01X1271746Y38414D02*
Y38427D01*
G01X1271720Y38407D02*
Y38390D01*
G01X1271674D02*
Y38407D01*
G01X1271647Y38324D02*
Y38307D01*
G01X1271595Y38464D02*
Y38324D01*
G01X1271575D02*
Y38464D01*
G01X1271523Y38307D02*
Y38324D01*
G01X1271496Y38307D02*
Y38464D01*
G01X1271477Y38324D02*
Y38374D01*
G01Y38464D02*
Y38394D01*
G01X1271395Y38353D02*
Y38344D01*
G01X1271375Y38357D02*
Y38344D01*
G01X1271346Y38414D02*
Y38424D01*
G01X1271342Y38347D02*
Y38357D01*
G01X1271329Y38414D02*
Y38424D01*
G01X1271326Y38347D02*
Y38353D01*
G01X1271247D02*
Y38347D01*
G01X1271244Y38424D02*
Y38414D01*
G01X1271231Y38357D02*
Y38347D01*
G01X1271227Y38424D02*
Y38414D01*
G01X1270243Y41535D02*
Y35629D01*
G01X1270079Y41535D02*
Y35629D01*
G01X1267717Y37598D02*
Y35629D01*
G01Y41535D02*
Y39566D01*
G01X1272222Y38397D02*
X1272218Y38417D01*
G01X1272136Y38374D02*
X1272139Y38353D01*
G01X1274787Y38374D02*
X1274777Y38370D01*
G01X1273301Y38330D02*
X1273291Y38327D01*
G01X1272970Y38374D02*
X1272960Y38370D01*
G01X1272631Y38330D02*
X1272622Y38327D01*
G01X1272316Y38377D02*
X1272297Y38370D01*
G01X1271798Y38377D02*
X1271779Y38370D01*
G01X1271414Y38374D02*
X1271405Y38370D01*
G01X1274525Y38427D02*
X1274528Y38411D01*
G01X1274403Y38330D02*
X1274400Y38347D01*
G01X1273196Y38411D02*
X1273192Y38427D01*
G01X1272897D02*
X1272901Y38411D01*
G01X1272776Y38330D02*
X1272773Y38347D01*
G01X1272238Y38400D02*
X1272235Y38417D01*
G01X1272120Y38370D02*
X1272123Y38353D01*
G01X1274508Y38411D02*
X1274505Y38424D01*
G01X1273511Y38330D02*
X1273507Y38344D01*
G01X1273344Y38420D02*
X1273340Y38434D01*
G01X1273334Y38357D02*
X1273330Y38370D01*
G01X1273173Y38424D02*
X1273176Y38411D01*
G01X1272881D02*
X1272877Y38424D01*
G01X1272674Y38420D02*
X1272671Y38434D01*
G01X1272664Y38357D02*
X1272661Y38370D01*
G01X1272267Y38400D02*
X1272264Y38414D01*
G01X1272271Y38330D02*
X1272267Y38344D01*
G01X1271749Y38400D02*
X1271746Y38414D01*
G01X1271752Y38330D02*
X1271749Y38344D01*
G01X1274767D02*
X1274771Y38333D01*
G01X1274748Y38344D02*
X1274751Y38333D01*
G01X1274420Y38347D02*
X1274423Y38337D01*
G01X1273744Y38400D02*
X1273740Y38411D01*
G01X1273320Y38431D02*
X1273324Y38420D01*
G01X1273311Y38364D02*
X1273314Y38353D01*
G01X1273232Y38344D02*
X1273235Y38333D01*
G01X1272950Y38344D02*
X1272953Y38333D01*
G01X1272930Y38344D02*
X1272933Y38333D01*
G01X1272792Y38347D02*
X1272796Y38337D01*
G01X1272651Y38431D02*
X1272655Y38420D01*
G01X1272641Y38364D02*
X1272645Y38353D01*
G01X1272563Y38344D02*
X1272566Y38333D01*
G01X1272428Y38400D02*
X1272425Y38411D01*
G01X1272379Y38437D02*
X1272382Y38427D01*
G01X1272235Y38417D02*
X1272231Y38427D01*
G01X1272123Y38353D02*
X1272126Y38344D01*
G01X1271956Y38320D02*
X1271926Y38411D01*
G01X1271910Y38464D02*
X1271923Y38424D01*
G01X1271861Y38437D02*
X1271864Y38427D01*
G01X1271395Y38344D02*
X1271398Y38333D01*
G01X1271375Y38344D02*
X1271378Y38333D01*
G01X1267828Y38974D02*
X1267894Y38774D01*
G01X1268058Y38254D02*
X1267911Y38706D01*
G01X1275118Y38464D02*
X1275171Y38307D01*
G01X1271942D02*
X1271890Y38464D01*
G01X1267992Y38187D02*
X1267730Y38974D01*
G01X1275151Y38307D02*
X1275105Y38444D01*
G01X1274794Y38394D02*
X1274767Y38464D01*
G01X1272976Y38394D02*
X1272950Y38464D01*
G01X1271421Y38394D02*
X1271395Y38464D01*
G01X1274744D02*
X1274774Y38387D01*
G01X1272927Y38464D02*
X1272956Y38387D01*
G01X1271372Y38464D02*
X1271401Y38387D01*
G01X1273724Y38407D02*
X1273731Y38390D01*
G01X1272409Y38407D02*
X1272415Y38390D01*
G01X1271346Y38424D02*
X1271339Y38440D01*
G01X1271227Y38414D02*
X1271234Y38397D01*
G01X1271231Y38347D02*
X1271237Y38330D01*
G01X1274518Y38440D02*
X1274525Y38427D01*
G01X1273842Y38424D02*
X1273836Y38437D01*
G01X1273816D02*
X1273822Y38424D01*
G01X1273222Y38411D02*
X1273229Y38397D01*
G01X1273255Y38337D02*
X1273251Y38344D01*
G01X1273192Y38427D02*
X1273186Y38440D01*
G01X1272891D02*
X1272897Y38427D01*
G01X1272586Y38337D02*
X1272582Y38344D01*
G01X1272553Y38411D02*
X1272559Y38397D01*
G01X1272527Y38424D02*
X1272520Y38437D01*
G01X1272500D02*
X1272507Y38424D01*
G01X1272366Y38427D02*
X1272363Y38434D01*
G01X1272281Y38414D02*
X1272287Y38400D01*
G01X1272231Y38427D02*
X1272225Y38440D01*
G01X1272126Y38344D02*
X1272133Y38330D01*
G01X1271848Y38427D02*
X1271844Y38434D01*
G01X1271762Y38414D02*
X1271769Y38400D01*
G01X1271342Y38357D02*
X1271336Y38370D01*
G01X1273340Y38434D02*
X1273330Y38451D01*
G01X1272671Y38434D02*
X1272661Y38451D01*
G01X1279823Y38468D02*
X1279528Y38937D01*
G01X1279659D02*
X1279905Y38551D01*
G01X1274505Y38424D02*
X1274498Y38434D01*
G01X1273750Y38390D02*
X1273744Y38400D01*
G01X1273527Y38344D02*
X1273534Y38333D01*
G01X1273248Y38404D02*
X1273242Y38414D01*
G01X1273166Y38434D02*
X1273173Y38424D01*
G01X1272877D02*
X1272871Y38434D01*
G01X1272579Y38404D02*
X1272572Y38414D01*
G01X1272435Y38390D02*
X1272428Y38400D01*
G01X1272372Y38447D02*
X1272379Y38437D01*
G01X1272274Y38390D02*
X1272267Y38400D01*
G01X1272284Y38344D02*
X1272290Y38333D01*
G01X1272218Y38417D02*
X1272205Y38437D01*
G01X1272139Y38353D02*
X1272153Y38333D01*
G01X1271854Y38447D02*
X1271861Y38437D01*
G01X1271755Y38390D02*
X1271749Y38400D01*
G01X1271765Y38344D02*
X1271772Y38333D01*
G01X1271326Y38353D02*
X1271319Y38364D01*
G01X1271247Y38347D02*
X1271253Y38337D01*
G01X1274751Y38333D02*
X1274761Y38320D01*
G01X1273836Y38437D02*
X1273826Y38451D01*
G01X1273731Y38390D02*
X1273740Y38377D01*
G01X1273235Y38333D02*
X1273245Y38320D01*
G01X1272933Y38333D02*
X1272943Y38320D01*
G01X1272520Y38437D02*
X1272510Y38451D01*
G01X1272566Y38333D02*
X1272576Y38320D01*
G01X1272415Y38390D02*
X1272425Y38377D01*
G01X1271329Y38424D02*
X1271319Y38437D01*
G01X1271378Y38333D02*
X1271388Y38320D01*
G01X1271244Y38414D02*
X1271253Y38400D01*
G01X1274771Y38333D02*
X1274777Y38327D01*
G01X1274505Y38454D02*
X1274518Y38440D01*
G01X1274416Y38317D02*
X1274403Y38330D01*
G01X1273524Y38317D02*
X1273511Y38330D01*
G01X1273311Y38440D02*
X1273320Y38431D01*
G01X1273330Y38370D02*
X1273317Y38384D01*
G01X1273229Y38397D02*
X1273242Y38384D01*
G01X1273186Y38440D02*
X1273173Y38454D01*
G01X1273261Y38330D02*
X1273255Y38337D01*
G01X1272877Y38454D02*
X1272891Y38440D01*
G01X1272953Y38333D02*
X1272960Y38327D01*
G01X1272789Y38317D02*
X1272776Y38330D01*
G01X1272641Y38440D02*
X1272651Y38431D01*
G01X1272661Y38370D02*
X1272648Y38384D01*
G01X1272559Y38397D02*
X1272572Y38384D01*
G01X1272363Y38434D02*
X1272356Y38440D01*
G01X1272225D02*
X1272215Y38451D01*
G01X1272284Y38317D02*
X1272271Y38330D01*
G01X1272133D02*
X1272143Y38320D01*
G01X1271765Y38317D02*
X1271752Y38330D01*
G01X1271339Y38440D02*
X1271329Y38451D01*
G01X1271398Y38333D02*
X1271405Y38327D01*
G01X1271336Y38370D02*
X1271326Y38380D01*
G01X1271237Y38330D02*
X1271247Y38320D01*
G01X1272592Y38330D02*
X1272586Y38337D01*
G01X1271844Y38434D02*
X1271838Y38440D01*
G01X1274761Y38320D02*
X1274774Y38310D01*
G01X1273245Y38320D02*
X1273258Y38310D01*
G01X1272943Y38320D02*
X1272956Y38310D01*
G01X1272576Y38320D02*
X1272589Y38310D01*
G01X1271388Y38320D02*
X1271401Y38310D01*
G01X1271319Y38364D02*
X1271306Y38374D01*
G01X1271234Y38397D02*
X1271247Y38387D01*
G01X1271253Y38337D02*
X1271267Y38327D01*
G01X1274498Y38434D02*
X1274488Y38440D01*
G01X1274423Y38337D02*
X1274433Y38330D01*
G01X1273806Y38444D02*
X1273816Y38437D01*
G01X1273760Y38384D02*
X1273750Y38390D01*
G01X1273534Y38333D02*
X1273544Y38327D01*
G01X1273301Y38370D02*
X1273311Y38364D01*
G01X1273258Y38397D02*
X1273248Y38404D01*
G01X1273157Y38440D02*
X1273166Y38434D01*
G01X1272871D02*
X1272861Y38440D01*
G01X1272796Y38337D02*
X1272805Y38330D01*
G01X1272631Y38370D02*
X1272641Y38364D01*
G01X1272589Y38397D02*
X1272579Y38404D01*
G01X1272490Y38444D02*
X1272500Y38437D01*
G01X1272363Y38454D02*
X1272372Y38447D01*
G01X1272444Y38384D02*
X1272435Y38390D01*
G01X1272287Y38400D02*
X1272297Y38394D01*
G01X1272205Y38437D02*
X1272195Y38444D01*
G01X1272290Y38333D02*
X1272300Y38327D01*
G01X1272153Y38333D02*
X1272163Y38327D01*
G01X1271844Y38454D02*
X1271854Y38447D01*
G01X1271769Y38400D02*
X1271779Y38394D01*
G01X1271772Y38333D02*
X1271782Y38327D01*
G01X1273826Y38451D02*
X1273809Y38461D01*
G01X1273740Y38377D02*
X1273757Y38367D01*
G01X1273330Y38451D02*
X1273314Y38461D01*
G01X1272661Y38451D02*
X1272645Y38461D01*
G01X1272510Y38451D02*
X1272494Y38461D01*
G01X1272425Y38377D02*
X1272441Y38367D01*
G01X1272215Y38451D02*
X1272198Y38461D01*
G01X1272143Y38320D02*
X1272159Y38310D01*
G01X1271329Y38451D02*
X1271313Y38461D01*
G01X1271247Y38320D02*
X1271263Y38310D01*
G01X1274492Y38461D02*
X1274505Y38454D01*
G01X1274429Y38310D02*
X1274416Y38317D01*
G01X1273537Y38310D02*
X1273524Y38317D01*
G01X1273317Y38384D02*
X1273304Y38390D01*
G01X1273173Y38454D02*
X1273160Y38461D01*
G01X1273242Y38384D02*
X1273255Y38377D01*
G01X1272864Y38461D02*
X1272877Y38454D01*
G01X1272802Y38310D02*
X1272789Y38317D01*
G01X1272648Y38384D02*
X1272635Y38390D01*
G01X1272572Y38384D02*
X1272586Y38377D01*
G01X1272350Y38461D02*
X1272363Y38454D01*
G01X1272356Y38440D02*
X1272350Y38444D01*
G01X1272297Y38310D02*
X1272284Y38317D01*
G01X1271831Y38461D02*
X1271844Y38454D01*
G01X1271838Y38440D02*
X1271831Y38444D01*
G01X1271779Y38310D02*
X1271765Y38317D01*
G01X1271319Y38437D02*
X1271306Y38444D01*
G01X1271326Y38380D02*
X1271319Y38384D01*
G01X1271253Y38400D02*
X1271267Y38394D01*
G01X1271247Y38387D02*
X1271253Y38384D01*
G01X1272290D02*
X1272274Y38390D01*
G01X1271772Y38384D02*
X1271755Y38390D01*
G01X1274777Y38327D02*
X1274787Y38324D01*
G01X1273291Y38374D02*
X1273301Y38370D01*
G01X1273271Y38327D02*
X1273261Y38330D01*
G01X1272960Y38327D02*
X1272970Y38324D01*
G01X1272622Y38374D02*
X1272631Y38370D01*
G01X1272602Y38327D02*
X1272592Y38330D01*
G01X1271405Y38327D02*
X1271414Y38324D01*
G01X1274488Y38440D02*
X1274475Y38444D01*
G01X1274433Y38330D02*
X1274446Y38327D01*
G01X1273773Y38380D02*
X1273760Y38384D01*
G01X1273298Y38444D02*
X1273311Y38440D01*
G01X1273271Y38394D02*
X1273258Y38397D01*
G01X1272635Y38390D02*
X1272622Y38394D01*
G01X1272336Y38464D02*
X1272350Y38461D01*
G01X1272805Y38330D02*
X1272818Y38327D01*
G01X1272458Y38380D02*
X1272444Y38384D01*
G01X1271306Y38444D02*
X1271293Y38447D01*
G01X1271306Y38374D02*
X1271293Y38377D01*
G01X1273793Y38447D02*
X1273806Y38444D01*
G01X1273143D02*
X1273157Y38440D01*
G01X1273304Y38390D02*
X1273291Y38394D01*
G01X1272861Y38440D02*
X1272848Y38444D01*
G01X1272628D02*
X1272641Y38440D01*
G01X1272477Y38447D02*
X1272490Y38444D01*
G01X1272602Y38394D02*
X1272589Y38397D01*
G01X1271818Y38464D02*
X1271831Y38461D01*
G01X1271267Y38394D02*
X1271280Y38390D01*
G01X1271267Y38327D02*
X1271280Y38324D01*
G01X1274475Y38464D02*
X1274492Y38461D01*
G01X1274774Y38310D02*
X1274790Y38307D01*
G01X1273809Y38461D02*
X1273793Y38464D01*
G01X1274446Y38307D02*
X1274429Y38310D01*
G01X1273314Y38461D02*
X1273298Y38464D01*
G01X1273757Y38367D02*
X1273773Y38364D01*
G01X1273160Y38461D02*
X1273143Y38464D01*
G01X1273544Y38327D02*
X1273560Y38324D01*
G01X1272848Y38464D02*
X1272864Y38461D01*
G01X1273255Y38377D02*
X1273271Y38374D01*
G01X1272645Y38461D02*
X1272628Y38464D01*
G01X1273258Y38310D02*
X1273275Y38307D01*
G01X1272494Y38461D02*
X1272477Y38464D01*
G01X1272350Y38444D02*
X1272333Y38447D01*
G01X1272956Y38310D02*
X1272973Y38307D01*
G01X1272586Y38377D02*
X1272602Y38374D01*
G01X1272195Y38444D02*
X1272179Y38447D01*
G01X1272818Y38307D02*
X1272802Y38310D01*
G01X1272441Y38367D02*
X1272458Y38364D01*
G01X1272589Y38310D02*
X1272605Y38307D01*
G01X1271831Y38444D02*
X1271814Y38447D01*
G01X1272300Y38327D02*
X1272316Y38324D01*
G01X1272163Y38327D02*
X1272179Y38324D01*
G01X1271313Y38461D02*
X1271296Y38464D01*
G01X1271782Y38327D02*
X1271798Y38324D01*
G01X1271401Y38310D02*
X1271418Y38307D01*
G01X1271263Y38310D02*
X1271280Y38307D01*
G01X1273557D02*
X1273537Y38310D01*
G01X1272198Y38461D02*
X1272179Y38464D01*
G01X1272297Y38394D02*
X1272316Y38390D01*
G01X1271779Y38394D02*
X1271798Y38390D01*
G01X1272159Y38310D02*
X1272179Y38307D01*
G01X1272320D02*
X1272297Y38310D01*
G01X1271801Y38307D02*
X1271779Y38310D01*
G01X1267730Y38974D02*
X1267828D01*
G01X1268288D02*
X1268386D01*
G01X1280020Y38937D02*
X1280118D01*
G01X1279528D02*
X1279659D01*
G01X1267894Y38774D02*
X1268222D01*
G01X1267911Y38706D02*
X1268206D01*
G01X1273868Y38464D02*
X1273888D01*
G01X1274144D02*
X1274164D01*
G01X1274354D02*
X1274374D01*
G01X1274242D02*
X1274262D01*
G01X1274446D02*
X1274475D01*
G01X1274554D02*
X1274574D01*
G01X1274600D02*
X1274718D01*
G01X1274895D02*
X1275013D01*
G01X1275092D02*
X1275118D01*
G01X1275197D02*
X1275315D01*
G01X1271575D02*
X1271595D01*
G01X1271792D02*
X1271818D01*
G01X1271890D02*
X1271910D01*
G01X1272001D02*
X1272021D01*
G01X1272310D02*
X1272336D01*
G01X1272818D02*
X1272848D01*
G01X1273442D02*
X1273462D01*
G01X1273507D02*
X1273625D01*
G01X1271296D02*
X1271277D01*
G01X1271496D02*
X1271477D01*
G01X1271395D02*
X1271372D01*
G01X1272477D02*
X1272458D01*
G01X1272628D02*
X1272602D01*
G01X1273051D02*
X1273032D01*
G01X1272950D02*
X1272927D01*
G01X1273143D02*
X1273130D01*
G01X1273298D02*
X1273271D01*
G01X1273793D02*
X1273773D01*
G01X1274869D02*
X1274850D01*
G01X1274767D02*
X1274744D01*
G01X1273773Y38447D02*
X1273793D01*
G01X1272458D02*
X1272477D01*
G01X1271293D02*
X1271280D01*
G01X1271814D02*
X1271795D01*
G01X1272333D02*
X1272313D01*
G01X1273600D02*
X1273507D01*
G01X1272602Y38444D02*
X1272628D01*
G01X1273130D02*
X1273143D01*
G01X1273271D02*
X1273298D01*
G01X1272848D02*
X1272818D01*
G01X1274475D02*
X1274446D01*
G01X1274698D02*
X1274600D01*
G01X1274994D02*
X1274895D01*
G01X1275296D02*
X1275197D01*
G01X1271864Y38427D02*
X1271848D01*
G01X1272382D02*
X1272366D01*
G01X1273822Y38424D02*
X1273842D01*
G01X1271923D02*
X1271988D01*
G01X1272507D02*
X1272527D01*
G01X1272792D02*
X1272773D01*
G01X1272655Y38420D02*
X1272674D01*
G01X1273324D02*
X1273344D01*
G01X1271926Y38411D02*
X1271985D01*
G01X1271674Y38407D02*
X1271720D01*
G01X1272048D02*
X1272094D01*
G01X1272700D02*
X1272746D01*
G01X1273370D02*
X1273416D01*
G01X1273652D02*
X1273698D01*
G01X1274420Y38397D02*
X1274449D01*
G01X1271477Y38394D02*
X1271421D01*
G01X1272527D02*
X1272503D01*
G01X1272622D02*
X1272602D01*
G01X1273032D02*
X1272976D01*
G01X1273291D02*
X1273271D01*
G01X1273842D02*
X1273819D01*
G01X1274850D02*
X1274794D01*
G01X1274262Y38390D02*
X1274354D01*
G01X1274909D02*
X1274994D01*
G01X1275210D02*
X1275296D01*
G01X1271280D02*
X1271293D01*
G01X1271798D02*
X1271811D01*
G01X1272316D02*
X1272330D01*
G01X1271720D02*
X1271674D01*
G01X1272094D02*
X1272048D01*
G01X1272746D02*
X1272700D01*
G01X1273416D02*
X1273370D01*
G01X1273698D02*
X1273652D01*
G01X1272477Y38380D02*
X1272458D01*
G01X1273793D02*
X1273773D01*
G01X1271293Y38377D02*
X1271280D01*
G01X1271811D02*
X1271798D01*
G01X1272330D02*
X1272316D01*
G01X1274449D02*
X1274400D01*
G01X1272602Y38374D02*
X1272622D01*
G01X1273271D02*
X1273291D01*
G01X1271477D02*
X1271414D01*
G01X1273032D02*
X1272970D01*
G01X1274850D02*
X1274787D01*
G01X1274354Y38370D02*
X1274262D01*
G01X1274994D02*
X1274909D01*
G01X1275296D02*
X1275210D01*
G01X1273773Y38364D02*
X1273793D01*
G01X1272458D02*
X1272477D01*
G01X1274400Y38347D02*
X1274420D01*
G01X1272773D02*
X1272792D01*
G01X1271844Y38344D02*
X1271861D01*
G01X1272363D02*
X1272379D01*
G01X1273606D02*
X1273622D01*
G01X1272582D02*
X1272563D01*
G01X1273251D02*
X1273232D01*
G01X1274446Y38327D02*
X1274475D01*
G01X1274895D02*
X1274994D01*
G01X1275197D02*
X1275296D01*
G01X1272818D02*
X1272848D01*
G01X1272622D02*
X1272602D01*
G01X1273291D02*
X1273271D01*
G01X1274092Y38324D02*
X1274144D01*
G01X1274164D02*
X1274216D01*
G01X1274787D02*
X1274850D01*
G01X1271280D02*
X1271293D01*
G01X1271414D02*
X1271477D01*
G01X1271523D02*
X1271575D01*
G01X1271595D02*
X1271647D01*
G01X1271798D02*
X1271811D01*
G01X1272316D02*
X1272330D01*
G01X1272970D02*
X1273032D01*
G01X1273560D02*
X1273573D01*
G01X1272510D02*
X1272415D01*
G01X1273826D02*
X1273731D01*
G01Y38307D02*
X1273842D01*
G01X1274790D02*
X1274869D01*
G01X1271280D02*
X1271293D01*
G01X1271418D02*
X1271496D01*
G01X1272415D02*
X1272527D01*
G01X1272605D02*
X1272622D01*
G01X1272973D02*
X1273051D01*
G01X1273176D02*
X1273196D01*
G01X1273078D02*
X1273098D01*
G01X1273275D02*
X1273291D01*
G01X1271647D02*
X1271523D01*
G01X1271808D02*
X1271801D01*
G01X1271969D02*
X1271942D01*
G01X1272326D02*
X1272320D01*
G01X1272848D02*
X1272818D01*
G01X1273462D02*
X1273442D01*
G01X1273570D02*
X1273557D01*
G01X1273888D02*
X1273868D01*
G01X1274216D02*
X1274092D01*
G01X1274374D02*
X1274354D01*
G01X1274262D02*
X1274242D01*
G01X1274475D02*
X1274446D01*
G01X1274574D02*
X1274554D01*
G01X1274718D02*
X1274698D01*
G01X1275013D02*
X1274895D01*
G01X1275171D02*
X1275151D01*
G01X1275059D02*
X1275040D01*
G01X1275315D02*
X1275197D01*
G01X1268124Y38187D02*
X1267992D01*
G01X1280118Y38149D02*
X1280020D01*
G01X1279659D02*
X1279528D01*
G01X1267717Y35629D02*
X1280315D01*
G01X1271831Y38310D02*
X1271808Y38307D01*
G01X1272350Y38310D02*
X1272326Y38307D01*
G01X1273593Y38310D02*
X1273570Y38307D01*
G01X1272179Y38464D02*
X1272159Y38461D01*
G01X1272179Y38307D02*
X1272198Y38310D01*
G01X1271277Y38464D02*
X1271260Y38461D01*
G01X1271795Y38447D02*
X1271779Y38444D01*
G01X1271293Y38307D02*
X1271309Y38310D01*
G01X1272179Y38447D02*
X1272163Y38444D01*
G01X1272313Y38447D02*
X1272297Y38444D01*
G01X1272458Y38464D02*
X1272441Y38461D01*
G01X1271811Y38324D02*
X1271828Y38327D01*
G01X1272602Y38464D02*
X1272586Y38461D01*
G01X1272802D02*
X1272818Y38464D01*
G01X1272179Y38324D02*
X1272195Y38327D01*
G01X1272477Y38364D02*
X1272494Y38367D01*
G01X1272330Y38324D02*
X1272346Y38327D01*
G01X1273130Y38464D02*
X1273114Y38461D01*
G01X1273271Y38464D02*
X1273255Y38461D01*
G01X1272864Y38310D02*
X1272848Y38307D01*
G01X1273773Y38464D02*
X1273757Y38461D01*
G01X1273573Y38324D02*
X1273590Y38327D01*
G01X1273793Y38364D02*
X1273809Y38367D01*
G01X1274429Y38461D02*
X1274446Y38464D01*
G01X1274492Y38310D02*
X1274475Y38307D01*
G01X1271280Y38447D02*
X1271267Y38444D01*
G01X1271293Y38390D02*
X1271306Y38394D01*
G01X1271280Y38377D02*
X1271267Y38374D01*
G01X1271779Y38461D02*
X1271792Y38464D01*
G01X1271293Y38324D02*
X1271306Y38327D01*
G01X1272297Y38461D02*
X1272310Y38464D01*
G01X1272444Y38444D02*
X1272458Y38447D01*
G01X1272589Y38440D02*
X1272602Y38444D01*
G01X1272490Y38384D02*
X1272477Y38380D01*
G01X1272818Y38444D02*
X1272805Y38440D01*
G01X1273117D02*
X1273130Y38444D01*
G01X1272622Y38307D02*
X1272635Y38310D01*
G01X1273258Y38440D02*
X1273271Y38444D01*
G01X1272848Y38327D02*
X1272861Y38330D01*
G01X1273760Y38444D02*
X1273773Y38447D01*
G01X1273291Y38307D02*
X1273304Y38310D01*
G01X1273806Y38384D02*
X1273793Y38380D01*
G01X1274446Y38444D02*
X1274433Y38440D01*
G01X1274475Y38327D02*
X1274488Y38330D01*
G01X1280315Y41535D02*
X1267717D01*
G01X1271890Y310836D02*
G03X1269823Y311803I-1260J0D01*
G01X1273071Y303153D02*
G03X1277008Y307090I0J3937D01*
G01Y390948D02*
Y307090D01*
G01X1273071Y306653D02*
Y391377D01*
G01X1272284Y307440D02*
Y390590D01*
G01X1271890Y313389D02*
Y307440D01*
G01X1271103Y306653D02*
Y312004D01*
G01X1270343Y312559D02*
Y326181D01*
G01X1269786Y312559D02*
Y326181D01*
G01X1267976Y329527D02*
Y310590D01*
G01X1267420Y329527D02*
Y310590D01*
G01X1266863D02*
Y330118D01*
G01X1266533Y309059D02*
X1269823Y311803D01*
G01X1271890Y307440D02*
X1271103Y306653D01*
G01X1273071Y318503D02*
X1272284D01*
G01Y315998D02*
X1273071D01*
G01X1277008Y313389D02*
X1271890D01*
G01X1270343Y312559D02*
X1269786D01*
G01X1272284Y310826D02*
X1273071D01*
G01X1272284Y309566D02*
X1273071D01*
G01Y307677D02*
X1272284D01*
G01X1273071Y307598D02*
X1272284D01*
G01X1273071Y307440D02*
X1271890D01*
G01X1273071Y306653D02*
X1271103D01*
G01X1273016Y332411D02*
X1273057Y332223D01*
G01X1273016Y332414D02*
X1273057Y332223D01*
G01X1272264Y327677D02*
G03X1272284Y327657I20J0D01*
G01X1273032Y328665D02*
G03X1273071Y328576I118J-1D01*
G01X1272559Y328665D02*
G03X1273071Y328079I591J-1D01*
G01X1271693Y327677D02*
G03X1272284Y327087I591J1D01*
G01X1272559Y332208D02*
G03X1272549Y332318I-590J2D01*
G01X1273071Y332073D02*
G03X1273057Y332223I-787J2D01*
G01X1273071Y332073D02*
G03X1273057Y332223I-790J2D01*
G01X1273032Y332208D02*
G03X1273012Y332413I-1063J0D01*
G01X1271693Y331857D02*
G03X1271683Y331968I-591J3D01*
G01X1272264Y331857D02*
G03X1272244Y332074I-1162J2D01*
G01X1273032Y332208D02*
Y328665D01*
G01X1272559Y332208D02*
Y328665D01*
G01X1272264Y331857D02*
Y327677D01*
G01X1271693Y331857D02*
Y327677D01*
G01X1267284Y329645D02*
Y328897D01*
G01X1272244Y332074D02*
X1270682Y340282D01*
G01X1270122Y340176D02*
X1271683Y331968D01*
G01X1271607Y339680D02*
X1273016Y332411D01*
G01X1273057Y332223D02*
X1270074Y347568D01*
G01X1269301Y347418D02*
X1272284Y332073D01*
G01X1270684Y340290D02*
X1272284Y332073D01*
G01X1273013Y332411D02*
X1271557Y339485D01*
G01X1271094Y339390D02*
X1272549Y332318D01*
G01X1270343Y326181D02*
X1267976Y329527D01*
G01X1269786Y326181D02*
X1267420Y329527D01*
G01X1266392Y330393D02*
X1267284Y329645D01*
G01X1273071Y333648D02*
X1272284D01*
G01Y333321D02*
X1273071D01*
G01Y332583D02*
X1272284D01*
G01X1273032Y332208D02*
X1272559D01*
G01X1273071Y332073D02*
X1272284D01*
G01X1272264Y331857D02*
X1271693D01*
G01X1272284Y331784D02*
X1273071D01*
G01Y331195D02*
X1272284D01*
G01X1273071Y330511D02*
X1272284D01*
G01Y330458D02*
X1273071D01*
G01X1267420Y329527D02*
X1267976D01*
G01X1273032Y328665D02*
X1272559D01*
G01X1272264Y327677D02*
X1271693D01*
G01X1270343Y326181D02*
X1269786D01*
G01X1273071Y324803D02*
X1272284D01*
G01X1273071Y322563D02*
X1277008D01*
G01Y320673D02*
X1273071D01*
G01X1271683Y331968D02*
X1272244Y332074D01*
G01X1273057Y332223D02*
X1272284Y332073D01*
G01X1270961Y347862D02*
X1271063Y347863D01*
G01X1270776Y347855D02*
X1270961Y347862D01*
G01X1271621Y347916D02*
X1271750Y347976D01*
G01X1271504Y347879D02*
X1271621Y347916D01*
G01X1271394Y347859D02*
X1271504Y347879D01*
G01X1271283Y347854D02*
X1271394Y347859D01*
G01X1271063Y347863D02*
X1271283Y347854D01*
G01X1270579Y350062D02*
X1270568Y350002D01*
G01X1270604Y350116D02*
X1270579Y350062D01*
G01X1270638Y350159D02*
X1270604Y350116D01*
G01X1270667Y350192D02*
X1270638Y350159D01*
G01X1270700Y350234D02*
X1270667Y350192D01*
G01X1270745Y350276D02*
X1270700Y350234D01*
G01X1270800Y350296D02*
X1270745Y350276D01*
G01X1270858Y350297D02*
X1270800Y350296D01*
G01X1270918Y350285D02*
X1270858Y350297D01*
G01X1271433Y350237D02*
X1271331Y350149D01*
G01X1271553Y350276D02*
X1271433Y350237D01*
G01X1271672Y350250D02*
X1271553Y350276D01*
G01X1270242Y340656D02*
X1270145Y340482D01*
G01X1270391Y340788D02*
X1270242Y340656D01*
G01X1270575Y340863D02*
X1270391Y340788D01*
G01X1270694Y347857D02*
X1270776Y347855D01*
G01X1270620Y347875D02*
X1270694Y347857D01*
G01X1270566Y347920D02*
X1270620Y347875D01*
G01X1271214Y347990D02*
X1271205Y348020D01*
G01X1271225Y347966D02*
X1271214Y347990D01*
G01X1271238Y347945D02*
X1271225Y347966D01*
G01X1271253Y347929D02*
X1271238Y347945D01*
G01X1271926Y349600D02*
X1271851Y349666D01*
G01X1271974Y349497D02*
X1271926Y349600D01*
G01X1271996Y349385D02*
X1271974Y349497D01*
G01X1272011Y349262D02*
X1271996Y349385D01*
G01X1272043Y349132D02*
X1272011Y349262D01*
G01X1272093Y349006D02*
X1272043Y349132D01*
G01X1272128Y348879D02*
X1272093Y349006D01*
G01X1272142Y348736D02*
X1272128Y348879D01*
G01X1272138Y348572D02*
X1272142Y348736D01*
G01X1272103Y348400D02*
X1272138Y348572D01*
G01X1273071Y349606D02*
G03X1272677Y349212I0J-394D01*
G01Y348818D02*
G03X1273071Y348425I394J1D01*
G01X1272284Y350000D02*
G03X1271890Y349443I197J-557D01*
G01Y348588D02*
G03X1272284Y348031I591J0D01*
G01X1274646Y349015D02*
G03I-1968J0D01*
G01X1271246Y348818D02*
G03X1271639Y348425I394J1D01*
G01Y349606D02*
G03X1271246Y349212I1J-394D01*
G01X1270458Y348588D02*
G03X1270852Y348031I591J0D01*
G01Y350000D02*
G03X1270458Y349443I197J-557D01*
G01X1271607Y339680D02*
G03X1271557Y339485I174J-148D01*
G01X1270575Y340863D02*
G03X1270122Y340176I127J-577D01*
G01X1271511Y340178D02*
G03X1271094Y339390I269J-647D01*
G01X1273057Y365909D02*
X1270054Y350464D01*
G01X1272284Y366060D02*
X1269281Y350614D01*
G01X1270145Y340482D02*
X1270111Y340286D01*
G01X1273068Y350393D02*
Y347637D01*
G01X1272887Y348425D02*
Y347637D01*
G01Y350393D02*
Y349606D01*
G01X1272677Y349212D02*
Y348818D01*
G01X1272546D02*
Y349212D01*
G01X1272379Y347637D02*
Y350393D01*
G01X1272328Y347637D02*
Y350393D01*
G01X1272281D02*
Y347637D01*
G01X1272205Y348031D02*
Y347637D01*
G01Y350393D02*
Y350000D01*
G01X1271986Y347637D02*
Y350393D01*
G01X1271935Y347637D02*
Y350393D01*
G01X1271890Y348588D02*
Y349443D01*
G01X1271864Y348588D02*
Y349443D01*
G01X1271824Y350393D02*
Y349606D01*
G01Y348425D02*
Y347637D01*
G01X1271639Y349606D02*
Y350393D01*
G01Y347637D02*
Y348425D01*
G01X1271483Y348818D02*
Y349212D01*
G01X1271246D02*
Y348818D01*
G01X1271142Y348031D02*
Y347637D01*
G01Y350393D02*
Y350000D01*
G01X1270852Y347637D02*
Y348031D01*
G01Y350000D02*
Y350393D01*
G01X1270801Y348588D02*
Y349443D01*
G01X1270458Y348588D02*
Y349443D01*
G01X1270111Y340286D02*
X1270122Y340176D01*
G01X1270271Y351579D02*
X1269498Y351730D01*
G01X1270054Y350464D02*
X1269281Y350614D01*
G01X1272284Y351181D02*
X1273071D01*
G01Y350393D02*
X1270852D01*
G01X1272284Y350097D02*
X1273071D01*
G01X1270852Y350000D02*
X1272284D01*
G01X1273068Y349803D02*
X1272281D01*
G01X1273071Y349606D02*
X1271639D01*
G01X1271890Y349443D02*
X1270458D01*
G01X1271246Y349212D02*
X1272677D01*
G01Y348818D02*
X1271246D01*
G01X1270458Y348588D02*
X1271890D01*
G01X1271639Y348425D02*
X1273071D01*
G01X1273068Y348228D02*
X1272281D01*
G01X1272284Y348031D02*
X1270852D01*
G01X1273071Y347934D02*
X1272284D01*
G01X1273071Y347637D02*
X1270852D01*
G01X1273071Y346850D02*
X1272284D01*
G01X1273071Y345132D02*
X1272284D01*
G01Y344394D02*
X1273071D01*
G01X1272284Y344298D02*
X1273071D01*
G01X1272284Y342433D02*
X1273071D01*
G01Y342269D02*
X1272284D01*
G01X1270682Y340282D02*
X1270122Y340176D01*
G01X1270074Y347568D02*
X1269301Y347418D01*
G01X1270291Y346453D02*
X1269518Y346303D01*
G01X1271557Y339485D02*
X1271094Y339390D01*
G01X1271683Y366063D02*
G03X1271693Y366174I-581J108D01*
G01X1272549Y365713D02*
G03X1272559Y365823I-580J108D01*
G01X1273057Y365909D02*
G03X1273071Y366060I-773J148D01*
G01X1273057Y365909D02*
G03X1273071Y366060I-776J148D01*
G01X1273031Y365776D02*
G03X1273032Y365823I-1062J46D01*
G01X1272244Y365956D02*
G03X1272264Y366174I-1142J215D01*
G01X1271555Y358534D02*
G03X1271591Y358372I226J-35D01*
G01X1270122Y357855D02*
G03X1270556Y357172I580J-111D01*
G01X1271094Y358640D02*
G03X1271492Y357861I687J-140D01*
G01X1271557Y358545D02*
X1272797Y364574D01*
G01X1272549Y365713D02*
X1271094Y358640D01*
G01X1271324Y361124D02*
X1272244Y365956D01*
G01X1271683Y366063D02*
X1270122Y357855D01*
G01D02*
X1270111Y357744D01*
G01X1273032Y369366D02*
Y365823D01*
G01X1272559Y369366D02*
Y365823D01*
G01X1272264Y370353D02*
Y366174D01*
G01X1271693Y370353D02*
Y366174D01*
G01X1272797Y364574D02*
X1272335Y364669D01*
G01X1271094Y358640D02*
X1271557Y358545D01*
G01X1273057Y365909D02*
X1272284Y366060D01*
G01X1271683Y366063D02*
X1272244Y365956D01*
G01X1270669Y357751D02*
X1270122Y357855D01*
G01X1273071Y367573D02*
X1272284D01*
G01X1273071Y367519D02*
X1272284D01*
G01Y366835D02*
X1273071D01*
G01Y366246D02*
X1272284D01*
G01X1272264Y366174D02*
X1271693D01*
G01X1273071Y366060D02*
X1272284D01*
G01X1273032Y365823D02*
X1272559D01*
G01X1272284Y365447D02*
X1273071D01*
G01Y364710D02*
X1272284D01*
G01Y364383D02*
X1273071D01*
G01X1270668Y357744D02*
X1270111D01*
G01X1272284Y355762D02*
X1273071D01*
G01Y355598D02*
X1272284D01*
G01X1273071Y353733D02*
X1272284D01*
G01X1273071Y353636D02*
X1272284D01*
G01Y352899D02*
X1273071D01*
G01X1272284Y370373D02*
G03X1272264Y370353I0J-20D01*
G01X1273071Y369454D02*
G03X1273032Y369366I79J-88D01*
G01X1273071Y369952D02*
G03X1272559Y369366I79J-586D01*
G01X1272284Y370944D02*
G03X1271693Y370353I0J-591D01*
G01X1271890Y390590D02*
Y384649D01*
G01D02*
X1277008D01*
G01X1272284Y382033D02*
X1273071D01*
G01Y377759D02*
X1277008D01*
G01Y375476D02*
X1273071D01*
G01X1272264Y370353D02*
X1271693D01*
G01X1273032Y369366D02*
X1272559D01*
G01X1269823Y386227D02*
G03X1271890Y387195I807J967D01*
G01X1277008Y390948D02*
G03X1273071Y394885I-3937J0D01*
G01X1271103Y386027D02*
Y391377D01*
G01X1267234Y394964D02*
Y394885D01*
G01X1266718D02*
Y394964D01*
G01X1266403D02*
Y394885D01*
G01X1266285Y394964D02*
Y394885D01*
G01X1266047Y394964D02*
Y394885D01*
G01X1265988D02*
Y394964D01*
G01X1265928D02*
Y394885D01*
G01X1265750Y394964D02*
Y394885D01*
G01X1265631Y394964D02*
Y394885D01*
G01X1271890Y390590D02*
X1271103Y391377D01*
G01X1269823Y386227D02*
X1266533Y388972D01*
G01X1271103Y391377D02*
X1273071D01*
G01X1271890Y390590D02*
X1273071D01*
G01X1272284Y390433D02*
X1273071D01*
G01Y390354D02*
X1272284D01*
G01X1273071Y388464D02*
X1272284D01*
G01Y387204D02*
X1273071D01*
G01X1300788Y7086D02*
G03I-1575J0D01*
G01X1300985D02*
G03I-1772J0D01*
G01X1292771Y5641D02*
X1292688Y5578D01*
G01X1285204Y5641D02*
X1285122Y5578D01*
G01X1291417Y5683D02*
X1290905Y5222D01*
G01X1290741D02*
X1291315Y5746D01*
G01X1296421Y5704D02*
X1296462Y5746D01*
G01X1292668Y5704D02*
X1292709Y5746D01*
G01X1290782Y5955D02*
X1290864Y6039D01*
G01X1288895Y5181D02*
X1288977Y5264D01*
G01X1287972Y5181D02*
X1288055Y5264D01*
G01X1288424Y6039D02*
X1288342Y5955D01*
G01X1287501Y6039D02*
X1287419Y5955D01*
G01X1285102Y5704D02*
X1285143Y5746D01*
G01X1284015Y5264D02*
X1283933Y5181D01*
G01X1290453Y5934D02*
X1290331Y5788D01*
G01Y5955D02*
X1290453Y6102D01*
G01X1285266Y5725D02*
X1285204Y5641D01*
G01X1296523D02*
X1296585Y5725D01*
G01X1292832D02*
X1292771Y5641D01*
G01X1291458Y5746D02*
X1291417Y5683D01*
G01X1290905Y5934D02*
X1290864Y5872D01*
G01X1288895Y5369D02*
X1288854Y5306D01*
G01X1287972Y5369D02*
X1287931Y5306D01*
G01X1283933Y5369D02*
X1283892Y5306D01*
G01X1282874Y-7678D02*
X1283859Y-5973D01*
G01X1291315Y5746D02*
X1291356Y5830D01*
G01X1288977Y5264D02*
X1289018Y5348D01*
G01X1288055Y5264D02*
X1288096Y5348D01*
G01X1284056D02*
X1284015Y5264D01*
G01X1290044Y5892D02*
X1289757Y5118D01*
G01X1289674Y5222D02*
X1289982Y6102D01*
G01X1293878Y5243D02*
X1294165Y6102D01*
G01X1294288D02*
X1293960Y5118D01*
G01X1296585Y5725D02*
X1296605Y5788D01*
G01X1296462Y5746D02*
X1296482Y5809D01*
G01X1292853Y5788D02*
X1292832Y5725D01*
G01X1292709Y5746D02*
X1292730Y5809D01*
G01X1288444Y5851D02*
X1288464Y5913D01*
G01X1287521Y5851D02*
X1287542Y5913D01*
G01X1296441Y5599D02*
X1296523Y5641D01*
G01X1290864Y6039D02*
X1290946Y6081D01*
G01X1288813Y5139D02*
X1288895Y5181D01*
G01X1287890Y5139D02*
X1287972Y5181D01*
G01X1288505Y6081D02*
X1288424Y6039D01*
G01X1287583Y6081D02*
X1287501Y6039D01*
G01X1283933Y5181D02*
X1283851Y5139D01*
G01X1290966Y5976D02*
X1290905Y5934D01*
G01X1288854Y5306D02*
X1288793Y5264D01*
G01X1287931Y5306D02*
X1287870Y5264D01*
G01X1288464Y5913D02*
X1288526Y5955D01*
G01X1287542Y5913D02*
X1287603Y5955D01*
G01X1283892Y5306D02*
X1283830Y5264D01*
G01X1285286Y5788D02*
X1285266Y5725D01*
G01X1285143Y5746D02*
X1285163Y5809D01*
G01X1291479Y5830D02*
X1291458Y5746D01*
G01X1290761Y5872D02*
X1290782Y5955D01*
G01X1288342D02*
X1288321Y5872D01*
G01X1287419Y5955D02*
X1287398Y5872D01*
G01X1283953Y5453D02*
X1283933Y5369D01*
G01X1284076Y5453D02*
X1284056Y5348D01*
G01X1296359Y5683D02*
X1296421Y5704D01*
G01X1292607Y5683D02*
X1292668Y5704D01*
G01X1288526Y5955D02*
X1288588Y5976D01*
G01X1287603Y5955D02*
X1287665Y5976D01*
G01X1285040Y5683D02*
X1285102Y5704D01*
G01X1296605Y5788D02*
Y5872D01*
G01X1296482Y5809D02*
Y5872D01*
G01X1295970Y5118D02*
Y5557D01*
G01Y5997D02*
Y5683D01*
G01X1295846Y6102D02*
Y5118D01*
G01X1295683Y6102D02*
Y5997D01*
G01X1295354D02*
Y5118D01*
G01X1295231D02*
Y5997D01*
G01X1294903D02*
Y6102D01*
G01X1294739Y5578D02*
Y5474D01*
G01X1294452D02*
Y5578D01*
G01X1293701Y196D02*
Y4921D01*
G01X1293304Y5578D02*
Y5474D01*
G01X1293017D02*
Y5578D01*
G01X1292853Y5872D02*
Y5788D01*
G01X1292730Y5809D02*
Y5872D01*
G01X1292217Y5997D02*
Y5683D01*
G01Y5557D02*
Y5118D01*
G01X1292094D02*
Y6102D01*
G01X1291930Y5578D02*
Y5474D01*
G01X1291643D02*
Y5578D01*
G01X1291479Y5872D02*
Y5830D01*
G01Y5222D02*
Y5118D01*
G01X1291356Y5830D02*
Y5872D01*
G01X1290741Y5118D02*
Y5222D01*
G01X1290577Y6102D02*
Y5118D01*
G01X1290453D02*
Y5934D01*
G01X1290331Y5788D02*
Y5955D01*
G01X1290166Y6102D02*
Y5118D01*
G01X1290044D02*
Y5892D01*
G01X1289305D02*
Y5118D01*
G01X1289182D02*
Y6102D01*
G01X1289018Y5348D02*
Y5453D01*
G01X1288895Y5432D02*
Y5369D01*
G01X1288444Y5809D02*
Y5851D01*
G01X1288321Y5872D02*
Y5788D01*
G01X1288096Y5348D02*
Y5453D01*
G01X1287972Y5432D02*
Y5369D01*
G01X1287521Y5809D02*
Y5851D01*
G01X1287398Y5872D02*
Y5788D01*
G01X1287173Y5243D02*
Y5118D01*
G01X1286558Y6102D02*
Y5243D01*
G01X1286435Y5118D02*
Y6102D01*
G01X1285286Y5872D02*
Y5788D01*
G01X1285163Y5809D02*
Y5872D01*
G01X1284651Y5997D02*
Y5683D01*
G01Y5557D02*
Y5118D01*
G01X1284527D02*
Y6102D01*
G01X1284364D02*
Y5118D01*
G01X1284240D02*
Y6102D01*
G01X1284076Y5767D02*
Y5453D01*
G01X1283953Y5767D02*
Y5453D01*
G01X1283859Y-5973D02*
Y4921D01*
G01X1283465Y-6655D02*
Y4921D01*
G01X1283379Y5243D02*
Y5976D01*
G01X1283256Y5118D02*
Y6102D01*
G01X1284056Y5872D02*
X1284076Y5767D01*
G01X1291458Y5955D02*
X1291479Y5872D01*
G01X1288321Y5788D02*
X1288342Y5704D01*
G01X1288259Y5390D02*
X1288280Y5306D01*
G01X1287398Y5788D02*
X1287419Y5704D01*
G01X1287337Y5390D02*
X1287357Y5306D01*
G01X1283933Y5851D02*
X1283953Y5767D01*
G01X1296605Y5872D02*
X1296585Y5934D01*
G01X1296482Y5872D02*
X1296462Y5934D01*
G01X1292832D02*
X1292853Y5872D01*
G01X1292730D02*
X1292709Y5934D01*
G01X1288957Y5872D02*
X1288936Y5934D01*
G01X1288464Y5746D02*
X1288444Y5809D01*
G01X1288403Y5327D02*
X1288383Y5390D01*
G01X1288034Y5872D02*
X1288013Y5934D01*
G01X1287542Y5746D02*
X1287521Y5809D01*
G01X1287480Y5327D02*
X1287460Y5390D01*
G01X1285266Y5934D02*
X1285286Y5872D01*
G01X1285163D02*
X1285143Y5934D01*
G01X1293796Y5118D02*
X1293468Y6102D01*
G01X1293591D02*
X1293878Y5243D01*
G01X1289367Y6102D02*
X1289674Y5222D01*
G01X1289592Y5118D02*
X1289305Y5892D01*
G01X1296318Y5557D02*
X1296482Y5118D01*
G01X1296625D02*
X1296441Y5599D01*
G01X1288813Y5913D02*
X1288834Y5872D01*
G01X1289018Y5453D02*
X1288977Y5537D01*
G01X1287890Y5913D02*
X1287911Y5872D01*
G01X1288096Y5453D02*
X1288055Y5537D01*
G01X1284015Y5955D02*
X1284056Y5872D01*
G01X1281890Y-5973D02*
X1282874Y-7678D01*
G01X1288280Y5306D02*
X1288342Y5202D01*
G01X1287357Y5306D02*
X1287419Y5202D01*
G01X1291356Y5872D02*
X1291315Y5934D01*
G01X1288854Y5494D02*
X1288895Y5432D01*
G01X1287931Y5494D02*
X1287972Y5432D01*
G01X1283892Y5913D02*
X1283933Y5851D01*
G01X1296585Y5934D02*
X1296523Y6018D01*
G01X1292771D02*
X1292832Y5934D01*
G01X1288936D02*
X1288875Y6018D01*
G01X1288013Y5934D02*
X1287952Y6018D01*
G01X1285204D02*
X1285266Y5934D01*
G01X1296462D02*
X1296421Y5976D01*
G01X1292709Y5934D02*
X1292668Y5976D01*
G01X1291376Y6039D02*
X1291458Y5955D01*
G01X1288772D02*
X1288813Y5913D01*
G01X1288977Y5537D02*
X1288895Y5620D01*
G01X1288342Y5704D02*
X1288424Y5620D01*
G01X1287850Y5955D02*
X1287890Y5913D01*
G01X1288464Y5264D02*
X1288403Y5327D01*
G01X1288055Y5537D02*
X1287972Y5620D01*
G01X1287419Y5704D02*
X1287501Y5620D01*
G01X1287542Y5264D02*
X1287480Y5327D01*
G01X1285143Y5934D02*
X1285102Y5976D01*
G01X1283933Y6039D02*
X1284015Y5955D01*
G01X1296523Y6018D02*
X1296441Y6081D01*
G01X1292688D02*
X1292771Y6018D01*
G01X1288875D02*
X1288793Y6081D01*
G01X1287952Y6018D02*
X1287870Y6081D01*
G01X1285122D02*
X1285204Y6018D01*
G01X1291315Y5934D02*
X1291253Y5976D01*
G01X1288793Y5537D02*
X1288854Y5494D01*
G01X1288526Y5704D02*
X1288464Y5746D01*
G01X1287870Y5537D02*
X1287931Y5494D01*
G01X1287603Y5704D02*
X1287542Y5746D01*
G01X1283830Y5955D02*
X1283892Y5913D01*
G01X1288342Y5202D02*
X1288444Y5139D01*
G01X1287419Y5202D02*
X1287521Y5139D01*
G01X1291294Y6081D02*
X1291376Y6039D01*
G01X1288895Y5620D02*
X1288813Y5662D01*
G01X1288424Y5620D02*
X1288505Y5578D01*
G01X1287972Y5620D02*
X1287890Y5662D01*
G01X1287501Y5620D02*
X1287583Y5578D01*
G01X1283851Y6081D02*
X1283933Y6039D01*
G01X1296421Y5976D02*
X1296359Y5997D01*
G01X1292668Y5976D02*
X1292607Y5997D01*
G01X1288711Y5976D02*
X1288772Y5955D01*
G01X1287788Y5976D02*
X1287850Y5955D01*
G01X1288588Y5683D02*
X1288526Y5704D01*
G01X1287665Y5683D02*
X1287603Y5704D01*
G01X1285102Y5976D02*
X1285040Y5997D01*
G01X1288711Y5557D02*
X1288793Y5537D01*
G01X1288505Y5578D02*
X1288588Y5557D01*
G01X1287788D02*
X1287870Y5537D01*
G01X1287583Y5578D02*
X1287665Y5557D01*
G01X1288547Y5243D02*
X1288464Y5264D01*
G01X1287624Y5243D02*
X1287542Y5264D01*
G01X1283748Y5976D02*
X1283830Y5955D01*
G01X1296441Y6081D02*
X1296338Y6102D01*
G01X1292586D02*
X1292688Y6081D01*
G01X1291253Y5976D02*
X1291151Y5997D01*
G01X1288793Y6081D02*
X1288690Y6102D01*
G01X1287870Y6081D02*
X1287767Y6102D01*
G01X1288813Y5662D02*
X1288711Y5683D01*
G01X1287890Y5662D02*
X1287788Y5683D01*
G01X1285020Y6102D02*
X1285122Y6081D01*
G01X1283748Y6102D02*
X1283851Y6081D01*
G01X1288444Y5139D02*
X1288547Y5118D01*
G01X1287521Y5139D02*
X1287624Y5118D01*
G01X1291171Y6102D02*
X1291294Y6081D01*
G01X1294903Y6102D02*
X1295683D01*
G01X1293468D02*
X1293591D01*
G01X1294165D02*
X1294288D01*
G01X1292094D02*
X1292586D01*
G01X1291089D02*
X1291171D01*
G01X1290453D02*
X1290577D01*
G01X1289182D02*
X1289367D01*
G01X1289982D02*
X1290166D01*
G01X1286435D02*
X1286558D01*
G01X1284527D02*
X1285020D01*
G01X1284240D02*
X1284364D01*
G01X1283256D02*
X1283748D01*
G01X1287767D02*
X1287665D01*
G01X1288690D02*
X1288588D01*
G01X1296338D02*
X1295846D01*
G01X1285040Y5997D02*
X1284651D01*
G01X1292607D02*
X1292217D01*
G01X1291151D02*
X1291069D01*
G01X1296359D02*
X1295970D01*
G01X1295683D02*
X1295354D01*
G01X1295231D02*
X1294903D01*
G01X1288588Y5976D02*
X1288711D01*
G01X1287665D02*
X1287788D01*
G01X1283379D02*
X1283748D01*
G01X1288834Y5872D02*
X1288957D01*
G01X1287911D02*
X1288034D01*
G01X1290864D02*
X1290761D01*
G01X1295970Y5683D02*
X1296359D01*
G01X1292217D02*
X1292607D01*
G01X1284651D02*
X1285040D01*
G01X1287788D02*
X1287665D01*
G01X1288711D02*
X1288588D01*
G01X1294452Y5578D02*
X1294739D01*
G01X1293017D02*
X1293304D01*
G01X1291643D02*
X1291930D01*
G01X1295970Y5557D02*
X1296318D01*
G01X1288588D02*
X1288711D01*
G01X1287665D02*
X1287788D01*
G01X1285020D02*
X1284651D01*
G01X1292586D02*
X1292217D01*
G01X1291930Y5474D02*
X1291643D01*
G01X1294739D02*
X1294452D01*
G01X1293304D02*
X1293017D01*
G01X1287460Y5390D02*
X1287337D01*
G01X1288383D02*
X1288259D01*
G01X1286558Y5243D02*
X1287173D01*
G01X1287788D02*
X1287624D01*
G01X1283748D02*
X1283379D01*
G01X1288711D02*
X1288547D01*
G01X1290905Y5222D02*
X1291479D01*
G01X1295846Y5118D02*
X1295970D01*
G01X1296482D02*
X1296625D01*
G01X1288547D02*
X1288711D01*
G01X1287624D02*
X1287788D01*
G01X1287173D02*
X1286435D01*
G01X1284651D02*
X1284527D01*
G01X1284364D02*
X1284240D01*
G01X1283748D02*
X1283256D01*
G01X1292217D02*
X1292094D01*
G01X1291479D02*
X1290741D01*
G01X1290577D02*
X1290453D01*
G01X1289757D02*
X1289592D01*
G01X1289305D02*
X1289182D01*
G01X1290166D02*
X1290044D01*
G01X1295354D02*
X1295231D01*
G01X1293960D02*
X1293796D01*
G01X1290946Y6081D02*
X1291089Y6102D01*
G01X1285122Y5578D02*
X1285020Y5557D01*
G01X1283851Y5139D02*
X1283748Y5118D01*
G01X1291069Y5997D02*
X1290966Y5976D01*
G01X1287788Y5118D02*
X1287890Y5139D01*
G01X1288711Y5118D02*
X1288813Y5139D01*
G01X1292688Y5578D02*
X1292586Y5557D01*
G01X1283830Y5264D02*
X1283748Y5243D01*
G01X1287665Y6102D02*
X1287583Y6081D01*
G01X1288588Y6102D02*
X1288505Y6081D01*
G01X1287870Y5264D02*
X1287788Y5243D01*
G01X1288793Y5264D02*
X1288711Y5243D01*
G01X1296188Y17025D02*
X1296270Y17109D01*
G01X1296106Y17905D02*
X1296188Y17988D01*
G01X1295122Y18407D02*
X1295286Y18575D01*
G01X1296475Y17067D02*
X1296393Y16941D01*
G01X1296434Y17988D02*
X1296352Y17863D01*
G01X1295368Y18365D02*
X1295286Y18240D01*
G01X1296270Y17109D02*
X1296311Y17192D01*
G01X1296188Y17988D02*
X1296270Y18156D01*
G01X1296516Y17192D02*
X1296475Y17067D01*
G01X1296270Y16857D02*
X1296106Y16774D01*
G01Y16983D02*
X1296188Y17025D01*
G01X1295286Y18575D02*
X1295450Y18659D01*
G01X1296393Y16941D02*
X1296270Y16857D01*
G01X1295491Y18449D02*
X1295368Y18365D01*
G01X1296352Y17863D02*
X1296188Y17737D01*
G01X1296475Y18156D02*
X1296434Y17988D01*
G01X1295081Y18240D02*
X1295122Y18407D01*
G01X1295860Y17821D02*
X1296106Y17905D01*
G01X1298032Y22834D02*
Y12992D01*
G01X1296851Y21850D02*
Y13976D01*
G01X1296516Y17360D02*
Y17192D01*
G01X1296475Y18240D02*
Y18156D01*
G01X1296311Y17192D02*
Y17360D01*
G01X1296270Y18156D02*
Y18240D01*
G01X1295696Y17653D02*
Y17821D01*
G01X1294488Y13976D02*
Y21850D01*
G01X1293307Y12992D02*
Y22834D01*
G01X1288189D02*
Y12992D01*
G01X1287008Y21850D02*
Y13976D01*
G01X1284646D02*
Y21850D01*
G01X1283465Y12992D02*
Y22834D01*
G01X1296434Y18407D02*
X1296475Y18240D01*
G01Y17527D02*
X1296516Y17360D01*
G01X1295081Y17067D02*
X1295040Y17192D01*
G01X1296311Y17360D02*
X1296229Y17527D01*
G01X1295245Y17192D02*
X1295286Y17109D01*
G01X1296270Y18240D02*
X1296188Y18365D01*
G01X1296393Y17653D02*
X1296475Y17527D01*
G01X1295163Y16941D02*
X1295081Y17067D01*
G01X1296270Y18575D02*
X1296434Y18407D01*
G01X1295286Y17109D02*
X1295368Y17025D01*
G01X1296188Y18365D02*
X1296065Y18449D01*
G01X1296229Y17527D02*
X1296106Y17611D01*
G01X1295286Y16857D02*
X1295163Y16941D01*
G01X1296106Y18659D02*
X1296270Y18575D01*
G01X1295368Y17025D02*
X1295450Y16983D01*
G01Y16774D02*
X1295286Y16857D01*
G01X1296188Y17737D02*
X1296393Y17653D01*
G01X1295614Y16732D02*
X1295450Y16774D01*
G01X1296065Y18449D02*
X1295860Y18491D01*
G01X1295450Y16983D02*
X1295655Y16941D01*
G01X1296106Y17611D02*
X1295860Y17653D01*
G01X1295819Y18700D02*
X1296106Y18659D01*
G01X1293307Y22834D02*
X1298032D01*
G01X1283465D02*
X1288189D01*
G01X1287008Y21850D02*
X1284646D01*
G01X1296851D02*
X1294488D01*
G01X1295737Y18700D02*
X1295819D01*
G01X1295860Y18491D02*
X1295696D01*
G01X1295286Y18240D02*
X1295081D01*
G01X1295696Y17821D02*
X1295860D01*
G01Y17653D02*
X1295696D01*
G01X1295040Y17192D02*
X1295245D01*
G01X1295655Y16941D02*
X1295901D01*
G01X1295942Y16732D02*
X1295614D01*
G01X1288189Y12992D02*
X1283465D01*
G01X1298032D02*
X1293307D01*
G01X1295450Y18659D02*
X1295737Y18700D01*
G01X1295696Y18491D02*
X1295491Y18449D01*
G01X1295901Y16941D02*
X1296106Y16983D01*
G01Y16774D02*
X1295942Y16732D01*
G01X1284646Y65894D02*
Y284398D01*
G01X1329922Y65894D02*
X1284646D01*
G01X1329922Y109202D02*
X1284646D01*
G01Y241091D02*
X1329922D01*
G01X1284646Y284398D02*
X1329922D01*
G01X1294626Y331709D02*
Y326181D01*
G01Y337992D02*
Y333217D01*
G01X1293150Y326181D02*
Y337992D01*
G01X1294626Y333217D02*
X1301516D01*
G01Y331709D02*
X1294626D01*
G01Y326181D02*
X1293150D01*
G01Y337992D02*
X1294626D01*
G01X1286221Y425196D02*
Y397637D01*
G01X1304528Y13976D02*
Y196D01*
G01X1308114Y65894D02*
X1329922Y87702D01*
G01X1311418Y87548D02*
G03I-6300J0D01*
G01X1311181Y151279D02*
Y149803D01*
G01X1305653Y158169D02*
Y151279D01*
G01X1304145D02*
Y158169D01*
G01X1299370Y149803D02*
Y151279D01*
G01X1305653D02*
X1311181D01*
G01X1299370D02*
X1304145D01*
G01X1311181Y149803D02*
X1299370D01*
G01X1309171Y169980D02*
X1309674Y170718D01*
G01X1310176Y169242D02*
X1310930Y170472D01*
G01X1309674Y170718D02*
X1309925Y171948D01*
G01X1310930Y170472D02*
X1311181Y171948D01*
G01X1309422Y168503D02*
X1310176Y169242D01*
G01X1311181Y159645D02*
Y158169D01*
G01X1307161Y165551D02*
Y161614D01*
G01X1306155D02*
Y165551D01*
G01X1304145D02*
Y161614D01*
G01X1303140D02*
Y165551D01*
G01X1299370Y158169D02*
Y159645D01*
G01Y171948D02*
X1299622Y170472D01*
G01X1300627Y171948D02*
X1300878Y170718D01*
G01X1307663Y168996D02*
X1309171Y169980D01*
G01X1308417Y168011D02*
X1309422Y168503D01*
G01X1307663Y167765D02*
X1308417Y168011D01*
G01X1299622Y170472D02*
X1300375Y169242D01*
G01X1300878Y170718D02*
X1301381Y169980D01*
G01X1300375Y169242D02*
X1301129Y168503D01*
G01X1301381Y169980D02*
X1302888Y168996D01*
G01X1301129Y168503D02*
X1302135Y168011D01*
G01D02*
X1302888Y167765D01*
G01D02*
X1304145Y167519D01*
G01X1302888Y168996D02*
X1304396Y168750D01*
G01D02*
X1306155D01*
G01X1304145Y167519D02*
X1306407D01*
G01X1306155Y165551D02*
X1307161D01*
G01X1303140D02*
X1304145D01*
G01X1307161Y161614D02*
X1306155D01*
G01X1304145D02*
X1303140D01*
G01X1299370Y159645D02*
X1311181D01*
G01X1304145Y158169D02*
X1299370D01*
G01X1311181D02*
X1305653D01*
G01X1306155Y168750D02*
X1307663Y168996D01*
G01X1306407Y167519D02*
X1307663Y167765D01*
G01X1301381Y173917D02*
X1300878Y173179D01*
G01X1300375Y174655D02*
X1299622Y173425D01*
G01X1304396Y181791D02*
X1304145Y181299D01*
G01X1304396Y185728D02*
X1304145Y185236D01*
G01X1303140Y181791D02*
X1303391Y182529D01*
G01X1303140Y185728D02*
X1303391Y186466D01*
G01X1300878Y173179D02*
X1300627Y171948D01*
G01X1299622Y173425D02*
X1299370Y171948D01*
G01X1301129Y175393D02*
X1300375Y174655D01*
G01X1304648Y182037D02*
X1304396Y181791D01*
G01X1303391Y182529D02*
X1304145Y183267D01*
G01X1304648Y185974D02*
X1304396Y185728D01*
G01X1303391Y186466D02*
X1303894Y186958D01*
G01X1311181Y179576D02*
Y178346D01*
G01Y183513D02*
Y182283D01*
G01Y187450D02*
Y186220D01*
G01X1304145Y181299D02*
Y180807D01*
G01Y185236D02*
Y184498D01*
G01X1303140Y184744D02*
Y185728D01*
G01Y178346D02*
Y179576D01*
G01Y180807D02*
Y181791D01*
G01X1311181Y171948D02*
X1310930Y173425D01*
G01X1309925Y171948D02*
X1309674Y173179D01*
G01X1302888Y174901D02*
X1301381Y173917D01*
G01X1303391Y184005D02*
X1303140Y184744D01*
G01X1304145Y180807D02*
X1304396Y180068D01*
G01X1303391D02*
X1303140Y180807D01*
G01X1303894Y186958D02*
X1305150Y187450D01*
G01X1302135Y175885D02*
X1301129Y175393D01*
G01X1305150Y182283D02*
X1304648Y182037D01*
G01X1305150Y186220D02*
X1304648Y185974D01*
G01X1304145Y184498D02*
X1304396Y184005D01*
G01X1310930Y173425D02*
X1310176Y174655D01*
G01X1302888Y176131D02*
X1302135Y175885D01*
G01X1309674Y173179D02*
X1309171Y173917D01*
G01X1304396Y184005D02*
X1304648Y183759D01*
G01X1304145Y183267D02*
X1303391Y184005D01*
G01X1310176Y174655D02*
X1309422Y175393D01*
G01X1304396Y180068D02*
X1304899Y179576D01*
G01X1303894D02*
X1303391Y180068D01*
G01X1309171Y173917D02*
X1307663Y174901D01*
G01X1304648Y183759D02*
X1305150Y183513D01*
G01X1309422Y175393D02*
X1308417Y175885D01*
G01D02*
X1307663Y176131D01*
G01D02*
X1306407Y176377D01*
G01X1307663Y174901D02*
X1306155Y175147D01*
G01X1305150Y187450D02*
X1311181D01*
G01Y186220D02*
X1305150D01*
G01Y183513D02*
X1311181D01*
G01Y182283D02*
X1305150D01*
G01X1303140Y179576D02*
X1303894D01*
G01X1304899D02*
X1311181D01*
G01Y178346D02*
X1303140D01*
G01X1306407Y176377D02*
X1304145D01*
G01X1306155Y175147D02*
X1304396D01*
G01D02*
X1302888Y174901D01*
G01X1304145Y176377D02*
X1302888Y176131D01*
G01X1304396Y192864D02*
X1304145Y192372D01*
G01X1304396Y196801D02*
X1304145Y196309D01*
G01X1303140Y192864D02*
X1303391Y193602D01*
G01X1303140Y196801D02*
X1303391Y197539D01*
G01X1304648Y193110D02*
X1304396Y192864D01*
G01X1303391Y193602D02*
X1304145Y194340D01*
G01X1304648Y197047D02*
X1304396Y196801D01*
G01X1303391Y197539D02*
X1303894Y198031D01*
G01X1311181Y190649D02*
Y189419D01*
G01Y194586D02*
Y193356D01*
G01Y198523D02*
Y197293D01*
G01X1304145Y196309D02*
Y195570D01*
G01Y192372D02*
Y191879D01*
G01X1303140Y195816D02*
Y196801D01*
G01Y191879D02*
Y192864D01*
G01Y189419D02*
Y190649D01*
G01X1303391Y195078D02*
X1303140Y195816D01*
G01X1304145Y191879D02*
X1304396Y191141D01*
G01X1303391D02*
X1303140Y191879D01*
G01X1305150Y193356D02*
X1304648Y193110D01*
G01X1305150Y197293D02*
X1304648Y197047D01*
G01X1304145Y195570D02*
X1304396Y195078D01*
G01X1303894Y198031D02*
X1305150Y198523D01*
G01X1304396Y195078D02*
X1304648Y194832D01*
G01X1304145Y194340D02*
X1303391Y195078D01*
G01X1304396Y191141D02*
X1304899Y190649D01*
G01X1303894D02*
X1303391Y191141D01*
G01X1304648Y194832D02*
X1305150Y194586D01*
G01Y198523D02*
X1311181D01*
G01Y197293D02*
X1305150D01*
G01Y194586D02*
X1311181D01*
G01Y193356D02*
X1305150D01*
G01X1303140Y190649D02*
X1303894D01*
G01X1304899D02*
X1311181D01*
G01Y189419D02*
X1303140D01*
G01X1311418Y262745D02*
G03I-6300J0D01*
G01X1313819Y337992D02*
Y326181D01*
G01X1312343D02*
Y335981D01*
G01X1310866Y334222D02*
Y336233D01*
G01X1308898Y331207D02*
Y330202D01*
G01Y334222D02*
Y333217D01*
G01X1304961D02*
Y334222D01*
G01Y330202D02*
Y331207D01*
G01X1302992Y337992D02*
Y326181D01*
G01X1301516Y333217D02*
Y337992D01*
G01Y326181D02*
Y331709D01*
G01X1312343Y335981D02*
X1310866Y334222D01*
G01X1304961D02*
X1308898D01*
G01Y333217D02*
X1304961D01*
G01Y331207D02*
X1308898D01*
G01Y330202D02*
X1304961D01*
G01X1302992Y326181D02*
X1301516D01*
G01X1313819D02*
X1312343D01*
G01X1310866Y336233D02*
X1312343Y337992D01*
G01D02*
X1313819D01*
G01X1301516D02*
X1302992D01*
G01X1332914Y-1575D02*
X1330945Y-3544D01*
G01X1329370Y14960D02*
Y-3544D01*
G01Y4527D02*
X1332914D01*
G01X1329370Y-1575D02*
X1333898D01*
G01X1329370Y-3544D02*
X1394922D01*
G01Y14960D02*
X1329370D01*
G01X1329922Y284398D02*
Y65894D01*
G01X1324646Y334725D02*
X1324400Y333720D01*
G01X1330551Y326181D02*
Y332212D01*
G01X1327845Y334222D02*
Y333468D01*
G01Y332463D02*
Y326181D01*
G01X1326614D02*
Y334222D01*
G01X1324400Y336233D02*
X1324646Y335227D01*
G01X1324400Y333720D02*
X1323908Y332966D01*
G01X1317756Y335981D02*
X1317264Y335227D01*
G01X1322677Y333720D02*
X1323170Y334725D01*
G01X1316034Y335227D02*
X1316280Y336233D01*
G01X1324646Y327437D02*
Y326181D01*
G01Y335227D02*
Y334725D01*
G01X1323170D02*
Y335227D01*
G01X1315788Y326181D02*
Y327437D01*
G01X1330551Y332212D02*
X1330305Y332715D01*
G01X1328337Y332966D02*
X1327845Y332463D01*
G01Y333468D02*
X1328337Y333971D01*
G01X1323170Y335227D02*
X1322677Y335981D01*
G01X1323908Y332966D02*
X1317756Y327437D01*
G01X1315788D02*
X1322677Y333720D01*
G01X1330798Y333971D02*
X1331536Y333217D01*
G01X1330305Y332715D02*
X1330059Y332966D01*
G01X1329075Y333217D02*
X1328337Y332966D01*
G01Y333971D02*
X1329075Y334222D01*
G01X1330059Y332966D02*
X1329567Y333217D01*
G01X1330059Y334222D02*
X1330798Y333971D01*
G01X1317264Y335227D02*
X1316034D01*
G01X1326614Y334222D02*
X1327845D01*
G01X1329075D02*
X1330059D01*
G01X1329567Y333217D02*
X1329075D01*
G01X1317756Y327437D02*
X1324646D01*
G01Y326181D02*
X1315788D01*
G01X1327845D02*
X1326614D01*
G01X1331782D02*
X1330551D01*
G01X1316280Y336233D02*
X1317264Y337238D01*
G01X1323416D02*
X1324400Y336233D01*
G01X1318494Y336484D02*
X1317756Y335981D01*
G01X1317264Y337238D02*
X1318248Y337740D01*
G01X1322677Y335981D02*
X1321939Y336484D01*
G01X1322431Y337740D02*
X1323416Y337238D01*
G01X1321939Y336484D02*
X1320709Y336735D01*
G01X1320955Y337992D02*
X1322431Y337740D01*
G01X1319971Y337992D02*
X1320955D01*
G01X1320709Y336735D02*
X1319725D01*
G01X1318248Y337740D02*
X1319971Y337992D01*
G01X1319725Y336735D02*
X1318494Y336484D01*
G01X1354801Y996063D02*
X1325399D01*
G01X1354801D02*
X1325399D01*
G01Y1023622D02*
X1385001D01*
G01X1325399D02*
X1385001D01*
G01X1346988Y-1969D02*
X1347382Y-193D01*
G01X1339114Y-1969D02*
X1339508Y-193D01*
G01X1347382Y-2560D02*
Y12204D01*
G01X1345414D02*
Y-2560D01*
G01X1341674Y14960D02*
Y6692D01*
G01X1339508Y12204D02*
Y-193D01*
G01X1339469Y12204D02*
Y-3544D01*
G01X1337579Y-2560D02*
Y12204D01*
G01X1337540Y-193D02*
Y12204D01*
G01X1333898D02*
Y-2560D01*
G01X1332914Y12204D02*
Y-1575D01*
G01X1345414Y-193D02*
X1345807Y-1969D01*
G01X1337540Y-193D02*
X1337933Y-1969D01*
G01X1339469Y6692D02*
X1353327D01*
G01Y5708D02*
X1339469D01*
G01X1353327Y5315D02*
X1339469D01*
G01X1339508Y-193D02*
X1337540D01*
G01X1347382D02*
X1345414D01*
G01Y-1575D02*
X1347382D01*
G01X1339469D02*
X1337579D01*
G01X1339114Y-1969D02*
X1337933D01*
G01X1346988D02*
X1345807D01*
G01X1347382Y-2560D02*
X1361162D01*
G01X1333898D02*
X1345414D01*
G01X1339469Y-2862D02*
X1353327D01*
G01X1337562Y20045D02*
G03X1336792Y20669I-770J-163D01*
G01X1340256D02*
G03X1339486Y20045I0J-787D01*
G01X1348130Y20669D02*
G03X1347360Y20045I0J-787D01*
G01X1345436D02*
G03X1344666Y20669I-770J-163D01*
G01X1346988Y22244D02*
X1347382Y22637D01*
G01X1345807Y21063D02*
X1345414Y20669D01*
G01X1339114Y22244D02*
X1339508Y22637D01*
G01X1337933Y21063D02*
X1337540Y20669D01*
G01X1347382Y30511D02*
Y20127D01*
G01X1346988Y21063D02*
Y22244D01*
G01X1345807D02*
Y21063D01*
G01X1345414Y20127D02*
Y30511D01*
G01X1343248Y21653D02*
Y15748D01*
G01X1341674Y21653D02*
Y15748D01*
G01X1339508Y30511D02*
Y20127D01*
G01X1339114Y21063D02*
Y22244D01*
G01X1337933D02*
Y21063D01*
G01X1337540Y20127D02*
Y30511D01*
G01X1335374Y21653D02*
Y15748D01*
G01X1332618Y21653D02*
Y14960D01*
G01X1345807Y22244D02*
X1345414Y22637D01*
G01X1347382Y20669D02*
X1346988Y21063D01*
G01X1337933Y22244D02*
X1337540Y22637D01*
G01X1339508Y20669D02*
X1339114Y21063D01*
G01X1339508Y22637D02*
X1337540D01*
G01X1347382D02*
X1345414D01*
G01X1339114Y22244D02*
X1337933D01*
G01X1346988D02*
X1345807D01*
G01X1335374Y21653D02*
X1332618D01*
G01X1343248D02*
X1341674D01*
G01X1345807Y21063D02*
X1346988D01*
G01X1337933D02*
X1339114D01*
G01X1341674Y20669D02*
X1335374D01*
G01X1349548D02*
X1343248D01*
G01X1339508Y20127D02*
X1337540D01*
G01X1347382D02*
X1345414D01*
G01X1339486Y20045D02*
X1337562D01*
G01X1347360D02*
X1345436D01*
G01X1341674Y19962D02*
X1335374D01*
G01X1349548D02*
X1343248D01*
G01X1341674Y15748D02*
X1335374D01*
G01X1349548D02*
X1343248D01*
G01X1391378Y12204D02*
X1332914D01*
G01X1346988Y30118D02*
X1347382Y30511D01*
G01X1345807Y28937D02*
X1345414Y28543D01*
G01X1339114Y30118D02*
X1339508Y30511D01*
G01X1337933Y28937D02*
X1337540Y28543D01*
G01X1346988Y28937D02*
Y30118D01*
G01X1345807D02*
Y28937D01*
G01X1339114D02*
Y30118D01*
G01X1337933D02*
Y28937D01*
G01X1345807Y30118D02*
X1345414Y30511D01*
G01X1347382Y28543D02*
X1346988Y28937D01*
G01X1337933Y30118D02*
X1337540Y30511D01*
G01X1339508Y28543D02*
X1339114Y28937D01*
G01X1339508Y30511D02*
X1337540D01*
G01X1347382D02*
X1345414D01*
G01X1339114Y30118D02*
X1337933D01*
G01X1346988D02*
X1345807D01*
G01Y28937D02*
X1346988D01*
G01X1337933D02*
X1339114D01*
G01X1339508Y28543D02*
X1337540D01*
G01X1347382D02*
X1345414D01*
G01X1339508Y27559D02*
X1337540D01*
G01X1347382D02*
X1345414D01*
G01X1339475Y238582D02*
Y125984D01*
G01D02*
X1400000D01*
G01X1339475Y229657D02*
X1348400Y238582D01*
G01X1386457D02*
X1339475D01*
G01X1346792Y332212D02*
Y326181D01*
G01X1345561D02*
Y332212D01*
G01X1342855D02*
Y326181D01*
G01X1341624D02*
Y332212D01*
G01X1338918Y334222D02*
Y333468D01*
G01Y332463D02*
Y326181D01*
G01X1337687D02*
Y334222D01*
G01X1335719Y332212D02*
Y326181D01*
G01X1334488D02*
Y332212D01*
G01X1331782D02*
Y326181D01*
G01X1346300Y333468D02*
X1346792Y332212D01*
G01X1343101Y332715D02*
X1342855Y332212D01*
G01X1332028Y332715D02*
X1331782Y332212D01*
G01X1335227Y333468D02*
X1335719Y332212D01*
G01X1345561D02*
X1345315Y332715D01*
G01X1341624Y332212D02*
X1341378Y332715D01*
G01X1334488Y332212D02*
X1334242Y332715D01*
G01X1343347Y332966D02*
X1343101Y332715D01*
G01X1342609Y333217D02*
X1343347Y333971D01*
G01X1339410Y332966D02*
X1338918Y332463D01*
G01Y333468D02*
X1339410Y333971D01*
G01X1332274Y332966D02*
X1332028Y332715D01*
G01X1331536Y333217D02*
X1332274Y333971D01*
G01X1345807D02*
X1346300Y333468D01*
G01X1345315Y332715D02*
X1345069Y332966D01*
G01X1341870Y333971D02*
X1342609Y333217D01*
G01X1341378Y332715D02*
X1341132Y332966D01*
G01X1334735Y333971D02*
X1335227Y333468D01*
G01X1334242Y332715D02*
X1333996Y332966D01*
G01X1343839Y333217D02*
X1343347Y332966D01*
G01X1332766Y333217D02*
X1332274Y332966D01*
G01X1343347Y333971D02*
X1344085Y334222D01*
G01X1340148Y333217D02*
X1339410Y332966D01*
G01Y333971D02*
X1340148Y334222D01*
G01X1332274Y333971D02*
X1333012Y334222D01*
G01X1345069Y332966D02*
X1344577Y333217D01*
G01X1341132Y332966D02*
X1340640Y333217D01*
G01X1333996Y332966D02*
X1333504Y333217D01*
G01X1345069Y334222D02*
X1345807Y333971D01*
G01X1341132Y334222D02*
X1341870Y333971D01*
G01X1333996Y334222D02*
X1334735Y333971D01*
G01X1344085Y334222D02*
X1345069D01*
G01X1340148D02*
X1341132D01*
G01X1337687D02*
X1338918D01*
G01X1333012D02*
X1333996D01*
G01X1333504Y333217D02*
X1332766D01*
G01X1344577D02*
X1343839D01*
G01X1340640D02*
X1340148D01*
G01X1335719Y326181D02*
X1334488D01*
G01X1338918D02*
X1337687D01*
G01X1342855D02*
X1341624D01*
G01X1346792D02*
X1345561D01*
G01X1355453Y-3544D02*
G03X1357422Y-1575I0J1969D01*
G01X1362737Y-1969D02*
X1363130Y-193D01*
G01X1354863Y-1969D02*
X1355256Y-193D01*
G01X1363130Y12204D02*
Y-2560D01*
G01X1361162D02*
Y12204D01*
G01X1357422D02*
Y-1575D01*
G01X1355256Y12204D02*
Y-193D01*
G01X1355217Y-2560D02*
Y12204D01*
G01X1353327Y-3544D02*
Y12204D01*
G01X1353288Y-193D02*
Y12204D01*
G01X1351122Y6692D02*
Y14960D01*
G01X1361162Y-193D02*
X1361555Y-1969D01*
G01X1353288Y-193D02*
X1353681Y-1969D01*
G01X1355256Y-193D02*
X1353288D01*
G01X1363130D02*
X1361162D01*
G01Y-1575D02*
X1363130D01*
G01X1355217D02*
X1353327D01*
G01X1354863Y-1969D02*
X1353681D01*
G01X1362737D02*
X1361555D01*
G01X1363130Y-2560D02*
X1376910D01*
G01X1356004Y20669D02*
G03X1355234Y20045I0J-787D01*
G01X1353310D02*
G03X1352540Y20669I-770J-163D01*
G01X1363878D02*
G03X1363108Y20045I0J-787D01*
G01X1361184D02*
G03X1360414Y20669I-770J-163D01*
G01X1362737Y22244D02*
X1363130Y22637D01*
G01X1361555Y21063D02*
X1361162Y20669D01*
G01X1354863Y22244D02*
X1355256Y22637D01*
G01X1353681Y21063D02*
X1353288Y20669D01*
G01X1363130Y30511D02*
Y20127D01*
G01X1362737Y21063D02*
Y22244D01*
G01X1361555D02*
Y21063D01*
G01X1361162Y20127D02*
Y30511D01*
G01X1358996Y21653D02*
Y15748D01*
G01X1357422Y21653D02*
Y15748D01*
G01X1355256Y30511D02*
Y20127D01*
G01X1354863Y21063D02*
Y22244D01*
G01X1353681D02*
Y21063D01*
G01X1353288Y20127D02*
Y30511D01*
G01X1351122Y21653D02*
Y15748D01*
G01X1349548Y21653D02*
Y15748D01*
G01X1361555Y22244D02*
X1361162Y22637D01*
G01X1363130Y20669D02*
X1362737Y21063D01*
G01X1353681Y22244D02*
X1353288Y22637D01*
G01X1355256Y20669D02*
X1354863Y21063D01*
G01X1355256Y22637D02*
X1353288D01*
G01X1363130D02*
X1361162D01*
G01X1354863Y22244D02*
X1353681D01*
G01X1362737D02*
X1361555D01*
G01X1351122Y21653D02*
X1349548D01*
G01X1358996D02*
X1357422D01*
G01X1361555Y21063D02*
X1362737D01*
G01X1353681D02*
X1354863D01*
G01X1357422Y20669D02*
X1351122D01*
G01X1365296D02*
X1358996D01*
G01X1355256Y20127D02*
X1353288D01*
G01X1363130D02*
X1361162D01*
G01X1355234Y20045D02*
X1353310D01*
G01X1363108D02*
X1361184D01*
G01X1357422Y19962D02*
X1351122D01*
G01X1365296D02*
X1358996D01*
G01X1357422Y15748D02*
X1351122D01*
G01X1365296D02*
X1358996D01*
G01X1362737Y30118D02*
X1363130Y30511D01*
G01X1361555Y28937D02*
X1361162Y28543D01*
G01X1354863Y30118D02*
X1355256Y30511D01*
G01X1353681Y28937D02*
X1353288Y28543D01*
G01X1362737Y28937D02*
Y30118D01*
G01X1361555D02*
Y28937D01*
G01X1354863D02*
Y30118D01*
G01X1353681D02*
Y28937D01*
G01X1361555Y30118D02*
X1361162Y30511D01*
G01X1363130Y28543D02*
X1362737Y28937D01*
G01X1353681Y30118D02*
X1353288Y30511D01*
G01X1355256Y28543D02*
X1354863Y28937D01*
G01X1355256Y30511D02*
X1353288D01*
G01X1363130D02*
X1361162D01*
G01X1354863Y30118D02*
X1353681D01*
G01X1362737D02*
X1361555D01*
G01Y28937D02*
X1362737D01*
G01X1353681D02*
X1354863D01*
G01X1355256Y28543D02*
X1353288D01*
G01X1363130D02*
X1361162D01*
G01X1355256Y27559D02*
X1353288D01*
G01X1363130D02*
X1361162D01*
G01X1359213Y154409D02*
Y155885D01*
G01X1371024Y154409D02*
X1359213D01*
G01X1362983Y166220D02*
Y170157D01*
G01X1359213Y162775D02*
Y164252D01*
G01X1362983Y170157D02*
X1363988D01*
G01Y166220D02*
X1362983D01*
G01X1359213Y164252D02*
X1371024D01*
G01X1363988Y162775D02*
X1359213D01*
G01Y155885D02*
X1363988D01*
G01X1360218Y179261D02*
X1359464Y178031D01*
G01X1362983Y186397D02*
X1363234Y187135D01*
G01X1360721Y177785D02*
X1360470Y176555D01*
G01X1359464Y178031D02*
X1359213Y176555D01*
G01X1360972Y180000D02*
X1360218Y179261D01*
G01X1363234Y187135D02*
X1363988Y187874D01*
G01X1361223Y178523D02*
X1360721Y177785D01*
G01X1362983Y182952D02*
Y184183D01*
G01Y185413D02*
Y186397D01*
G01X1359213Y176555D02*
X1359464Y175078D01*
G01X1360470Y176555D02*
X1360721Y175324D01*
G01X1362731Y179507D02*
X1361223Y178523D01*
G01X1363234Y184675D02*
X1362983Y185413D01*
G01X1361977Y180492D02*
X1360972Y180000D01*
G01X1359464Y175078D02*
X1360218Y173848D01*
G01X1360721Y175324D02*
X1361223Y174586D01*
G01X1362731Y180738D02*
X1361977Y180492D01*
G01X1363736Y184183D02*
X1363234Y184675D01*
G01X1360218Y173848D02*
X1360972Y173110D01*
G01X1361223Y174586D02*
X1362731Y173602D01*
G01X1360972Y173110D02*
X1361977Y172618D01*
G01D02*
X1362731Y172372D01*
G01D02*
X1363988Y172126D01*
G01X1362731Y173602D02*
X1364239Y173356D01*
G01X1362983Y184183D02*
X1363736D01*
G01X1371024Y182952D02*
X1362983D01*
G01X1364239Y179753D02*
X1362731Y179507D01*
G01X1363988Y180984D02*
X1362731Y180738D01*
G01X1362983Y190334D02*
X1363234Y191072D01*
G01X1362983Y197470D02*
X1363234Y198208D01*
G01X1362983Y201407D02*
X1363234Y202145D01*
G01Y191072D02*
X1363736Y191565D01*
G01X1363234Y198208D02*
X1363988Y198946D01*
G01X1362983Y200423D02*
Y201407D01*
G01Y196486D02*
Y197470D01*
G01Y194025D02*
Y195255D01*
G01Y189350D02*
Y190334D01*
G01X1363234Y202145D02*
X1363736Y202637D01*
G01X1363234Y199685D02*
X1362983Y200423D01*
G01X1363234Y195748D02*
X1362983Y196486D01*
G01X1363234Y188612D02*
X1362983Y189350D01*
G01X1363736Y191565D02*
X1364993Y192057D01*
G01X1363736Y202637D02*
X1364993Y203129D01*
G01X1363988Y198946D02*
X1363234Y199685D01*
G01X1363736Y195255D02*
X1363234Y195748D01*
G01X1363988Y187874D02*
X1363234Y188612D01*
G01X1362983Y195255D02*
X1363736D01*
G01X1371024Y194025D02*
X1362983D01*
G01X1354801Y988189D02*
G03Y996063I0J3937D01*
G01Y988189D02*
G03Y996063I0J3937D01*
G01X1380316Y-7874D02*
G03Y0I0J3937D01*
G01Y-7874D02*
G03Y0I0J3937D01*
G01X1366870Y-1575D02*
G03X1368839Y-3544I1969J0D01*
G01X1378485Y-1969D02*
X1378878Y-193D01*
G01X1370611Y-1969D02*
X1371004Y-193D01*
G01X1378878Y12204D02*
Y-2560D01*
G01X1376910Y12204D02*
Y-2560D01*
G01X1373170Y14960D02*
Y6692D01*
G01X1371004Y12204D02*
Y-193D01*
G01X1370965Y12204D02*
Y-3544D01*
G01X1369075Y-2560D02*
Y12204D01*
G01X1369036Y-193D02*
Y12204D01*
G01X1366870D02*
Y-1575D01*
G01X1376910Y-193D02*
X1377303Y-1969D01*
G01X1369036Y-193D02*
X1369429Y-1969D01*
G01X1384823Y6692D02*
X1370965D01*
G01Y5708D02*
X1384823D01*
G01X1370965Y5315D02*
X1384823D01*
G01X1371004Y-193D02*
X1369036D01*
G01X1378878D02*
X1376910D01*
G01Y-1575D02*
X1378878D01*
G01X1370965D02*
X1369075D01*
G01X1370611Y-1969D02*
X1369429D01*
G01X1378485D02*
X1377303D01*
G01X1378878Y-2560D02*
X1390394D01*
G01X1370965Y-2862D02*
X1384823D01*
G01X1371752Y20669D02*
G03X1370982Y20045I0J-787D01*
G01X1369058D02*
G03X1368288Y20669I-770J-163D01*
G01X1379626D02*
G03X1378856Y20045I0J-787D01*
G01X1376932D02*
G03X1376162Y20669I-770J-163D01*
G01X1378485Y22244D02*
X1378878Y22637D01*
G01X1377303Y21063D02*
X1376910Y20669D01*
G01X1370611Y22244D02*
X1371004Y22637D01*
G01X1369429Y21063D02*
X1369036Y20669D01*
G01X1378878Y30511D02*
Y20127D01*
G01X1378485Y21063D02*
Y22244D01*
G01X1377303D02*
Y21063D01*
G01X1376910Y20127D02*
Y30511D01*
G01X1374744Y21653D02*
Y15748D01*
G01X1373170Y21653D02*
Y15748D01*
G01X1371004Y30511D02*
Y20127D01*
G01X1370611Y21063D02*
Y22244D01*
G01X1369429D02*
Y21063D01*
G01X1369036Y20127D02*
Y30511D01*
G01X1366870Y21653D02*
Y15748D01*
G01X1365296Y21653D02*
Y15748D01*
G01X1377303Y22244D02*
X1376910Y22637D01*
G01X1378878Y20669D02*
X1378485Y21063D01*
G01X1369429Y22244D02*
X1369036Y22637D01*
G01X1371004Y20669D02*
X1370611Y21063D01*
G01X1371004Y22637D02*
X1369036D01*
G01X1378878D02*
X1376910D01*
G01X1370611Y22244D02*
X1369429D01*
G01X1378485D02*
X1377303D01*
G01X1366870Y21653D02*
X1365296D01*
G01X1374744D02*
X1373170D01*
G01X1377303Y21063D02*
X1378485D01*
G01X1369429D02*
X1370611D01*
G01X1373170Y20669D02*
X1366870D01*
G01X1381044D02*
X1374744D01*
G01X1371004Y20127D02*
X1369036D01*
G01X1378878D02*
X1376910D01*
G01X1370982Y20045D02*
X1369058D01*
G01X1378856D02*
X1376932D01*
G01X1373170Y19962D02*
X1366870D01*
G01X1381044D02*
X1374744D01*
G01X1373170Y15748D02*
X1366870D01*
G01X1381044D02*
X1374744D01*
G01X1367658Y40551D02*
G03X1369233Y38976I1575J0D01*
G01X1378485Y30118D02*
X1378878Y30511D01*
G01X1377303Y28937D02*
X1376910Y28543D01*
G01X1370611Y30118D02*
X1371004Y30511D01*
G01X1369429Y28937D02*
X1369036Y28543D01*
G01X1374115Y40157D02*
X1373957Y39566D01*
G01X1378485Y28937D02*
Y30118D01*
G01X1377303D02*
Y28937D01*
G01X1373957Y44488D02*
Y39763D01*
G01X1370611Y28937D02*
Y30118D01*
G01X1369823Y45275D02*
Y39763D01*
G01X1369429Y30118D02*
Y28937D01*
G01X1368248Y45275D02*
Y39566D01*
G01X1377303Y30118D02*
X1376910Y30511D01*
G01X1378878Y28543D02*
X1378485Y28937D01*
G01X1369429Y30118D02*
X1369036Y30511D01*
G01X1371004Y28543D02*
X1370611Y28937D01*
G01X1389902Y39763D02*
X1369823D01*
G01X1373957Y39566D02*
X1368248D01*
G01X1390492Y38976D02*
X1369233D01*
G01X1371004Y30511D02*
X1369036D01*
G01X1378878D02*
X1376910D01*
G01X1370611Y30118D02*
X1369429D01*
G01X1378485D02*
X1377303D01*
G01Y28937D02*
X1378485D01*
G01X1369429D02*
X1370611D01*
G01X1371004Y28543D02*
X1369036D01*
G01X1378878D02*
X1376910D01*
G01X1371004Y27559D02*
X1369036D01*
G01X1378878D02*
X1376910D01*
G01X1385346Y51181D02*
G03I-5483J0D01*
G01X1386133D02*
G03I-6270J0D01*
G01X1386752D02*
G03I-6889J0D01*
G01X1387146D02*
G03I-7283J0D01*
G01X1371890Y42716D02*
G03I-492J0D01*
G01X1373071D02*
G03I-1673J0D01*
G01X1373170D02*
G03I-1772J0D01*
G01X1379416Y41020D02*
X1379154Y40752D01*
G01Y41355D02*
X1379023Y41154D01*
G01X1379548Y41288D02*
X1379416Y41020D01*
G01X1379220Y41623D02*
X1379154Y41355D01*
G01X1379023Y41154D02*
X1378826Y41020D01*
G01X1376102Y47814D02*
X1376713Y48425D01*
G01X1369015Y47814D02*
X1369626Y48425D01*
G01X1373170Y53937D02*
X1373781Y54548D01*
G01X1379613Y41623D02*
X1379548Y41288D01*
G01X1379154Y40752D02*
X1378891Y40618D01*
G01X1368750Y41611D02*
X1367725Y40944D01*
G01X1367658Y41611D02*
X1366633Y40944D01*
G01X1380138Y40551D02*
Y43700D01*
G01X1379613Y42628D02*
Y41623D01*
G01X1379220Y42628D02*
Y41623D01*
G01X1377382Y40953D02*
Y43298D01*
G01X1376988Y40551D02*
Y43700D01*
G01X1376713Y53937D02*
Y48425D01*
G01X1376102Y47814D02*
Y54548D01*
G01X1373781D02*
Y47814D01*
G01X1373170Y48425D02*
Y53937D01*
G01X1369626D02*
Y48425D01*
G01X1369015Y47814D02*
Y54548D01*
G01X1368839Y56928D02*
Y45433D01*
G01X1368750Y41611D02*
Y43700D01*
G01X1368445Y57086D02*
Y45275D01*
G01X1367658Y61811D02*
Y40551D01*
G01X1367138Y43700D02*
Y40944D01*
G01X1366942D02*
Y43700D01*
G01X1366124Y40944D02*
Y43700D01*
G01X1366110D02*
Y40944D01*
G01X1366109Y43700D02*
Y40944D01*
G01X1365766D02*
Y43700D01*
G01X1365032Y40944D02*
Y43700D01*
G01X1364935D02*
Y40944D01*
G01X1364928Y43700D02*
Y40944D01*
G01X1379548Y42963D02*
X1379613Y42628D01*
G01X1379154Y42896D02*
X1379220Y42628D01*
G01X1379416Y43231D02*
X1379548Y42963D01*
G01X1379023Y43097D02*
X1379154Y42896D01*
G01X1379416Y43231D02*
X1379154Y43499D01*
G01X1376102Y54548D02*
X1376713Y53937D01*
G01X1369015Y54548D02*
X1369626Y53937D01*
G01X1373781Y47814D02*
X1373170Y48425D01*
G01X1378826Y43231D02*
X1379023Y43097D01*
G01X1378891Y43633D02*
X1379154Y43499D01*
G01X1378826Y43231D02*
X1378563Y43298D01*
G01X1378891Y43633D02*
X1378563Y43700D01*
G01X1391280Y55118D02*
X1368445D01*
G01X1376102Y54548D02*
X1383623D01*
G01X1369015D02*
X1373781D01*
G01X1373170Y53937D02*
X1369626D01*
G01X1383012D02*
X1376713D01*
G01Y48425D02*
X1383012D01*
G01X1369626D02*
X1373170D01*
G01X1373781Y47814D02*
X1369015D01*
G01X1383623D02*
X1376102D01*
G01X1391280Y47244D02*
X1368445D01*
G01X1369823Y45275D02*
X1368445D01*
G01X1385768Y44488D02*
X1373957D01*
G01X1376988Y43700D02*
X1378563D01*
G01X1380138D02*
X1380532D01*
G01X1364928D02*
X1368750D01*
G01X1377382Y43298D02*
X1378563D01*
G01X1367658Y41611D02*
X1368750D01*
G01X1378563Y40953D02*
X1377382D01*
G01X1364928Y40944D02*
X1367725D01*
G01X1378563Y40551D02*
X1376988D01*
G01X1380532D02*
X1380138D01*
G01X1385610Y40157D02*
X1374115D01*
G01X1378891Y40618D02*
X1378563Y40551D01*
G01X1378826Y41020D02*
X1378563Y40953D01*
G01X1368248Y45275D02*
X1368839Y45433D01*
G01X1377243Y62401D02*
Y62204D01*
G01X1371890Y59645D02*
G03I-492J0D01*
G01X1369233Y63385D02*
G03X1367658Y61811I0J-1575D01*
G01X1373071Y59645D02*
G03I-1673J0D01*
G01X1373170D02*
G03I-1772J0D01*
G01X1377593Y59789D02*
X1377536Y59722D01*
G01X1377215Y60828D02*
X1377159Y60761D01*
G01X1377706Y59722D02*
X1377631Y59588D01*
G01X1377121Y60962D02*
X1377045Y60828D01*
G01X1377159Y60761D02*
X1377121Y60661D01*
G01X1377045Y60828D02*
X1377007Y60694D01*
G01X1377631Y59588D02*
X1377555Y59521D01*
G01X1377196Y61029D02*
X1377121Y60962D01*
G01X1379160Y60861D02*
X1378895Y59488D01*
G01X1379084Y61063D02*
X1378782Y59488D01*
G01X1378631Y61063D02*
X1378329Y59488D01*
G01X1378424Y60526D02*
X1378253Y59622D01*
G01X1378518Y61063D02*
X1378442Y60661D01*
G01X1377612Y59890D02*
X1377593Y59789D01*
G01X1377121Y60661D02*
X1377102Y60526D01*
G01X1377725Y59890D02*
X1377706Y59722D01*
G01X1377007Y60694D02*
X1376988Y60526D01*
G01X1377706Y60828D02*
X1377725Y60661D01*
G01X1376988Y60024D02*
X1377007Y59856D01*
G01X1377241Y62204D02*
X1377244Y62401D01*
G01X1377102Y60526D02*
Y60024D01*
G01X1376988D02*
Y60526D01*
G01X1373957Y62598D02*
Y57874D01*
G01X1369823Y62598D02*
Y57086D01*
G01X1368750Y58661D02*
Y60750D01*
G01X1368248Y62795D02*
Y57086D01*
G01X1367138Y61417D02*
Y58661D01*
G01X1366942D02*
Y61417D01*
G01X1366124Y58661D02*
Y61417D01*
G01X1366110D02*
Y58661D01*
G01X1366109Y61417D02*
Y58661D01*
G01X1365766D02*
Y61417D01*
G01X1365032Y58661D02*
Y61417D01*
G01X1364935D02*
Y58661D01*
G01X1364928Y61417D02*
Y58661D01*
G01X1377102Y60024D02*
X1377121Y59890D01*
G01X1377989Y61063D02*
X1378064Y60661D01*
G01X1378083Y60526D02*
X1378253Y59622D01*
G01X1377593Y60761D02*
X1377612Y60661D01*
G01X1379235Y61063D02*
X1379537Y59488D01*
G01X1377876Y61063D02*
X1378178Y59488D01*
G01X1379160Y60861D02*
X1379424Y59488D01*
G01X1377555Y59521D02*
X1377461Y59488D01*
G01X1377290Y61063D02*
X1377196Y61029D01*
G01X1377536Y59722D02*
X1377461Y59689D01*
G01X1377290Y60861D02*
X1377215Y60828D01*
G01X1373957Y62795D02*
X1374115Y62204D01*
G01X1377045Y59722D02*
X1377007Y59856D01*
G01X1377121Y59890D02*
X1377159Y59789D01*
G01X1377631Y60962D02*
X1377706Y60828D01*
G01X1377045Y59722D02*
X1377121Y59588D01*
G01X1377593Y60761D02*
X1377536Y60828D01*
G01X1377215Y59722D02*
X1377159Y59789D01*
G01X1377555Y61029D02*
X1377631Y60962D01*
G01X1377121Y59588D02*
X1377196Y59521D01*
G01X1367725Y61417D02*
X1368750Y60750D01*
G01X1366633Y61417D02*
X1367658Y60750D01*
G01X1377536Y60828D02*
X1377461Y60861D01*
G01X1377215Y59722D02*
X1377290Y59689D01*
G01X1377555Y61029D02*
X1377461Y61063D01*
G01X1377196Y59521D02*
X1377290Y59488D01*
G01X1368839Y56928D02*
X1368248Y57086D01*
G01X1390492Y63385D02*
X1369233D01*
G01X1373957Y62795D02*
X1368248D01*
G01X1389902Y62598D02*
X1369823D01*
G01X1382483Y62401D02*
X1377243D01*
G01X1377241Y62204D02*
X1374115D01*
G01X1364928Y61417D02*
X1367725D01*
G01X1377290Y61063D02*
X1377461D01*
G01X1377876D02*
X1377989D01*
G01X1378518D02*
X1378631D01*
G01X1379084D02*
X1379235D01*
G01X1377461Y60861D02*
X1377290D01*
G01X1367658Y60750D02*
X1368750D01*
G01X1378064Y60661D02*
X1378442D01*
G01X1377725D02*
X1377612D01*
G01X1378083Y60526D02*
X1378424D01*
G01X1377612Y59890D02*
X1377725D01*
G01X1377290Y59689D02*
X1377461D01*
G01Y59488D02*
X1377290D01*
G01X1378329D02*
X1378178D01*
G01X1379537D02*
X1379424D01*
G01X1378895D02*
X1378782D01*
G01X1364928Y58661D02*
X1368750D01*
G01X1385768Y57874D02*
X1373957D01*
G01X1369823Y57086D02*
X1368445D01*
G01X1385604Y87401D02*
G03I-5741J0D01*
G01X1386391D02*
G03I-6528J0D01*
G01X1386752D02*
G03I-6889J0D01*
G01X1387146D02*
G03I-7283J0D01*
G01X1371890Y78937D02*
G03I-492J0D01*
G01X1367658Y76771D02*
G03X1369233Y75196I1575J0D01*
G01X1373071Y78937D02*
G03I-1673J0D01*
G01X1373170D02*
G03I-1772J0D01*
G01X1379154Y77576D02*
X1379023Y77374D01*
G01X1379548Y77508D02*
X1379416Y77240D01*
G01X1376102Y84034D02*
X1376713Y84645D01*
G01X1369015Y84034D02*
X1369626Y84645D01*
G01X1379416Y77240D02*
X1379154Y76972D01*
G01X1374115Y76377D02*
X1373957Y75787D01*
G01X1379220Y77843D02*
X1379154Y77576D01*
G01X1379613Y77843D02*
X1379548Y77508D01*
G01X1368750Y77832D02*
X1367725Y77165D01*
G01X1367658Y77832D02*
X1366633Y77165D01*
G01X1379023Y77374D02*
X1378826Y77240D01*
G01X1380138Y76771D02*
Y79921D01*
G01X1379613Y78849D02*
Y77843D01*
G01X1379220Y78849D02*
Y77843D01*
G01X1377382Y77173D02*
Y79519D01*
G01X1376988Y76771D02*
Y79921D01*
G01X1376713Y90157D02*
Y84645D01*
G01X1376102Y84034D02*
Y90768D01*
G01X1373957Y80708D02*
Y75984D01*
G01X1373781Y90768D02*
Y84034D01*
G01X1373170Y84645D02*
Y90157D01*
G01X1369823Y81496D02*
Y75984D01*
G01X1369626Y90157D02*
Y84645D01*
G01X1369015Y84034D02*
Y90768D01*
G01X1368839Y93148D02*
Y81654D01*
G01X1368750Y77832D02*
Y79921D01*
G01X1368445Y93307D02*
Y81496D01*
G01X1368248D02*
Y75787D01*
G01X1367658Y98031D02*
Y76771D01*
G01X1367138Y79921D02*
Y77165D01*
G01X1366942D02*
Y79921D01*
G01X1366124Y77165D02*
Y79921D01*
G01X1366110D02*
Y77165D01*
G01X1366109Y79921D02*
Y77165D01*
G01X1365766D02*
Y79921D01*
G01X1365032Y77165D02*
Y79921D01*
G01X1364935D02*
Y77165D01*
G01X1364928Y79921D02*
Y77165D01*
G01X1379548Y79184D02*
X1379613Y78849D01*
G01X1379154Y79116D02*
X1379220Y78849D01*
G01X1379154Y76972D02*
X1378891Y76838D01*
G01X1379416Y79452D02*
X1379548Y79184D01*
G01X1379023Y79318D02*
X1379154Y79116D01*
G01X1379416Y79452D02*
X1379154Y79720D01*
G01X1373781Y84034D02*
X1373170Y84645D01*
G01X1379023Y79318D02*
X1378826Y79452D01*
G01X1378891Y79854D02*
X1379154Y79720D01*
G01X1378826Y79452D02*
X1378563Y79519D01*
G01X1378891Y79854D02*
X1378563Y79921D01*
G01X1376713Y84645D02*
X1383012D01*
G01X1369626D02*
X1373170D01*
G01X1373781Y84034D02*
X1369015D01*
G01X1383623D02*
X1376102D01*
G01X1391280Y83464D02*
X1368445D01*
G01X1369823Y81496D02*
X1368445D01*
G01X1385768Y80708D02*
X1373957D01*
G01X1376988Y79921D02*
X1378563D01*
G01X1380138D02*
X1380532D01*
G01X1364928D02*
X1368750D01*
G01X1377382Y79519D02*
X1378563D01*
G01X1367658Y77832D02*
X1368750D01*
G01X1378563Y77173D02*
X1377382D01*
G01X1364928Y77165D02*
X1367725D01*
G01X1378563Y76771D02*
X1376988D01*
G01X1380532D02*
X1380138D01*
G01X1385610Y76377D02*
X1374115D01*
G01X1389902Y75984D02*
X1369823D01*
G01X1373957Y75787D02*
X1368248D01*
G01X1390492Y75196D02*
X1369233D01*
G01X1378891Y76838D02*
X1378563Y76771D01*
G01X1378826Y77240D02*
X1378563Y77173D01*
G01X1368248Y81496D02*
X1368839Y81654D01*
G01X1377243Y98622D02*
Y98425D01*
G01X1371890Y95866D02*
G03I-492J0D01*
G01X1369233Y99606D02*
G03X1367658Y98031I0J-1575D01*
G01X1373071Y95866D02*
G03I-1673J0D01*
G01X1373170D02*
G03I-1772J0D01*
G01X1377706Y95943D02*
X1377631Y95809D01*
G01X1377121Y97183D02*
X1377045Y97048D01*
G01X1377159Y96981D02*
X1377121Y96881D01*
G01X1377631Y95809D02*
X1377555Y95742D01*
G01X1377196Y97250D02*
X1377121Y97183D01*
G01X1373170Y90157D02*
X1373781Y90768D01*
G01X1377593Y96010D02*
X1377536Y95943D01*
G01X1377215Y97048D02*
X1377159Y96981D01*
G01X1377045Y97048D02*
X1377007Y96915D01*
G01X1379160Y97082D02*
X1378895Y95708D01*
G01X1379084Y97283D02*
X1378782Y95708D01*
G01X1378631Y97283D02*
X1378329Y95708D01*
G01X1378424Y96747D02*
X1378253Y95842D01*
G01X1378518Y97283D02*
X1378442Y96881D01*
G01X1377612Y96110D02*
X1377593Y96010D01*
G01X1377121Y96881D02*
X1377102Y96747D01*
G01X1377725Y96110D02*
X1377706Y95943D01*
G01X1377007Y96915D02*
X1376988Y96747D01*
G01X1377706Y97048D02*
X1377725Y96881D01*
G01X1376988Y96244D02*
X1377007Y96077D01*
G01X1377241Y98425D02*
X1377244Y98622D01*
G01X1377102Y96747D02*
Y96244D01*
G01X1376988D02*
Y96747D01*
G01X1373957Y98818D02*
Y94094D01*
G01X1369823Y98818D02*
Y93307D01*
G01X1368750Y94881D02*
Y96970D01*
G01X1368248Y99015D02*
Y93307D01*
G01X1367138Y97637D02*
Y94881D01*
G01X1366942D02*
Y97637D01*
G01X1366124Y94881D02*
Y97637D01*
G01X1366110D02*
Y94881D01*
G01X1366109Y97637D02*
Y94881D01*
G01X1365766D02*
Y97637D01*
G01X1365032Y94881D02*
Y97637D01*
G01X1364935D02*
Y94881D01*
G01X1364928Y97637D02*
Y94881D01*
G01X1377102Y96244D02*
X1377121Y96110D01*
G01X1377989Y97283D02*
X1378064Y96881D01*
G01X1378083Y96747D02*
X1378253Y95842D01*
G01X1377593Y96981D02*
X1377612Y96881D01*
G01X1379235Y97283D02*
X1379537Y95708D01*
G01X1377876Y97283D02*
X1378178Y95708D01*
G01X1379160Y97082D02*
X1379424Y95708D01*
G01X1373957Y99015D02*
X1374115Y98425D01*
G01X1377536Y95943D02*
X1377461Y95909D01*
G01X1377290Y97082D02*
X1377215Y97048D01*
G01X1377007Y96077D02*
X1377045Y95943D01*
G01X1377121Y96110D02*
X1377159Y96010D01*
G01X1377461Y95708D02*
X1377555Y95742D01*
G01X1377290Y97283D02*
X1377196Y97250D01*
G01X1377631Y97183D02*
X1377706Y97048D01*
G01X1377045Y95943D02*
X1377121Y95809D01*
G01X1377593Y96981D02*
X1377536Y97048D01*
G01X1377215Y95943D02*
X1377159Y96010D01*
G01X1376102Y90768D02*
X1376713Y90157D01*
G01X1369015Y90768D02*
X1369626Y90157D01*
G01X1377555Y97250D02*
X1377631Y97183D01*
G01X1377121Y95809D02*
X1377196Y95742D01*
G01X1367725Y97637D02*
X1368750Y96970D01*
G01X1366633Y97637D02*
X1367658Y96970D01*
G01X1377536Y97048D02*
X1377461Y97082D01*
G01X1377215Y95943D02*
X1377290Y95909D01*
G01X1377555Y97250D02*
X1377461Y97283D01*
G01X1377196Y95742D02*
X1377290Y95708D01*
G01X1368839Y93148D02*
X1368248Y93307D01*
G01X1390492Y99606D02*
X1369233D01*
G01X1373957Y99015D02*
X1368248D01*
G01X1389902Y98818D02*
X1369823D01*
G01X1382483Y98622D02*
X1377243D01*
G01X1377241Y98425D02*
X1374115D01*
G01X1364928Y97637D02*
X1367725D01*
G01X1377290Y97283D02*
X1377461D01*
G01X1377876D02*
X1377989D01*
G01X1378518D02*
X1378631D01*
G01X1379084D02*
X1379235D01*
G01X1377461Y97082D02*
X1377290D01*
G01X1367658Y96970D02*
X1368750D01*
G01X1378064Y96881D02*
X1378442D01*
G01X1377725D02*
X1377612D01*
G01X1378083Y96747D02*
X1378424D01*
G01X1377612Y96110D02*
X1377725D01*
G01X1377290Y95909D02*
X1377461D01*
G01Y95708D02*
X1377290D01*
G01X1378329D02*
X1378178D01*
G01X1379537D02*
X1379424D01*
G01X1378895D02*
X1378782D01*
G01X1364928Y94881D02*
X1368750D01*
G01X1385768Y94094D02*
X1373957D01*
G01X1369823Y93307D02*
X1368445D01*
G01X1391280Y91338D02*
X1368445D01*
G01X1376102Y90768D02*
X1383623D01*
G01X1369015D02*
X1373781D01*
G01X1373170Y90157D02*
X1369626D01*
G01X1383012D02*
X1376713D01*
G01X1380650Y119094D02*
G03I-787J0D01*
G01X1381044D02*
G03I-1181J0D01*
G01X1380650Y108464D02*
G03I-787J0D01*
G01Y113779D02*
G03I-787J0D01*
G01X1380712D02*
G03I-849J0D01*
G01X1380779D02*
G03I-916J0D01*
G01X1381044Y108464D02*
G03I-1181J0D01*
G01X1381158Y113779D02*
G03I-1295J0D01*
G01X1378403Y113189D02*
G03X1378878Y112550I1460J589D01*
G01X1381322Y114370D02*
G03X1378403I-1459J-591D01*
G01X1381536Y113779D02*
G03I-1673J0D01*
G01X1382815D02*
G03I-2952J0D01*
G01X1383700D02*
G03I-3837J0D01*
G01X1383800D02*
G03I-3937J0D01*
G01X1383996D02*
G03I-4133J0D01*
G01X1385729D02*
G03I-5866J0D01*
G01X1385768D02*
G03I-5905J0D01*
G01X1374922Y120000D02*
G03X1374933Y119881I591J-5D01*
G01X1372270D02*
G03X1373032Y120472I-1J788D01*
G01X1371398Y119881D02*
G03X1370611Y119094I0J-787D01*
G01Y108464D02*
G03X1371398Y107677I787J0D01*
G01X1374933D02*
G03X1374922Y107559I578J-113D01*
G01X1373032Y107086D02*
G03X1372270Y107677I-763J-197D01*
G01X1373268D02*
X1373071Y107480D01*
G01X1378091Y117126D02*
X1375925Y114960D01*
G01X1376122Y117126D02*
X1373957Y114960D01*
G01X1377343Y119881D02*
X1372658Y115196D01*
G01X1376255Y120472D02*
X1371988Y116205D01*
G01X1373189Y119881D02*
X1373386Y120078D01*
G01X1374154Y117126D02*
X1372973Y116141D01*
G01Y118110D02*
X1374154Y119094D01*
G01X1379961Y117126D02*
Y110433D01*
G01X1379764Y117126D02*
Y110433D01*
G01X1379154Y115295D02*
Y116646D01*
G01Y112263D02*
Y110913D01*
G01X1378878Y112550D02*
Y110433D01*
G01X1378288Y115354D02*
Y112204D01*
G01X1377697Y114370D02*
Y113189D01*
G01X1377500Y118307D02*
Y118897D01*
G01Y112598D02*
Y114960D01*
G01X1375925D02*
Y112795D01*
G01X1375512Y107677D02*
Y107086D01*
G01Y120472D02*
Y119881D01*
G01X1375414Y114960D02*
Y112598D01*
G01X1375335Y119763D02*
Y120669D01*
G01Y107795D02*
Y106889D01*
G01X1375138Y114370D02*
Y113385D01*
G01X1374922Y107677D02*
Y107086D01*
G01Y120472D02*
Y119881D01*
G01X1374750Y110433D02*
Y108464D01*
G01Y115753D02*
Y114960D01*
G01Y119094D02*
Y117126D01*
G01X1374154Y107519D02*
Y108464D01*
G01Y120039D02*
Y119094D01*
G01X1374095Y110482D02*
Y108513D01*
G01Y119045D02*
Y117076D01*
G01X1373937Y119881D02*
Y120472D01*
G01Y107086D02*
Y107677D01*
G01X1373918Y112598D02*
Y114960D01*
G01X1373707Y110805D02*
Y108837D01*
G01Y118722D02*
Y116753D01*
G01X1373658Y110846D02*
Y108877D01*
G01Y118681D02*
Y116712D01*
G01X1373327Y113385D02*
Y114370D01*
G01X1373270Y111169D02*
Y109200D01*
G01Y118358D02*
Y116389D01*
G01X1373032Y119881D02*
Y120472D01*
G01Y107086D02*
Y107677D01*
G01X1372973Y107519D02*
Y106889D01*
G01Y120669D02*
Y120039D01*
G01X1372855Y120472D02*
Y119881D01*
G01X1372737Y114960D02*
Y112598D01*
G01X1372658Y115196D02*
Y112362D01*
G01X1372615Y111417D02*
Y109448D01*
G01Y118110D02*
Y116141D01*
G01X1372264Y119881D02*
Y122637D01*
G01X1371988Y118897D02*
Y108661D01*
G01X1371949Y114960D02*
Y112795D01*
G01X1371792Y119094D02*
Y108464D01*
G01X1371595Y119881D02*
Y120472D01*
G01Y107677D02*
Y107086D01*
G01Y115748D02*
Y111811D01*
G01X1371004Y107677D02*
Y107086D01*
G01Y122637D02*
Y119881D01*
G01X1370611Y106889D02*
Y120669D01*
G01X1368248Y116141D02*
Y118110D01*
G01Y111417D02*
Y109448D01*
G01X1372973Y119960D02*
X1371044Y119252D01*
G01X1373800Y119763D02*
X1372422Y119252D01*
G01X1373465Y120078D02*
X1373662Y119881D01*
G01X1377343Y107677D02*
X1372658Y112362D01*
G01X1371988Y111353D02*
X1376255Y107086D01*
G01X1372965Y107480D02*
X1372768Y107677D01*
G01X1374154Y110433D02*
X1372973Y111417D01*
G01Y109448D02*
X1374154Y108464D01*
G01X1373800Y107795D02*
X1372422Y108307D01*
G01X1372973Y107598D02*
X1371044Y108307D01*
G01X1372264Y121063D02*
X1371004D01*
G01X1372973Y120669D02*
X1370611D01*
G01X1384390D02*
X1375335D01*
G01X1376255Y120472D02*
X1371004D01*
G01X1383470D02*
X1376255D01*
G01X1373032Y120078D02*
X1374922D01*
G01X1370611Y120039D02*
X1374154D01*
G01X1375335Y119960D02*
X1372973D01*
G01X1372270Y119881D02*
X1371004D01*
G01X1388721D02*
X1372277D01*
G01D02*
X1372270D01*
G01X1373800Y119763D02*
X1375335D01*
G01X1370611Y119252D02*
X1372422D01*
G01X1371792Y119094D02*
X1387933D01*
G01X1377500Y118897D02*
X1371988D01*
G01X1382225Y118307D02*
X1377500D01*
G01X1372973Y118110D02*
X1368248D01*
G01X1378091Y117126D02*
X1381634D01*
G01X1374154D02*
X1374750D01*
G01D02*
X1378091D01*
G01X1372973Y116141D02*
X1368248D01*
G01X1388130Y115748D02*
X1371595D01*
G01X1381437Y115354D02*
X1378288D01*
G01X1377500Y114960D02*
X1371949D01*
G01X1381437D02*
X1378288D01*
G01X1378347Y114488D02*
X1376996D01*
G01X1375138Y114370D02*
X1373327D01*
G01X1378403D02*
X1377697D01*
G01X1375138Y113385D02*
X1373327D01*
G01X1378403Y113189D02*
X1377697D01*
G01X1378347Y113070D02*
X1376996D01*
G01X1375925Y112795D02*
X1371949D01*
G01X1378288Y112598D02*
X1381437D01*
G01X1372737D02*
X1373918D01*
G01X1375414D02*
X1377500D01*
G01X1378288Y112204D02*
X1381437D01*
G01X1380847Y111945D02*
X1378878D01*
G01X1380847Y111915D02*
X1378878D01*
G01X1371595Y111811D02*
X1388130D01*
G01X1372973Y111417D02*
X1368248D01*
G01X1379961Y110937D02*
X1379764D01*
G01X1378878Y110433D02*
X1374154D01*
G01X1384975D02*
X1378878D01*
G01X1368248Y109448D02*
X1372973D01*
G01X1371988Y108661D02*
X1387737D01*
G01X1371792Y108464D02*
X1387933D01*
G01X1372422Y108307D02*
X1370611D01*
G01X1375335Y107795D02*
X1373800D01*
G01X1371004Y107677D02*
X1388721D01*
G01X1375335Y107598D02*
X1372973D01*
G01X1370611Y107519D02*
X1374154D01*
G01X1372965Y107480D02*
X1374922D01*
G01X1371004Y107086D02*
X1376255D01*
G01X1383470D02*
X1376255D01*
G01X1372973Y106889D02*
X1370611D01*
G01X1384390D02*
X1375335D01*
G01X1368203Y125984D02*
X1400000Y157781D01*
G01X1372264Y122637D02*
X1371004D01*
G01X1383268Y147244D02*
G03I-6299J0D01*
G01X1371024Y155885D02*
Y154409D01*
G01Y164252D02*
Y162775D01*
G01X1367003Y170157D02*
Y166220D01*
G01X1365998D02*
Y170157D01*
G01X1365496Y162775D02*
Y155885D01*
G01X1363988D02*
Y162775D01*
G01Y170157D02*
Y166220D01*
G01X1365998Y170157D02*
X1367003D01*
G01Y166220D02*
X1365998D01*
G01X1371024Y162775D02*
X1365496D01*
G01Y155885D02*
X1371024D01*
G01X1369014Y174586D02*
X1369516Y175324D01*
G01X1370019Y173848D02*
X1370773Y175078D01*
G01X1364239Y186397D02*
X1363988Y185905D01*
G01X1369516Y175324D02*
X1369768Y176555D01*
G01X1370773Y175078D02*
X1371024Y176555D01*
G01X1369265Y173110D02*
X1370019Y173848D01*
G01X1364490Y186643D02*
X1364239Y186397D01*
G01X1371024Y184183D02*
Y182952D01*
G01Y188120D02*
Y186889D01*
G01X1363988Y185905D02*
Y185413D01*
G01X1371024Y176555D02*
X1370773Y178031D01*
G01X1369768Y176555D02*
X1369516Y177785D01*
G01X1367506Y173602D02*
X1369014Y174586D01*
G01X1363988Y185413D02*
X1364239Y184675D01*
G01X1368260Y172618D02*
X1369265Y173110D01*
G01X1364993Y186889D02*
X1364490Y186643D01*
G01X1370773Y178031D02*
X1370019Y179261D01*
G01X1367506Y172372D02*
X1368260Y172618D01*
G01X1369516Y177785D02*
X1369014Y178523D01*
G01X1370019Y179261D02*
X1369265Y180000D01*
G01X1364239Y184675D02*
X1364742Y184183D01*
G01X1369014Y178523D02*
X1367506Y179507D01*
G01X1369265Y180000D02*
X1368260Y180492D01*
G01D02*
X1367506Y180738D01*
G01D02*
X1366249Y180984D01*
G01X1367506Y179507D02*
X1365998Y179753D01*
G01X1371024Y186889D02*
X1364993D01*
G01X1364742Y184183D02*
X1371024D01*
G01X1366249Y180984D02*
X1363988D01*
G01X1365998Y179753D02*
X1364239D01*
G01Y173356D02*
X1365998D01*
G01X1363988Y172126D02*
X1366249D01*
G01X1365998Y173356D02*
X1367506Y173602D01*
G01X1366249Y172126D02*
X1367506Y172372D01*
G01X1364239Y190334D02*
X1363988Y189842D01*
G01X1364239Y197470D02*
X1363988Y196978D01*
G01X1364239Y201407D02*
X1363988Y200915D01*
G01X1364490Y190580D02*
X1364239Y190334D01*
G01X1364490Y197716D02*
X1364239Y197470D01*
G01X1371024Y195255D02*
Y194025D01*
G01Y192057D02*
Y190826D01*
G01Y199192D02*
Y197962D01*
G01Y203129D02*
Y201899D01*
G01X1363988Y189842D02*
Y189104D01*
G01Y200915D02*
Y200177D01*
G01Y196978D02*
Y196486D01*
G01X1364490Y201653D02*
X1364239Y201407D01*
G01X1363988Y196486D02*
X1364239Y195748D01*
G01X1364993Y190826D02*
X1364490Y190580D01*
G01X1363988Y200177D02*
X1364239Y199685D01*
G01X1363988Y189104D02*
X1364239Y188612D01*
G01X1364993Y197962D02*
X1364490Y197716D01*
G01X1364993Y201899D02*
X1364490Y201653D01*
G01X1364239Y199685D02*
X1364490Y199439D01*
G01X1364239Y195748D02*
X1364742Y195255D01*
G01X1364239Y188612D02*
X1364490Y188366D01*
G01Y199439D02*
X1364993Y199192D01*
G01X1364490Y188366D02*
X1364993Y188120D01*
G01Y203129D02*
X1371024D01*
G01Y201899D02*
X1364993D01*
G01Y199192D02*
X1371024D01*
G01Y197962D02*
X1364993D01*
G01X1364742Y195255D02*
X1371024D01*
G01X1364993Y192057D02*
X1371024D01*
G01Y190826D02*
X1364993D01*
G01Y188120D02*
X1371024D01*
G01X1383268Y216535D02*
G03I-6299J0D01*
G01X1379998Y996063D02*
G03Y988189I0J-3937D01*
G01Y996063D02*
G03Y988189I0J-3937D01*
G01X1400000Y968503D02*
G03X1380315Y988189I-19685J1D01*
G01X1384252Y987791D02*
G03X1380315Y988189I-3938J-19287D01*
G01X1400000Y968503D02*
G03X1380315Y988189I-19685J1D01*
G01X1400001Y996063D02*
X1379998D01*
G01X1400001D02*
X1379998D01*
G01X1392127Y-25591D02*
G03X1400001Y-17717I0J7874D01*
G01X1392167Y-15015D02*
G03X1383585I-4291J0D01*
G01D02*
G03X1392167I4291J0D01*
G01X1392127Y-25591D02*
G03X1400001Y-17717I0J7874D01*
G01X1396064Y-7874D02*
X1400001D01*
G01X1396064Y0D02*
G03Y-7874I0J-3937D01*
G01D02*
X1400001D01*
G01X1396064Y0D02*
G03Y-7874I0J-3937D01*
G01X1396063Y0D02*
G03X1400000Y3937I0J3937D01*
G01X1396063Y0D02*
G03X1400000Y3937I0J3937D01*
G01X1386359Y-1969D02*
X1386752Y-193D01*
G01X1394922Y14960D02*
Y-3544D01*
G01X1391378Y12204D02*
Y-1575D01*
G01X1390394Y12204D02*
Y-2560D01*
G01X1386752Y12204D02*
Y-193D01*
G01X1386713Y12204D02*
Y-2560D01*
G01X1384823Y-3544D02*
Y12204D01*
G01X1384784Y-193D02*
Y12204D01*
G01X1382618Y6692D02*
Y14960D01*
G01X1384784Y-193D02*
X1385177Y-1969D01*
G01X1393347Y-3544D02*
X1391378Y-1575D01*
G01Y4527D02*
X1394922D01*
G01X1386752Y-193D02*
X1384784D01*
G01X1390394Y-1575D02*
X1394922D01*
G01X1386713D02*
X1384823D01*
G01X1386359Y-1969D02*
X1385177D01*
G01X1387500Y20669D02*
G03X1386730Y20045I0J-787D01*
G01X1384806D02*
G03X1384036Y20669I-770J-163D01*
G01X1386359Y22244D02*
X1386752Y22637D01*
G01X1385177Y21063D02*
X1384784Y20669D01*
G01X1391674Y21653D02*
Y14960D01*
G01X1388918Y21653D02*
Y15748D01*
G01X1386752Y30511D02*
Y20127D01*
G01X1386359Y21063D02*
Y22244D01*
G01X1385177D02*
Y21063D01*
G01X1384784Y20127D02*
Y30511D01*
G01X1382618Y21653D02*
Y15748D01*
G01X1381044Y21653D02*
Y15748D01*
G01X1385177Y22244D02*
X1384784Y22637D01*
G01X1386752Y20669D02*
X1386359Y21063D01*
G01X1386752Y22637D02*
X1384784D01*
G01X1386359Y22244D02*
X1385177D01*
G01X1382618Y21653D02*
X1381044D01*
G01X1391674D02*
X1388918D01*
G01X1385177Y21063D02*
X1386359D01*
G01X1382618Y20669D02*
X1388918D01*
G01X1386752Y20127D02*
X1384784D01*
G01X1386730Y20045D02*
X1384806D01*
G01X1388918Y19962D02*
X1382618D01*
G01Y15748D02*
X1388918D01*
G01X1390492Y38976D02*
G03X1392067Y40551I0J1575D01*
G01X1386359Y30118D02*
X1386752Y30511D01*
G01X1385177Y28937D02*
X1384784Y28543D01*
G01X1385892Y35854D02*
X1385296Y35145D01*
G01Y35955D02*
X1385892Y36665D01*
G01X1391477Y45275D02*
Y39566D01*
G01X1389902Y45275D02*
Y39763D01*
G01X1386487Y36665D02*
Y31901D01*
G01X1386359Y28937D02*
Y30118D01*
G01X1385892Y31901D02*
Y35854D01*
G01X1385768Y44488D02*
Y39763D01*
G01X1385296Y35145D02*
Y35955D01*
G01X1385177Y30118D02*
Y28937D01*
G01X1385768Y39566D02*
X1385610Y40157D01*
G01X1385177Y30118D02*
X1384784Y30511D01*
G01X1386752Y28543D02*
X1386359Y28937D01*
G01X1391477Y39566D02*
X1385768D01*
G01X1385892Y36665D02*
X1386487D01*
G01Y31901D02*
X1385892D01*
G01X1386752Y30511D02*
X1384784D01*
G01X1386359Y30118D02*
X1385177D01*
G01Y28937D02*
X1386359D01*
G01X1386752Y28543D02*
X1384784D01*
G01X1386752Y27559D02*
X1384784D01*
G01X1388819Y42716D02*
G03I-492J0D01*
G01X1390000D02*
G03I-1673J0D01*
G01X1390099D02*
G03I-1772J0D01*
G01X1385944Y47814D02*
X1386555Y48425D01*
G01X1390710Y54548D02*
X1390099Y53937D01*
G01X1383025Y41087D02*
X1382894Y40953D01*
G01X1383419Y41087D02*
X1383222Y40819D01*
G01X1383485Y41288D02*
X1383419Y41087D01*
G01X1383091Y41288D02*
X1383025Y41087D01*
G01X1383222Y40819D02*
X1382960Y40618D01*
G01X1383623Y54548D02*
X1383012Y53937D01*
G01X1394797Y43700D02*
Y40944D01*
G01X1394790D02*
Y43700D01*
G01X1394693D02*
Y40944D01*
G01X1393959Y43700D02*
Y40944D01*
G01X1393616Y43700D02*
Y40944D01*
G01X1393615D02*
Y43700D01*
G01X1393601D02*
Y40944D01*
G01X1392783Y43700D02*
Y40944D01*
G01X1392587D02*
Y43700D01*
G01X1392067Y61811D02*
Y40551D01*
G01X1391280Y57086D02*
Y45275D01*
G01X1390975Y41611D02*
Y43700D01*
G01X1390933Y43072D02*
Y42429D01*
G01X1390886Y56928D02*
Y45433D01*
G01X1390710Y54548D02*
Y47814D01*
G01X1390099Y48425D02*
Y53937D01*
G01X1386555D02*
Y48425D01*
G01X1385944Y47814D02*
Y54548D01*
G01X1385784Y42429D02*
Y43072D01*
G01X1383623Y54548D02*
Y47814D01*
G01X1383485Y41556D02*
Y41288D01*
G01X1383091Y41489D02*
Y41288D01*
G01X1383012Y48425D02*
Y53937D01*
G01X1381450Y40886D02*
Y41891D01*
G01Y43700D02*
Y42293D01*
G01X1381057Y40551D02*
Y43700D01*
G01X1380532D02*
Y40551D01*
G01X1382894Y40953D02*
X1382697Y40886D01*
G01X1383419Y41757D02*
X1383485Y41556D01*
G01X1383025Y41690D02*
X1383091Y41489D01*
G01X1383222Y42025D02*
X1383419Y41757D01*
G01X1383025Y41690D02*
X1382894Y41824D01*
G01X1385944Y54548D02*
X1386555Y53937D01*
G01X1390099Y48425D02*
X1390710Y47814D01*
G01X1383012Y48425D02*
X1383623Y47814D01*
G01X1390166Y43716D02*
X1390933Y43072D01*
G01X1390057D02*
X1389290Y43716D01*
G01X1383222Y42025D02*
X1382960Y42226D01*
G01X1393092Y40944D02*
X1392067Y41611D01*
G01X1392000Y40944D02*
X1390975Y41611D01*
G01X1382894Y41824D02*
X1382697Y41891D01*
G01X1390886Y45433D02*
X1391477Y45275D01*
G01X1382960Y42226D02*
X1382631Y42293D01*
G01X1385944Y54548D02*
X1390710D01*
G01X1390099Y53937D02*
X1386555D01*
G01Y48425D02*
X1390099D01*
G01X1390710Y47814D02*
X1385944D01*
G01X1391280Y45275D02*
X1389902D01*
G01X1389290Y43716D02*
X1390166D01*
G01X1390975Y43700D02*
X1394797D01*
G01X1381057D02*
X1381450D01*
G01X1385784Y43072D02*
X1390057D01*
G01X1390933Y42429D02*
X1385784D01*
G01X1381450Y42293D02*
X1382631D01*
G01X1381450Y41891D02*
X1382697D01*
G01X1392067Y41611D02*
X1390975D01*
G01X1392000Y40944D02*
X1394797D01*
G01X1382697Y40886D02*
X1381450D01*
G01X1382631Y40551D02*
X1381057D01*
G01X1382960Y40618D02*
X1382631Y40551D01*
G01X1382483Y62204D02*
Y62401D01*
G01X1388819Y59645D02*
G03I-492J0D01*
G01X1392067Y61811D02*
G03X1390492Y63385I-1575J-1D01*
G01X1390000Y59645D02*
G03I-1673J0D01*
G01X1390099D02*
G03I-1772J0D01*
G01X1382086Y59789D02*
X1382029Y59722D01*
G01X1381727Y60828D02*
X1381671Y60761D01*
G01X1382199Y59722D02*
X1382124Y59588D01*
G01X1381633Y60962D02*
X1381557Y60828D01*
G01X1382124Y59890D02*
X1382086Y59789D01*
G01X1381671Y60761D02*
X1381633Y60661D01*
G01X1381237Y60828D02*
X1380764Y59488D01*
G01X1381180Y61063D02*
X1380708Y59689D01*
G01X1382237Y59856D02*
X1382199Y59722D01*
G01X1381557Y60828D02*
X1381520Y60694D01*
G01X1385610Y62204D02*
X1385768Y62795D01*
G01X1382124Y59588D02*
X1382048Y59521D01*
G01X1381708Y61029D02*
X1381633Y60962D01*
G01X1382142Y60024D02*
X1382124Y59890D01*
G01X1381633Y60661D02*
X1381614Y60526D01*
G01X1382256Y60024D02*
X1382237Y59856D01*
G01X1381520Y60694D02*
X1381501Y60526D01*
G01X1394797Y61417D02*
Y58661D01*
G01X1394790D02*
Y61417D01*
G01X1394693D02*
Y58661D01*
G01X1393959Y61417D02*
Y58661D01*
G01X1393616Y61417D02*
Y58661D01*
G01X1393615D02*
Y61417D01*
G01X1393601D02*
Y58661D01*
G01X1392783Y61417D02*
Y58661D01*
G01X1392587D02*
Y61417D01*
G01X1391477Y62795D02*
Y57086D01*
G01X1390975Y58661D02*
Y60750D01*
G01X1389902Y62598D02*
Y57086D01*
G01X1382237Y60694D02*
X1382256Y60526D01*
G01X1381501Y60024D02*
X1381520Y59856D01*
G01X1392067Y60750D02*
X1393092Y61417D01*
G01X1390975Y60750D02*
X1392000Y61417D01*
G01X1385768Y62598D02*
Y57874D01*
G01X1382256Y60526D02*
Y60024D01*
G01X1382142Y60526D02*
Y60024D01*
G01X1381614D02*
Y60526D01*
G01X1381501Y60024D02*
Y60526D01*
G01X1381350Y61063D02*
Y59488D01*
G01X1381237D02*
Y60828D01*
G01X1380708Y61063D02*
Y59689D01*
G01X1380594Y59488D02*
Y61063D01*
G01X1382481Y62401D02*
X1382484Y62204D01*
G01X1382124Y60661D02*
X1382142Y60526D01*
G01X1381614Y60024D02*
X1381633Y59890D01*
G01X1382048Y59521D02*
X1381954Y59488D01*
G01X1381803Y61063D02*
X1381708Y61029D01*
G01X1382029Y59722D02*
X1381954Y59689D01*
G01X1381803Y60861D02*
X1381727Y60828D01*
G01X1382237Y60694D02*
X1382199Y60828D01*
G01X1381557Y59722D02*
X1381520Y59856D01*
G01X1382086Y60761D02*
X1382124Y60661D01*
G01X1381633Y59890D02*
X1381671Y59789D01*
G01X1382124Y60962D02*
X1382199Y60828D01*
G01X1381633Y59588D02*
X1381557Y59722D01*
G01X1382029Y60828D02*
X1382086Y60761D01*
G01X1381671Y59789D02*
X1381727Y59722D01*
G01X1382124Y60962D02*
X1382048Y61029D01*
G01X1381708Y59521D02*
X1381633Y59588D01*
G01X1381954Y60861D02*
X1382029Y60828D01*
G01X1381803Y59689D02*
X1381727Y59722D01*
G01X1381954Y61063D02*
X1382048Y61029D01*
G01X1381708Y59521D02*
X1381803Y59488D01*
G01X1391477Y62795D02*
X1385768D01*
G01X1385610Y62204D02*
X1382484D01*
G01X1394797Y61417D02*
X1392000D01*
G01X1381803Y61063D02*
X1381954D01*
G01X1380594D02*
X1380708D01*
G01X1381180D02*
X1381350D01*
G01X1381803Y60861D02*
X1381954D01*
G01X1392067Y60750D02*
X1390975D01*
G01X1381954Y59689D02*
X1381803D01*
G01X1381350Y59488D02*
X1381237D01*
G01X1380764D02*
X1380594D01*
G01X1381954D02*
X1381803D01*
G01X1390975Y58661D02*
X1394797D01*
G01X1391280Y57086D02*
X1389902D01*
G01X1391477D02*
X1390886Y56928D01*
G01X1388819Y78937D02*
G03I-492J0D01*
G01X1390492Y75196D02*
G03X1392067Y76771I0J1575D01*
G01X1390000Y78937D02*
G03I-1673J0D01*
G01X1390099D02*
G03I-1772J0D01*
G01X1383419Y77307D02*
X1383222Y77039D01*
G01X1383485Y77508D02*
X1383419Y77307D01*
G01X1383091Y77508D02*
X1383025Y77307D01*
G01X1383222Y77039D02*
X1382960Y76838D01*
G01X1385944Y84034D02*
X1386555Y84645D01*
G01X1383025Y77307D02*
X1382894Y77173D01*
G01X1394797Y79921D02*
Y77165D01*
G01X1394790D02*
Y79921D01*
G01X1394693D02*
Y77165D01*
G01X1393959Y79921D02*
Y77165D01*
G01X1393616Y79921D02*
Y77165D01*
G01X1393615D02*
Y79921D01*
G01X1393601D02*
Y77165D01*
G01X1392783Y79921D02*
Y77165D01*
G01X1392587D02*
Y79921D01*
G01X1392067Y98031D02*
Y76771D01*
G01X1391477Y81496D02*
Y75787D01*
G01X1391280Y93307D02*
Y81496D01*
G01X1390975Y77832D02*
Y79921D01*
G01X1390933Y79293D02*
Y78649D01*
G01X1390886Y93148D02*
Y81654D01*
G01X1390710Y90768D02*
Y84034D01*
G01X1390099Y84645D02*
Y90157D01*
G01X1389902Y81496D02*
Y75984D01*
G01X1386555Y90157D02*
Y84645D01*
G01X1385944Y84034D02*
Y90768D01*
G01X1385784Y78649D02*
Y79293D01*
G01X1385768Y80708D02*
Y75984D01*
G01X1383623Y90768D02*
Y84034D01*
G01X1383485Y77776D02*
Y77508D01*
G01X1383091Y77709D02*
Y77508D01*
G01X1383012Y84645D02*
Y90157D01*
G01X1381450Y77106D02*
Y78111D01*
G01Y79921D02*
Y78514D01*
G01X1381057Y76771D02*
Y79921D01*
G01X1380532D02*
Y76771D01*
G01X1385768Y75787D02*
X1385610Y76377D01*
G01X1383419Y77977D02*
X1383485Y77776D01*
G01X1383025Y77911D02*
X1383091Y77709D01*
G01X1382894Y77173D02*
X1382697Y77106D01*
G01X1383222Y78246D02*
X1383419Y77977D01*
G01X1383025Y77911D02*
X1382894Y78044D01*
G01X1390099Y84645D02*
X1390710Y84034D01*
G01X1383012Y84645D02*
X1383623Y84034D01*
G01X1390166Y79937D02*
X1390933Y79293D01*
G01X1390057D02*
X1389290Y79937D01*
G01X1383222Y78246D02*
X1382960Y78446D01*
G01X1393092Y77165D02*
X1392067Y77832D01*
G01X1392000Y77165D02*
X1390975Y77832D01*
G01X1382894Y78044D02*
X1382697Y78111D01*
G01X1390886Y81654D02*
X1391477Y81496D01*
G01X1382960Y78446D02*
X1382631Y78514D01*
G01X1386555Y84645D02*
X1390099D01*
G01X1390710Y84034D02*
X1385944D01*
G01X1391280Y81496D02*
X1389902D01*
G01X1389290Y79937D02*
X1390166D01*
G01X1390975Y79921D02*
X1394797D01*
G01X1381057D02*
X1381450D01*
G01X1385784Y79293D02*
X1390057D01*
G01X1390933Y78649D02*
X1385784D01*
G01X1381450Y78514D02*
X1382631D01*
G01X1381450Y78111D02*
X1382697D01*
G01X1392067Y77832D02*
X1390975D01*
G01X1392000Y77165D02*
X1394797D01*
G01X1382697Y77106D02*
X1381450D01*
G01X1382631Y76771D02*
X1381057D01*
G01X1391477Y75787D02*
X1385768D01*
G01X1382960Y76838D02*
X1382631Y76771D01*
G01X1382483Y98425D02*
Y98622D01*
G01X1388819Y95866D02*
G03I-492J0D01*
G01X1392067Y98031D02*
G03X1390492Y99606I-1575J0D01*
G01X1390000Y95866D02*
G03I-1673J0D01*
G01X1390099D02*
G03I-1772J0D01*
G01X1382199Y95943D02*
X1382124Y95809D01*
G01X1381633Y97183D02*
X1381557Y97048D01*
G01X1382124Y96110D02*
X1382086Y96010D01*
G01X1381671Y96981D02*
X1381633Y96881D01*
G01X1381237Y97048D02*
X1380764Y95708D01*
G01X1381180Y97283D02*
X1380708Y95909D01*
G01X1382124Y95809D02*
X1382048Y95742D01*
G01X1381708Y97250D02*
X1381633Y97183D01*
G01X1390710Y90768D02*
X1390099Y90157D01*
G01X1383623Y90768D02*
X1383012Y90157D01*
G01X1382086Y96010D02*
X1382029Y95943D01*
G01X1381727Y97048D02*
X1381671Y96981D01*
G01X1382237Y96077D02*
X1382199Y95943D01*
G01X1381557Y97048D02*
X1381520Y96915D01*
G01X1385610Y98425D02*
X1385768Y99015D01*
G01X1382142Y96244D02*
X1382124Y96110D01*
G01X1381633Y96881D02*
X1381614Y96747D01*
G01X1382256Y96244D02*
X1382237Y96077D01*
G01X1381520Y96915D02*
X1381501Y96747D01*
G01X1394797Y97637D02*
Y94881D01*
G01X1394790D02*
Y97637D01*
G01X1394693D02*
Y94881D01*
G01X1393959Y97637D02*
Y94881D01*
G01X1393616Y97637D02*
Y94881D01*
G01X1393615D02*
Y97637D01*
G01X1393601D02*
Y94881D01*
G01X1392783Y97637D02*
Y94881D01*
G01X1392587D02*
Y97637D01*
G01X1391477Y99015D02*
Y93307D01*
G01X1390975Y94881D02*
Y96970D01*
G01X1389902Y98818D02*
Y93307D01*
G01X1382237Y96915D02*
X1382256Y96747D01*
G01X1381501Y96244D02*
X1381520Y96077D01*
G01X1382124Y96881D02*
X1382142Y96747D01*
G01X1381633Y96110D02*
X1381614Y96244D01*
G01X1392067Y96970D02*
X1393092Y97637D01*
G01X1390975Y96970D02*
X1392000Y97637D01*
G01X1385768Y98818D02*
Y94094D01*
G01X1382256Y96747D02*
Y96244D01*
G01X1382142Y96747D02*
Y96244D01*
G01X1381614D02*
Y96747D01*
G01X1381501Y96244D02*
Y96747D01*
G01X1381350Y97283D02*
Y95708D01*
G01X1381237D02*
Y97048D01*
G01X1380708Y97283D02*
Y95909D01*
G01X1380594Y95708D02*
Y97283D01*
G01X1382481Y98622D02*
X1382484Y98425D01*
G01X1382237Y96915D02*
X1382199Y97048D01*
G01X1381520Y96077D02*
X1381557Y95943D01*
G01X1382029D02*
X1381954Y95909D01*
G01X1381803Y97082D02*
X1381727Y97048D01*
G01X1382086Y96981D02*
X1382124Y96881D01*
G01X1381633Y96110D02*
X1381671Y96010D01*
G01X1382048Y95742D02*
X1381954Y95708D01*
G01X1381803Y97283D02*
X1381708Y97250D01*
G01X1382124Y97183D02*
X1382199Y97048D01*
G01X1381557Y95943D02*
X1381633Y95809D01*
G01X1382029Y97048D02*
X1382086Y96981D01*
G01X1381671Y96010D02*
X1381727Y95943D01*
G01X1385944Y90768D02*
X1386555Y90157D01*
G01X1382124Y97183D02*
X1382048Y97250D01*
G01X1381708Y95742D02*
X1381633Y95809D01*
G01X1381954Y97082D02*
X1382029Y97048D01*
G01X1381803Y95909D02*
X1381727Y95943D01*
G01X1381954Y97283D02*
X1382048Y97250D01*
G01X1381708Y95742D02*
X1381803Y95708D01*
G01X1391477Y99015D02*
X1385768D01*
G01X1385610Y98425D02*
X1382484D01*
G01X1394797Y97637D02*
X1392000D01*
G01X1381803Y97283D02*
X1381954D01*
G01X1380594D02*
X1380708D01*
G01X1381180D02*
X1381350D01*
G01X1381803Y97082D02*
X1381954D01*
G01X1392067Y96970D02*
X1390975D01*
G01X1381954Y95909D02*
X1381803D01*
G01X1381350Y95708D02*
X1381237D01*
G01X1380764D02*
X1380594D01*
G01X1381954D02*
X1381803D01*
G01X1390975Y94881D02*
X1394797D01*
G01X1391280Y93307D02*
X1389902D01*
G01X1385944Y90768D02*
X1390710D01*
G01X1390099Y90157D02*
X1386555D01*
G01X1391477Y93307D02*
X1390886Y93148D01*
G01X1384792Y119881D02*
G03X1384803Y120000I-580J114D01*
G01X1386693Y120472D02*
G03X1387456Y119881I763J197D01*
G01X1389114Y119094D02*
G03X1388327Y119881I-787J0D01*
G01Y107677D02*
G03X1389114Y108464I0J787D01*
G01X1380847Y112550D02*
G03X1381322Y113189I-985J1228D01*
G01X1384803Y107559D02*
G03X1384792Y107677I-591J4D01*
G01X1387456D02*
G03X1386693Y107086I0J-788D01*
G01X1386929Y107677D02*
X1386733Y107480D01*
G01X1383470Y107086D02*
X1387737Y111353D01*
G01X1387067Y112362D02*
X1382382Y107677D01*
G01X1386457Y119881D02*
X1386654Y120078D01*
G01X1393130Y109151D02*
X1392653Y108582D01*
G01Y109232D02*
X1393130Y109801D01*
G01D02*
Y109151D01*
G01X1392653Y112401D02*
Y109232D01*
G01X1392175Y108582D02*
Y112401D01*
G01X1391477Y116141D02*
Y118110D01*
G01Y111417D02*
Y109448D01*
G01X1389114Y120669D02*
Y106889D01*
G01X1388721Y107677D02*
Y107086D01*
G01Y120472D02*
Y119881D01*
G01X1388130D02*
Y120472D01*
G01Y111811D02*
Y115748D01*
G01Y107086D02*
Y107677D01*
G01X1387933Y108464D02*
Y119094D01*
G01X1387776Y114960D02*
Y112795D01*
G01X1387737Y108661D02*
Y118897D01*
G01X1386752Y109448D02*
X1385571Y108464D01*
G01X1386752Y111417D02*
X1385571Y110433D01*
G01X1387110Y111417D02*
Y109448D01*
G01Y118110D02*
Y116141D01*
G01X1387067Y112362D02*
Y115196D01*
G01X1386988Y112598D02*
Y114960D01*
G01X1386752Y107519D02*
Y106889D01*
G01Y120669D02*
Y120039D01*
G01X1386693Y107677D02*
Y107086D01*
G01Y120472D02*
Y119881D01*
G01X1386455Y111169D02*
Y109200D01*
G01Y118358D02*
Y116389D01*
G01X1386398Y114370D02*
Y113385D01*
G01X1386067Y110846D02*
Y108877D01*
G01Y118681D02*
Y116712D01*
G01X1386018Y110805D02*
Y108837D01*
G01Y118722D02*
Y116753D01*
G01X1385807Y114960D02*
Y112598D01*
G01X1385788Y107677D02*
Y107086D01*
G01Y120472D02*
Y119881D01*
G01X1385630Y110482D02*
Y108513D01*
G01Y119045D02*
Y117076D01*
G01X1385571Y119094D02*
Y120039D01*
G01Y107519D02*
Y108464D01*
G01X1384975Y114960D02*
Y115753D01*
G01Y110433D02*
Y108464D01*
G01Y119094D02*
Y117126D01*
G01X1384803Y107677D02*
Y107086D01*
G01Y120472D02*
Y119881D01*
G01X1384587Y113385D02*
Y114370D01*
G01X1384390Y107795D02*
Y106889D01*
G01Y120669D02*
Y119763D01*
G01X1384311Y112598D02*
Y114960D01*
G01X1384213Y119881D02*
Y120472D01*
G01Y107086D02*
Y107677D01*
G01X1383800Y114960D02*
Y112795D01*
G01X1382225Y114960D02*
Y112598D01*
G01Y118897D02*
Y118307D01*
G01X1382028Y114370D02*
Y113189D01*
G01X1381437Y112204D02*
Y115354D01*
G01X1380847Y110433D02*
Y112550D01*
G01X1380571Y115295D02*
Y116646D01*
G01Y112263D02*
Y110913D01*
G01X1388681Y108307D02*
X1386752Y107598D01*
G01X1387303Y108307D02*
X1385925Y107795D01*
G01X1386929Y119881D02*
X1386733Y120078D01*
G01X1387737Y116205D02*
X1383470Y120472D01*
G01X1387067Y115196D02*
X1382382Y119881D01*
G01X1385768Y114960D02*
X1383603Y117126D01*
G01X1383800Y114960D02*
X1381634Y117126D01*
G01X1386615Y107480D02*
X1386418Y107677D01*
G01X1386752Y118110D02*
X1385571Y119094D01*
G01X1386752Y116141D02*
X1385571Y117126D01*
G01X1385925Y119763D02*
X1387303Y119252D01*
G01X1388681D02*
X1386752Y119960D01*
G01X1389114Y120669D02*
X1386752D01*
G01X1388721Y120472D02*
X1383470D01*
G01X1388342Y120078D02*
X1384803D01*
G01X1389114Y120039D02*
X1385571D01*
G01X1386752Y119960D02*
X1384390D01*
G01Y119763D02*
X1385925D01*
G01X1387303Y119252D02*
X1389114D01*
G01X1387737Y118897D02*
X1382225D01*
G01X1391477Y118110D02*
X1386752D01*
G01X1384975Y117126D02*
X1385571D01*
G01X1381634D02*
X1384975D01*
G01X1391477Y116141D02*
X1386752D01*
G01X1382225Y114960D02*
X1385768D01*
G01D02*
X1387776D01*
G01X1381378Y114488D02*
X1382729D01*
G01X1384587Y114370D02*
X1386398D01*
G01X1382028D02*
X1381322D01*
G01X1386398Y113385D02*
X1384587D01*
G01X1382028Y113189D02*
X1381322D01*
G01X1381378Y113070D02*
X1382729D01*
G01X1387776Y112795D02*
X1383800D01*
G01X1385807Y112598D02*
X1386988D01*
G01X1382225D02*
X1384311D01*
G01X1392175Y112401D02*
X1392653D01*
G01X1391477Y111417D02*
X1386752D01*
G01X1384975Y110433D02*
X1385571D01*
G01X1391477Y109448D02*
X1386752D01*
G01X1392653Y108582D02*
X1392175D01*
G01X1389114Y108307D02*
X1387303D01*
G01X1385925Y107795D02*
X1384390D01*
G01Y107598D02*
X1386752D01*
G01X1389114Y107519D02*
X1385571D01*
G01X1384803Y107480D02*
X1388342D01*
G01X1383470Y107086D02*
X1388721D01*
G01X1389114Y106889D02*
X1386752D01*
G01X1386457Y254330D02*
Y238582D01*
G01X1400000Y254330D02*
X1386457D01*
G01X1384252Y987791D02*
Y429133D01*
G01X1394761Y663490D02*
Y660866D01*
G01X1394090D02*
Y663490D01*
G01X1393755Y658569D02*
Y653976D01*
G01X1392750D02*
Y658569D01*
G01Y663490D02*
Y660866D01*
G01X1392080D02*
Y663490D01*
G01X1389567Y658569D02*
Y659553D01*
G01Y652992D02*
Y653976D01*
G01X1394090Y663490D02*
X1394761D01*
G01X1392080D02*
X1392750D01*
G01X1394761Y660866D02*
X1394090D01*
G01X1392750D02*
X1392080D01*
G01X1389567Y659553D02*
X1397441D01*
G01X1392750Y658569D02*
X1389567D01*
G01X1397441D02*
X1393755D01*
G01Y653976D02*
X1397441D01*
G01X1389567D02*
X1392750D01*
G01X1397441Y652992D02*
X1389567D01*
G01Y667755D02*
X1389735Y666771D01*
G01X1396603Y667755D02*
X1396436Y668576D01*
G01X1390405Y667755D02*
X1390572Y666935D01*
G01X1392248Y675794D02*
X1392080Y676286D01*
G01X1392750Y673661D02*
X1392918Y673169D01*
G01X1392248D02*
X1392080Y673661D01*
G01X1392750Y676122D02*
X1392918Y675794D01*
G01X1389735Y666771D02*
X1390237Y665951D01*
G01X1396436Y668576D02*
X1396101Y669068D01*
G01X1390572Y666935D02*
X1390907Y666443D01*
G01X1392750Y673989D02*
Y673661D01*
G01Y676614D02*
Y676122D01*
G01X1392080Y679402D02*
Y680223D01*
G01Y673661D02*
Y674317D01*
G01Y676286D02*
Y676942D01*
G01Y672020D02*
Y672841D01*
G01X1392918Y680551D02*
X1393253Y680223D01*
G01X1392583D02*
X1392248Y680551D01*
G01X1392918Y675794D02*
X1393085Y675629D01*
G01X1392750Y675302D02*
X1392248Y675794D01*
G01X1396771Y669560D02*
X1396268Y670052D01*
G01X1392918Y673169D02*
X1393253Y672841D01*
G01X1392583D02*
X1392248Y673169D01*
G01X1390237Y665951D02*
X1390740Y665459D01*
G01X1396436Y666935D02*
X1396603Y667755D01*
G01X1390572Y668576D02*
X1390405Y667755D01*
G01X1389735Y668740D02*
X1389567Y667755D01*
G01X1396101Y669068D02*
X1395096Y669724D01*
G01X1390907Y666443D02*
X1391913Y665787D01*
G01X1392080Y674317D02*
X1392248Y674809D01*
G01X1392080Y676942D02*
X1392248Y677434D01*
G01X1393085Y675629D02*
X1393420Y675465D01*
G01X1396268Y670052D02*
X1395598Y670380D01*
G01X1390740Y665459D02*
X1391410Y665131D01*
G01X1392918Y674317D02*
X1392750Y673989D01*
G01X1392918Y676942D02*
X1392750Y676614D01*
G01X1395598Y670380D02*
X1395096Y670544D01*
G01X1391410Y665131D02*
X1391913Y664967D01*
G01X1390237Y669560D02*
X1389735Y668740D01*
G01X1396101Y666443D02*
X1396436Y666935D01*
G01X1390907Y669068D02*
X1390572Y668576D01*
G01X1395096Y670544D02*
X1394258Y670708D01*
G01X1391913Y664967D02*
X1392750Y664803D01*
G01X1395096Y669724D02*
X1394090Y669888D01*
G01X1391913Y665787D02*
X1392918Y665623D01*
G01X1392080Y680223D02*
X1392583D01*
G01X1393253D02*
X1397441D01*
G01X1396268Y665459D02*
X1396771Y665951D01*
G01X1390740Y670052D02*
X1390237Y669560D01*
G01X1393085Y674481D02*
X1392918Y674317D01*
G01X1392248Y674809D02*
X1392750Y675302D01*
G01X1393085Y677106D02*
X1392918Y676942D01*
G01X1392248Y677434D02*
X1392583Y677762D01*
G01X1397441Y679402D02*
X1392080D01*
G01X1393420Y678090D02*
X1397441D01*
G01Y677270D02*
X1393420D01*
G01Y675465D02*
X1397441D01*
G01Y674645D02*
X1393420D01*
G01X1392080Y672841D02*
X1392583D01*
G01X1393253D02*
X1397441D01*
G01Y672020D02*
X1392080D01*
G01X1394258Y670708D02*
X1392750D01*
G01X1394090Y669888D02*
X1392918D01*
G01Y665623D02*
X1394090D01*
G01X1392750Y664803D02*
X1394258D01*
G01X1395096Y665787D02*
X1396101Y666443D01*
G01X1391913Y669724D02*
X1390907Y669068D01*
G01X1392918Y669888D02*
X1391913Y669724D01*
G01X1394090Y665623D02*
X1395096Y665787D01*
G01X1392750Y670708D02*
X1391913Y670544D01*
G01X1394258Y664803D02*
X1395096Y664967D01*
G01X1395598Y665131D02*
X1396268Y665459D01*
G01X1391410Y670380D02*
X1390740Y670052D01*
G01X1393420Y674645D02*
X1393085Y674481D01*
G01X1393420Y677270D02*
X1393085Y677106D01*
G01X1392583Y677762D02*
X1393420Y678090D01*
G01X1395096Y664967D02*
X1395598Y665131D01*
G01X1391913Y670544D02*
X1391410Y670380D01*
G01X1392248Y683176D02*
X1392080Y683668D01*
G01X1392750Y681043D02*
X1392918Y680551D01*
G01X1392248D02*
X1392080Y681043D01*
G01X1392750Y683503D02*
X1392918Y683176D01*
G01X1392750Y681371D02*
Y681043D01*
G01Y683996D02*
Y683503D01*
G01X1392080Y683668D02*
Y684324D01*
G01Y681043D02*
Y681699D01*
G01X1392918Y683176D02*
X1393085Y683011D01*
G01X1392750Y682683D02*
X1392248Y683176D01*
G01X1392080Y681699D02*
X1392248Y682191D01*
G01X1392080Y684324D02*
X1392248Y684816D01*
G01X1393085Y683011D02*
X1393420Y682847D01*
G01X1392918Y681699D02*
X1392750Y681371D01*
G01X1392918Y684324D02*
X1392750Y683996D01*
G01X1393420Y685472D02*
X1397441D01*
G01Y684652D02*
X1393420D01*
G01Y682847D02*
X1397441D01*
G01Y682027D02*
X1393420D01*
G01X1393085Y681863D02*
X1392918Y681699D01*
G01X1392248Y682191D02*
X1392750Y682683D01*
G01X1393085Y684488D02*
X1392918Y684324D01*
G01X1392248Y684816D02*
X1392583Y685144D01*
G01X1393420Y682027D02*
X1393085Y681863D01*
G01X1393420Y684652D02*
X1393085Y684488D01*
G01X1392583Y685144D02*
X1393420Y685472D01*
G01X1380710Y1008622D02*
G03X1389292I4291J0D01*
G01D02*
G03X1380710I-4291J0D01*
G01X1400001D02*
G03X1385001Y1023622I-15000J0D01*
G01X1400001Y1008622D02*
G03X1385001Y1023622I-15000J0D01*
G01X1402340Y1059123D02*
X1403272Y1059721D01*
X1403804Y1060520D01*
X1403937Y1061418D01*
X1403804Y1062217D01*
X1403139Y1063015D01*
X1402340Y1063514D01*
X1401542Y1063614D01*
X1400610Y1063415D01*
X1399945Y1062716D01*
X1399678Y1062017D01*
Y1061119D01*
G01Y1062017D02*
X1399279Y1062616D01*
X1398614Y1063115D01*
X1397815Y1063315D01*
X1397017Y1063115D01*
X1396351Y1062616D01*
X1395952Y1061718D01*
X1396085Y1060819D01*
X1396618Y1059921D01*
G01X1402740Y1067108D02*
X1403405Y1067706D01*
X1403804Y1068405D01*
X1403937Y1069303D01*
X1403671Y1070202D01*
X1403139Y1070900D01*
X1402207Y1071400D01*
X1401142Y1071499D01*
X1400078Y1071300D01*
X1399412Y1070801D01*
X1398880Y1070102D01*
X1398747Y1069403D01*
X1398880Y1068705D01*
X1399412Y1067806D01*
X1395952Y1068106D01*
Y1070801D01*
G01X1402740Y1075093D02*
X1403405Y1075691D01*
X1403804Y1076390D01*
X1403937Y1077288D01*
X1403671Y1078187D01*
X1403139Y1078885D01*
X1402207Y1079385D01*
X1401142Y1079484D01*
X1400078Y1079285D01*
X1399412Y1078786D01*
X1398880Y1078087D01*
X1398747Y1077388D01*
X1398880Y1076690D01*
X1399412Y1075791D01*
X1395952Y1076091D01*
Y1078786D01*
G01X1404203Y1085273D02*
X1404070Y1085074D01*
X1403804D01*
X1403671Y1085273D01*
X1403804Y1085473D01*
X1404070D01*
X1404203Y1085273D01*
G01X1400610Y1091362D02*
X1399678Y1092061D01*
X1399146Y1092660D01*
X1398880Y1093458D01*
X1399146Y1094157D01*
X1399678Y1094656D01*
X1400477Y1095055D01*
X1401408Y1095155D01*
X1402207Y1095055D01*
X1403006Y1094656D01*
X1403671Y1094057D01*
X1403937Y1093358D01*
X1403671Y1092560D01*
X1402873Y1091861D01*
X1401675Y1091462D01*
X1400344Y1091362D01*
X1398614Y1091562D01*
X1397682Y1091861D01*
X1396751Y1092360D01*
X1396085Y1093059D01*
X1395952Y1093758D01*
X1396218Y1094456D01*
X1396884Y1094955D01*
G01X1395952Y1101243D02*
X1396218Y1100445D01*
X1396884Y1099846D01*
X1397682Y1099447D01*
X1398747Y1099147D01*
X1399945Y1099048D01*
X1401142Y1099147D01*
X1402207Y1099447D01*
X1403006Y1099846D01*
X1403671Y1100445D01*
X1403937Y1101243D01*
X1403671Y1102042D01*
X1403006Y1102641D01*
X1402207Y1103040D01*
X1401142Y1103340D01*
X1399945Y1103439D01*
X1398747Y1103340D01*
X1397682Y1103040D01*
X1396884Y1102641D01*
X1396218Y1102042D01*
X1395952Y1101243D01*
G01X1400001Y-17717D02*
Y-7874D01*
G01Y-17717D02*
Y-7874D01*
G01X1400000Y3937D02*
Y968503D01*
G01Y3937D02*
Y968503D01*
G01Y125984D02*
Y254330D01*
G01X1397441Y653976D02*
Y652992D01*
G01Y659553D02*
Y658569D01*
G01Y667755D02*
X1397274Y668740D01*
G01D02*
X1396771Y669560D01*
G01X1397441Y672841D02*
Y672020D01*
G01Y678090D02*
Y677270D01*
G01Y675465D02*
Y674645D01*
G01Y680223D02*
Y679402D01*
G01X1397274Y666771D02*
X1397441Y667755D01*
G01X1396771Y665951D02*
X1397274Y666771D01*
G01X1397441Y682847D02*
Y682027D01*
G01Y685472D02*
Y684652D01*
G01X1400000Y968750D02*
Y1057969D01*
G01X1400001Y996063D02*
Y1008622D01*
G01Y996063D02*
Y1008622D01*
G01X1584102Y-1837784D02*
Y-1856796D01*
G01X1692187Y-1852994D02*
Y-1841587D01*
X1690476Y-1843868D01*
G01Y-1852994D02*
X1693898D01*
G01X1703595Y-1841587D02*
X1702454Y-1841967D01*
X1701599Y-1842918D01*
X1701028Y-1844058D01*
X1700600Y-1845580D01*
X1700458Y-1847291D01*
X1700600Y-1849002D01*
X1701028Y-1850523D01*
X1701599Y-1851663D01*
X1702454Y-1852614D01*
X1703595Y-1852994D01*
X1704736Y-1852614D01*
X1705591Y-1851663D01*
X1706162Y-1850523D01*
X1706590Y-1849002D01*
X1706732Y-1847291D01*
X1706590Y-1845580D01*
X1706162Y-1844058D01*
X1705591Y-1842918D01*
X1704736Y-1841967D01*
X1703595Y-1841587D01*
G01X1804643Y-1837784D02*
Y-1856796D01*
G01X1913488Y-1852994D02*
Y-1841587D01*
X1911777Y-1843868D01*
G01Y-1852994D02*
X1915199D01*
G01X1924896D02*
Y-1841587D01*
X1923185Y-1843868D01*
G01Y-1852994D02*
X1926607D01*
G01X2025184Y-1837784D02*
Y-1856796D01*
G01Y1453929D02*
Y1434916D01*
G01X2079995Y322428D02*
G03I-6103J0D01*
G01X2080388D02*
G03I-6496J0D01*
G01X2058949Y315472D02*
Y329094D01*
G01X2058392Y315472D02*
Y329094D01*
G01X2056025Y332440D02*
Y313503D01*
G01X2055564Y333031D02*
Y313503D01*
G01X2058392Y315472D02*
X2058949D01*
G01X2087729Y313503D02*
X2055564D01*
G01X2056384Y333031D02*
G03X2056431Y332834I2028J380D01*
G01X2068950Y322624D02*
Y322782D01*
G01X2057139Y331653D02*
Y333031D01*
G01X2058949Y329094D02*
X2056582Y332440D01*
G01X2058392Y329094D02*
X2056025Y332440D01*
G01X2055564Y333031D02*
X2095084D01*
G01X2056582Y332440D02*
X2056025D01*
G01X2058392Y329094D02*
X2058949D01*
G01X2068950Y322782D02*
X2073596D01*
G01Y322624D02*
X2068950D01*
G01X2073753D02*
Y317979D01*
G01X2073596D02*
Y322624D01*
G01X2073753Y317979D02*
X2073596D01*
G01X2078399Y322782D02*
Y322624D01*
G01X2073753Y327427D02*
Y322782D01*
G01X2073596D02*
Y327427D01*
G01D02*
X2073753D01*
G01Y322782D02*
X2078399D01*
G01Y322624D02*
X2073753D01*
G01X2093769Y942583D02*
X2085108D01*
X2086840Y941284D01*
G01X2093769D02*
Y943882D01*
G01X2094058Y951244D02*
X2093913Y951027D01*
X2093625D01*
X2093480Y951244D01*
X2093625Y951461D01*
X2093913D01*
X2094058Y951244D01*
G01X2093769Y961204D02*
X2085108D01*
X2091315Y957198D01*
Y962612D01*
G01X2085108Y968566D02*
X2085397Y967700D01*
X2086118Y967050D01*
X2086984Y966617D01*
X2088139Y966292D01*
X2089439Y966184D01*
X2090738Y966292D01*
X2091893Y966617D01*
X2092759Y967050D01*
X2093480Y967700D01*
X2093769Y968566D01*
X2093480Y969432D01*
X2092759Y970082D01*
X2091893Y970515D01*
X2090738Y970840D01*
X2089439Y970948D01*
X2088139Y970840D01*
X2086984Y970515D01*
X2086118Y970082D01*
X2085397Y969432D01*
X2085108Y968566D01*
G01X2094058Y975278D02*
X2085108Y979176D01*
G01Y975278D02*
X2085397Y974628D01*
X2085830Y974304D01*
X2086696Y974087D01*
X2087562Y974304D01*
X2087995Y974628D01*
X2088284Y975278D01*
X2087995Y975928D01*
X2087562Y976253D01*
X2086696Y976469D01*
X2085830Y976253D01*
X2085397Y975928D01*
X2085108Y975278D01*
G01X2090882Y979176D02*
X2091171Y978526D01*
X2091604Y978201D01*
X2092470Y977985D01*
X2093336Y978201D01*
X2093769Y978526D01*
X2094058Y979176D01*
X2093769Y979825D01*
X2093336Y980150D01*
X2092470Y980367D01*
X2091604Y980150D01*
X2091171Y979825D01*
X2090882Y979176D01*
G01X2094058Y983939D02*
X2085108Y987837D01*
G01Y983939D02*
X2085397Y983289D01*
X2085830Y982965D01*
X2086696Y982748D01*
X2087562Y982965D01*
X2087995Y983289D01*
X2088284Y983939D01*
X2087995Y984589D01*
X2087562Y984914D01*
X2086696Y985130D01*
X2085830Y984914D01*
X2085397Y984589D01*
X2085108Y983939D01*
G01X2090882Y987837D02*
X2091171Y987187D01*
X2091604Y986862D01*
X2092470Y986646D01*
X2093336Y986862D01*
X2093769Y987187D01*
X2094058Y987837D01*
X2093769Y988486D01*
X2093336Y988811D01*
X2092470Y989028D01*
X2091604Y988811D01*
X2091171Y988486D01*
X2090882Y987837D01*
G01X2093769Y992384D02*
X2085108D01*
Y994982D01*
X2085541Y995848D01*
X2086551Y996498D01*
X2087706Y996714D01*
X2088861Y996498D01*
X2089727Y995956D01*
X2090160Y994982D01*
Y992384D01*
G01X2085108Y1003210D02*
X2085397Y1002344D01*
X2086118Y1001694D01*
X2086984Y1001261D01*
X2088139Y1000936D01*
X2089439Y1000828D01*
X2090738Y1000936D01*
X2091893Y1001261D01*
X2092759Y1001694D01*
X2093480Y1002344D01*
X2093769Y1003210D01*
X2093480Y1004076D01*
X2092759Y1004726D01*
X2091893Y1005159D01*
X2090738Y1005484D01*
X2089439Y1005592D01*
X2088139Y1005484D01*
X2086984Y1005159D01*
X2086118Y1004726D01*
X2085397Y1004076D01*
X2085108Y1003210D01*
G01X2094058Y1011871D02*
X2093913Y1011654D01*
X2093625D01*
X2093480Y1011871D01*
X2093625Y1012088D01*
X2093913D01*
X2094058Y1011871D01*
G01X2093769Y1020532D02*
X2085108D01*
X2086840Y1019233D01*
G01X2093769D02*
Y1021831D01*
G01X2092037Y1026811D02*
X2093047Y1027461D01*
X2093625Y1028327D01*
X2093769Y1029301D01*
X2093625Y1030167D01*
X2092903Y1031034D01*
X2092037Y1031575D01*
X2091171Y1031683D01*
X2090160Y1031467D01*
X2089439Y1030709D01*
X2089150Y1029951D01*
Y1028976D01*
G01Y1029951D02*
X2088717Y1030600D01*
X2087995Y1031142D01*
X2087129Y1031358D01*
X2086263Y1031142D01*
X2085541Y1030600D01*
X2085108Y1029626D01*
X2085252Y1028652D01*
X2085830Y1027677D01*
G01X2095997Y-2599D02*
G03X2096785Y-3386I787J0D01*
G01X2095603D02*
G03X2095790Y-3896I788J0D01*
G01X2094816Y-3386D02*
G03X2096391Y-4961I1575J0D01*
G01X2095997Y-2599D02*
Y36215D01*
G01X2095800Y-4145D02*
Y19197D01*
G01X2095603Y-3386D02*
Y37866D01*
G01X2094816Y-3386D02*
Y88909D01*
G01X2095623Y-3367D02*
X2095800Y-3544D01*
G01X2095603Y6644D02*
X2095800D01*
G01X2095603Y416D02*
X2095800D01*
G01X2094816Y-2599D02*
X2095603D01*
G01X2096785Y-3386D02*
X2108556D01*
G01X2095603D02*
X2094816D01*
G01X2095800Y-4145D02*
X2105249D01*
G01X2095027Y-4174D02*
X2095800D01*
G01X2096559Y-4903D02*
X2104688D01*
G01X2096391Y-4961D02*
X2108556D01*
G01X2095997Y19157D02*
X2095800Y18969D01*
G01X2095997Y19386D02*
X2095800Y19197D01*
G01X2095603Y15551D02*
X2095800D01*
G01X2095595Y38071D02*
X2095568Y38067D01*
G01X2096391Y38175D02*
X2095904Y38113D01*
G01X2096498Y36948D02*
G03X2095997Y36215I286J-733D01*
G01X2095904Y38113D02*
G03X2095595Y38071I3289J-25357D01*
G01X2109079Y41872D02*
X2096498Y36948D01*
G01X2096391Y38175D02*
X2107898Y42677D01*
G01X2096391Y36887D02*
Y87657D01*
G01X2094816Y37866D02*
X2095603D01*
G01X2095997Y29527D02*
X2095603D01*
G01X2095997Y28543D02*
X2095603D01*
G01X2101903Y48610D02*
G03X2102670Y47823I787J0D01*
G01X2101903Y59577D02*
Y48610D01*
G01X2102670Y60365D02*
G03X2101903Y59577I20J-787D01*
G01X2100717Y71417D02*
Y71614D01*
G01X2100525Y63937D02*
Y71614D01*
G01X2100131D02*
Y63740D01*
G01Y71614D02*
X2105052D01*
G01Y71417D02*
X2100525D01*
G01X2105052Y63937D02*
X2100525D01*
G01X2100131Y63740D02*
X2105052D01*
G01X2095383Y88149D02*
X2096391Y87657D01*
G01X2097249Y88515D02*
X2096757Y89523D01*
G01X2097249Y88515D02*
X2096757Y89019D01*
G01X2096203Y87841D02*
X2096391Y87657D01*
G01X2096022Y88017D02*
X2096203Y87841D01*
G01X2095887Y88149D02*
X2096022Y88017D01*
G01X2095997Y89302D02*
G03X2095603Y88909I0J-394D01*
G01X2095997Y90090D02*
G03X2094816Y88909I0J-1181D01*
G01X2096021Y88015D02*
X2096391Y88385D01*
G01X2100131Y85560D02*
Y84009D01*
G01X2096757Y89019D02*
Y90090D01*
G01X2095603Y88909D02*
Y88149D01*
G01X2097249Y88515D02*
X2108730Y76744D01*
G01X2108161Y76176D02*
X2096391Y87657D01*
G01X2111745Y88515D02*
X2097249D01*
G01X2096391Y88385D02*
X2097375D01*
G01X2095887Y88149D02*
X2094816D01*
G01X2098143Y87598D02*
X2096452D01*
G01X2095997Y90090D02*
X2111745D01*
G01X2095997Y89302D02*
X2096757D01*
G01X2095407Y306066D02*
Y291594D01*
G01D02*
X2124737D01*
G01X2087729Y306066D02*
Y323586D01*
G01Y310003D02*
X2139304D01*
G01Y306066D02*
X2087729D01*
G01X2096019Y335136D02*
G03X2095996Y334986I53625J-8299D01*
G01X2089619Y325476D02*
G03Y378389I0J26456D01*
G01Y325476D02*
G03X2087729Y323586I0J-1890D01*
G01X2096019Y335136D02*
X2102779Y349366D01*
G01X2091596Y325550D02*
X2095996Y334986D01*
G01X2096019Y335136D02*
X2103874D01*
G01Y334986D02*
X2095996D01*
G01X2094035Y345979D02*
X2093979Y345958D01*
G01X2094081Y345984D02*
X2094035Y345979D01*
G01X2093936Y344077D02*
X2093991Y344035D01*
G01X2093902Y344149D02*
X2093936Y344077D01*
G01X2093899Y344177D02*
X2093902Y344149D01*
G01X2093900Y345833D02*
X2093899Y345822D01*
G01X2093926Y345909D02*
X2093900Y345833D01*
G01X2093979Y345958D02*
X2093926Y345909D01*
G01X2094076Y345653D02*
X2094214Y345551D01*
G01X2094082Y345984D02*
X2094102D01*
G01Y344015D02*
X2094083D01*
G01X2094214Y344448D02*
G03X2094123Y344272I85069J-44096D01*
G01X2096570Y348150D02*
G03X2096615Y348149I56J1492D01*
G01X2096671Y345716D02*
G03X2096665Y345551I2308J-167D01*
G01X2096570Y353187D02*
G03Y348150I68J-2519D01*
G01X2087819Y345236D02*
G03X2091598Y341456I3780J0D01*
G01X2096706Y345984D02*
Y348149D01*
G01Y341456D02*
Y344015D01*
G01X2096665Y344448D02*
Y345551D01*
G01X2096570Y344015D02*
Y341456D01*
G01Y348150D02*
Y345984D01*
G01X2096528Y344015D02*
Y345984D01*
G01X2094214Y345551D02*
Y344448D01*
G01X2093942Y345820D02*
Y344177D01*
G01X2093899Y345820D02*
Y344179D01*
G01X2087819Y345236D02*
Y380039D01*
G01X2093991Y344035D02*
X2094047Y344018D01*
G01D02*
X2094081Y344015D01*
G01X2094102D02*
X2094106D01*
G01X2094083D02*
X2094082D01*
G01X2096615Y348149D02*
X2102200D01*
G01X2096528Y345984D02*
X2101172D01*
G01X2096528D02*
X2094082D01*
G01X2094214Y345551D02*
X2100966D01*
G01X2100442Y344448D02*
X2094214D01*
G01X2094082Y344015D02*
X2096528D01*
G01X2100237D02*
X2096528D01*
G01X2099021Y341456D02*
X2091598D01*
G01X2094106Y345984D02*
X2094081D01*
G01X2094035Y357318D02*
X2093979Y357296D01*
G01X2094081Y357322D02*
X2094035Y357318D01*
G01X2093936Y355416D02*
X2093991Y355373D01*
G01X2093902Y355487D02*
X2093936Y355416D01*
G01X2093899Y355516D02*
X2093902Y355487D01*
G01X2093900Y357172D02*
X2093899Y357160D01*
G01X2093926Y357247D02*
X2093900Y357172D01*
G01X2093979Y357296D02*
X2093926Y357247D01*
G01X2094076Y356991D02*
X2094214Y356889D01*
G01X2094082Y357322D02*
X2094102D01*
G01Y355354D02*
X2094083D01*
G01X2094214Y355787D02*
G03X2094123Y355611I85069J-44096D01*
G01X2096615Y353189D02*
G03X2096570Y353188I11J-1494D01*
G01Y359489D02*
G03X2096615Y359487I89J1491D01*
G01X2096665Y355787D02*
G03X2096671Y355621I2314J1D01*
G01Y357055D02*
G03X2096665Y356889I2308J-167D01*
G01X2096638Y364527D02*
G03X2096570Y359489I0J-2519D01*
G01X2102779Y354493D02*
X2095972Y368823D01*
G01X2096706Y357322D02*
Y359488D01*
G01Y353189D02*
Y355354D01*
G01X2096665Y356889D02*
Y355787D01*
G01X2096570Y355354D02*
Y353187D01*
G01Y359489D02*
Y357322D01*
G01X2096528Y355354D02*
Y357322D01*
G01X2094214Y356889D02*
Y355787D01*
G01X2093942Y357158D02*
Y355516D01*
G01X2093899Y355518D02*
Y357158D01*
G01X2093991Y355373D02*
X2094047Y355356D01*
G01D02*
X2094081Y355354D01*
G01X2094102Y355353D02*
X2094106D01*
G01X2094083Y355354D02*
X2094082D01*
G01X2098012Y364527D02*
X2096638D01*
G01X2096615Y359488D02*
X2100406D01*
G01X2096528Y357322D02*
X2101435D01*
G01X2096528D02*
X2094082D01*
G01X2094214Y356889D02*
X2101640D01*
G01X2102164Y355787D02*
X2094214D01*
G01X2096528Y355354D02*
X2102370D01*
G01X2094082D02*
X2096528D01*
G01X2110682Y353189D02*
X2096615D01*
G01X2094106Y357322D02*
X2094081D01*
G01X2095948Y368973D02*
G03X2095971Y368823I53650J8150D01*
G01X2087730Y380673D02*
G03X2089619Y378389I2324J-1D01*
G01X2095948Y368973D02*
X2091592Y378316D01*
G01X2087729Y397799D02*
Y380673D01*
G01X2095948Y368973D02*
X2103874D01*
G01Y368823D02*
X2095972D01*
G01X2101865Y397877D02*
X2105740D01*
G01X2087729Y397799D02*
X2139304D01*
G01Y393862D02*
X2087729D01*
G01X2102340Y397877D02*
Y397799D01*
G01X2101865Y397877D02*
Y397799D01*
G01X2095934Y1010787D02*
Y937169D01*
G01X2135367Y1021023D02*
X2091997D01*
G01X2095934Y1036771D02*
Y1047007D01*
G01X2137374Y1026535D02*
X2091997D01*
G01X2105101Y-4783D02*
G03X2105249Y-4658I-405J630D01*
G01Y-4174D02*
G03X2104462Y-3386I-787J1D01*
G01X2111076D02*
G03X2111863Y-2599I0J787D01*
G01X2111076Y-4961D02*
G03X2112970Y-4011I0J2362D01*
G01X2115682Y17874D02*
Y-630D01*
G01X2112966Y-4961D02*
Y-2441D01*
G01X2111863Y-2599D02*
Y47583D01*
G01X2108556Y-3386D02*
Y-4961D01*
G01X2105249D02*
Y-4174D01*
G01X2104462Y-4903D02*
Y-4961D01*
G01X2115682Y-630D02*
X2125525D01*
G01X2112966Y-2441D02*
X2111863D01*
G01X2126903Y-2599D02*
X2112966D01*
G01X2111076Y-3386D02*
X2108556D01*
G01X2126903D02*
X2112966D01*
G01X2108556Y-4961D02*
X2111076D01*
G01X2112966D02*
X2111076D01*
G01X2133123D02*
X2112966D01*
G01X2118438Y24566D02*
Y17874D01*
G01X2139304D02*
X2115682D01*
G01X2136548Y24566D02*
X2118438D01*
G01X2109079Y41872D02*
G03X2109580Y42605I-286J733D01*
G01X2107898Y42677D02*
G03X2108399Y43411I-287J734D01*
G01X2109580Y42605D02*
Y47642D01*
G01X2108399Y43411D02*
Y47673D01*
G01X2102670Y60365D02*
Y47823D01*
G01D02*
X2125146Y47235D01*
G01X2109580Y60546D02*
Y76507D01*
G01X2108399Y60515D02*
Y75613D01*
G01X2105052Y63740D02*
Y71614D01*
G01X2125146Y60953D02*
X2102670Y60365D01*
G01X2108399Y75613D02*
G03X2108161Y76176I-787J-1D01*
G01X2108730Y76744D02*
G03X2109294Y76507I563J550D01*
G01X2111745Y84573D02*
G03X2112512Y83786I788J0D01*
G01Y96843D02*
Y83786D01*
G01X2111745Y96055D02*
Y84573D01*
G01X2112512Y83786D02*
X2125146Y83455D01*
G01X2133174Y76507D02*
X2109294D01*
G01X2137729Y76387D02*
X2109580D01*
G01Y75705D02*
X2137729D01*
G01Y74342D02*
X2109580D01*
G01X2112512Y96843D02*
G03X2111745Y96055I21J-787D01*
G01X2125146Y97174D02*
X2112512Y96843D01*
G01X2108911Y234035D02*
Y231279D01*
G01X2108222Y270649D02*
Y234035D01*
G01X2105761D02*
Y273051D01*
G01Y234035D02*
X2108911D01*
G01Y231279D02*
X2122493D01*
G01X2104777Y245059D02*
G03X2105269Y244206I984J-1D01*
G01Y249848D02*
G03X2105761Y250700I-492J852D01*
G01Y243381D02*
G03X2105269Y244206I-984J-28D01*
G01Y249848D02*
G03X2104777Y248996I492J-852D01*
G01X2105269Y249848D02*
Y244206D01*
G01X2104777Y248996D02*
Y245059D01*
G01X2112048Y282464D02*
G03X2111916Y281972I852J-492D01*
G01X2111169Y282910D02*
G03X2110932Y282025I1534J-885D01*
G01X2112464Y285157D02*
G03Y287715I-2216J1279D01*
G01X2113374Y284764D02*
G03X2113373Y288109I-2899J1672D01*
G01X2111916Y281383D02*
X2106745Y272777D01*
G01X2105761Y273051D02*
X2110932Y281656D01*
G01X2113374Y284764D02*
X2112048Y282464D01*
G01X2111169Y282910D02*
X2112464Y285157D01*
G01X2118044Y291594D02*
Y274566D01*
G01X2115407Y277362D02*
Y291594D01*
G01X2114589Y273818D02*
Y271456D01*
G01X2111916Y281383D02*
Y281972D01*
G01X2110932Y282025D02*
Y281656D01*
G01X2110826Y271850D02*
Y273818D01*
G01X2110485Y279002D02*
Y278543D01*
G01Y291594D02*
Y280913D01*
G01X2107902Y273818D02*
Y271850D01*
G01X2107808Y271456D02*
Y270649D01*
G01X2106745Y272777D02*
Y270649D01*
G01X2110486Y278543D02*
X2111666Y277362D01*
G01X2118044Y278543D02*
X2110485D01*
G01X2118044Y277362D02*
X2111666D01*
G01X2118044Y274566D02*
X2121391D01*
G01X2121489Y273818D02*
X2107902D01*
G01X2114589Y271850D02*
X2110826D01*
G01X2108006Y271456D02*
X2107808D01*
G01X2114589D02*
X2110455D01*
G01X2121489Y270649D02*
X2105761D01*
G01X2111863Y290987D02*
G03X2111995Y290495I985J0D01*
G01X2110879Y290934D02*
G03X2111116Y290048I1772J-1D01*
G01X2111863Y290987D02*
Y291594D01*
G01X2110879D02*
Y290934D01*
G01X2111995Y290495D02*
X2113373Y288109D01*
G01X2112464Y287715D02*
X2111116Y290048D01*
G01X2105251Y331490D02*
Y331449D01*
G01Y331490D02*
Y342593D01*
G01X2104779Y330992D02*
Y343091D01*
G01X2104346Y330992D02*
Y343091D01*
G01X2103874Y342593D02*
Y331490D01*
G01X2104779Y335231D02*
X2104346D01*
G01X2105251Y335136D02*
X2109959D01*
G01X2103874Y335121D02*
X2105251D01*
G01Y334986D02*
X2109936D01*
G01X2103874Y331578D02*
X2105251D01*
G01X2104779Y330992D02*
X2104346D01*
G01X2110599Y353010D02*
G03Y350847I2319J-1082D01*
G01X2112257Y338396D02*
Y341456D01*
G01X2114406Y342682D02*
X2110599Y350847D01*
G01X2106347Y349366D02*
X2111864Y337753D01*
G01X2110249Y341456D02*
Y341151D01*
G01Y353189D02*
Y348149D01*
G01X2108262Y345335D02*
Y345551D01*
G01X2106925Y348149D02*
X2111857D01*
G01X2108159Y345551D02*
X2108262D01*
G01X2104346Y343091D02*
X2104779D01*
G01Y342303D02*
X2104346D01*
G01X2113828Y341456D02*
X2110104D01*
G01X2111865Y366109D02*
X2106347Y354493D01*
G01X2110599Y353010D02*
X2114408Y361178D01*
G01X2112257Y359488D02*
Y364527D01*
G01X2110249Y362708D02*
Y359488D01*
G01X2108262Y355787D02*
Y356889D01*
G01X2107714D02*
Y355787D01*
G01X2105251Y361285D02*
Y372367D01*
G01X2104779Y360774D02*
Y372865D01*
G01X2104346Y360774D02*
Y372865D01*
G01X2103874Y361285D02*
Y372367D01*
G01X2112886Y364527D02*
X2111113D01*
G01X2104346Y361553D02*
X2104779D01*
G01Y360774D02*
X2104346D01*
G01X2108720Y359488D02*
X2113620D01*
G01X2107691Y357322D02*
X2107835D01*
G01X2107485Y356889D02*
X2108262D01*
G01X2106961Y355787D02*
X2108262D01*
G01X2106756Y355354D02*
X2107835D01*
G01X2103874Y372367D02*
X2103875Y372408D01*
G01X2104346Y372865D02*
X2104779D01*
G01X2103874Y372279D02*
X2105251D01*
G01X2109857Y368973D02*
X2105251D01*
G01X2109879Y368823D02*
X2105251D01*
G01X2103874Y368736D02*
X2105251D01*
G01X2104346Y368626D02*
X2104779D01*
G01X2117376Y397877D02*
Y397799D01*
G01X2116426D02*
Y397877D01*
G01X2115476D02*
Y397799D01*
G01X2114229D02*
Y397877D01*
G01X2114111D02*
Y397799D01*
G01X2112923Y397877D02*
Y397799D01*
G01X2112805Y397877D02*
Y397799D01*
G01X2112257Y397877D02*
Y426063D01*
G01X2111558Y397877D02*
Y397799D01*
G01Y397877D02*
X2115476D01*
G01X2116426D02*
X2120344D01*
G01X2106690D02*
X2110608D01*
G01D02*
Y397799D01*
G01X2110249Y397877D02*
Y430718D01*
G01X2109658Y397799D02*
Y397877D01*
G01X2107640D02*
Y397799D01*
G01X2106690D02*
Y397877D01*
G01X2105740D02*
Y397799D01*
G01X2116428Y434027D02*
G03X2111234Y430718I-1543J-3309D01*
G01X2116844Y434919D02*
G03X2110250Y430718I-1959J-4201D01*
G01X2123706Y431720D02*
X2116844Y434919D01*
G01X2116428Y434027D02*
X2123290Y430827D01*
G01X2119029Y430000D02*
Y426063D01*
G01X2113202D02*
Y430000D01*
G01X2111233D02*
X2139304D01*
G01X2110249Y426063D02*
X2121509D01*
G01X2111233D02*
Y430718D01*
G01X2130804Y719822D02*
X2102804D01*
G01Y754822D02*
Y719822D01*
G01X2130804Y754822D02*
X2102804D01*
G01X2129068Y1038278D02*
X2118832D01*
G01X2130342Y1062919D02*
G03X2113904Y1052381I15262J-41896D01*
G01X2132128Y-1852994D02*
Y-1841587D01*
X2130417Y-1843868D01*
G01Y-1852994D02*
X2133839D01*
G01X2140827Y-1843488D02*
X2141682Y-1842348D01*
X2142680Y-1841777D01*
X2143821Y-1841587D01*
X2145247Y-1841967D01*
X2146245Y-1842918D01*
X2146531Y-1844058D01*
X2146388Y-1845199D01*
X2145818Y-1846150D01*
X2142966Y-1848051D01*
X2141682Y-1849382D01*
X2140827Y-1851283D01*
X2140541Y-1852994D01*
X2146531D01*
G01X2133438Y-2599D02*
G03X2134225Y-3386I787J0D01*
G01X2133110Y-4681D02*
G03X2134225Y-4961I1116J2082D01*
G01X2127493Y1338D02*
X2125525Y-630D01*
G01X2133438Y-2599D02*
Y-2441D01*
G01X2133123Y-4961D02*
Y-2441D01*
G01X2132808Y-4764D02*
Y-40D01*
G01X2132414Y-3060D02*
Y354D01*
G01X2131430Y7440D02*
Y1338D01*
G01X2130446Y2720D02*
Y7440D01*
G01X2127493Y1338D02*
Y7440D01*
G01X2127296Y-3060D02*
Y1141D01*
G01X2126903Y-4764D02*
Y748D01*
G01X2130840Y944D02*
X2130446Y2720D01*
G01X2133399Y-630D02*
X2131430Y1338D01*
G01X2130446Y3110D02*
X2127493D01*
G01X2131430Y2720D02*
X2130446D01*
G01X2131824Y944D02*
X2130840D01*
G01X2133399Y-630D02*
X2139304D01*
G01Y-2441D02*
X2133123D01*
G01Y-2599D02*
X2132808D01*
G01X2132414Y-3060D02*
X2127296D01*
G01X2133123Y-3386D02*
X2132808D01*
G01X2136745D02*
X2134225D01*
G01X2132808Y-4764D02*
X2126903D01*
G01X2134225Y-4961D02*
X2136745D01*
G01X2134225D02*
X2133123D01*
G01X2127493Y7440D02*
X2131430D01*
G01X2125525Y31456D02*
G03X2124540Y30472I-1J-984D01*
G01X2125525Y33425D02*
G03X2122572Y30472I0J-2953D01*
G01X2133399Y25551D02*
G03X2131202Y24571I0J-2953D01*
G01X2132216Y37794D02*
X2133005Y39394D01*
G01X2131213Y35511D02*
X2130249Y33488D01*
G01X2134974Y38543D02*
Y41889D01*
G01X2133005Y33488D02*
Y39394D01*
G01X2132216Y35511D02*
Y37794D01*
G01X2131213D02*
Y35511D01*
G01X2130249Y39394D02*
Y33488D01*
G01X2124540Y30472D02*
Y24566D01*
G01X2122572D02*
Y30472D01*
G01X2132216Y35511D02*
X2133005Y33488D01*
G01X2131213Y37794D02*
X2130249Y39394D01*
G01X2133005D02*
X2130249D01*
G01X2139304Y38543D02*
X2134974D01*
G01X2132216Y37794D02*
X2131213D01*
G01Y35511D02*
X2132216D01*
G01X2130249Y33488D02*
X2133005D01*
G01X2125525Y33425D02*
X2139304D01*
G01Y31456D02*
X2125525D01*
G01X2133399Y25551D02*
X2139304D01*
G01X2125525Y47303D02*
G03X2124344Y46122I0J-1181D01*
G01Y45137D02*
G03X2125525Y43956I1181J0D01*
G01X2135367Y43858D02*
Y46614D01*
G01X2126312Y66299D02*
Y41889D01*
G01X2125525Y42480D02*
Y65708D01*
G01X2124344Y45137D02*
Y46122D01*
G01X2125525Y48347D02*
X2126312D01*
G01X2125525Y48189D02*
X2126312D01*
G01X2139304Y46614D02*
X2135367D01*
G01X2139304Y43858D02*
X2135367D01*
G01X2126312Y43464D02*
X2138123D01*
G01X2125525Y42480D02*
X2126312D01*
G01X2138123Y41889D02*
X2126312D01*
G01X2125525Y64232D02*
G03X2124344Y63051I0J-1181D01*
G01Y62066D02*
G03X2125525Y60885I1181J0D01*
G01X2135367Y64330D02*
Y61574D01*
G01X2124344Y62066D02*
Y63051D01*
G01X2126312Y66299D02*
X2138123D01*
G01X2125525Y65708D02*
X2126312D01*
G01X2138123Y64724D02*
X2126312D01*
G01X2139304Y64330D02*
X2135367D01*
G01X2139304Y61574D02*
X2135367D01*
G01X2125525Y60000D02*
X2126312D01*
G01Y59841D02*
X2125525D01*
G01X2120182Y81231D02*
G03X2120773Y80641I591J1D01*
G01X2125525Y83523D02*
G03X2124344Y82342I0J-1181D01*
G01Y81358D02*
G03X2125525Y80177I1181J0D01*
G01X2135367Y80078D02*
Y82834D01*
G01X2133174Y76507D02*
Y78110D01*
G01X2126312Y102519D02*
Y78110D01*
G01X2125525Y78700D02*
Y101929D01*
G01X2124344Y81358D02*
Y82342D01*
G01X2121588Y82047D02*
Y83548D01*
G01X2121391Y83553D02*
Y81653D01*
G01X2120182Y81231D02*
Y83585D01*
G01X2125525Y84567D02*
X2126312D01*
G01X2125525Y84409D02*
X2126312D01*
G01X2139304Y82834D02*
X2135367D01*
G01X2121588Y82047D02*
X2124344D01*
G01X2121391Y81653D02*
X2124344D01*
G01X2124593Y80641D02*
X2120773D01*
G01X2139304Y80078D02*
X2135367D01*
G01X2126312Y79685D02*
X2138123D01*
G01X2125525Y78700D02*
X2126312D01*
G01X2138123Y78110D02*
X2126312D01*
G01X2125525Y100452D02*
G03X2124344Y99271I0J-1181D01*
G01Y98287D02*
G03X2125525Y97106I1181J0D01*
G01X2135367Y100551D02*
Y97795D01*
G01X2124344Y98287D02*
Y99271D01*
G01X2126312Y102519D02*
X2138123D01*
G01X2125525Y101929D02*
X2126312D01*
G01X2138123Y100944D02*
X2126312D01*
G01X2139304Y100551D02*
X2135367D01*
G01X2139304Y97795D02*
X2135367D01*
G01X2125525Y96220D02*
X2126312D01*
G01Y96062D02*
X2125525D01*
G01X2132729Y110590D02*
G03X2133320Y110000I591J1D01*
G01D02*
Y123385D01*
G01X2132729Y110590D02*
Y122795D01*
G01X2131037Y112855D02*
Y120529D01*
G01X2129068D02*
Y112855D01*
G01X2133320Y110433D02*
X2134411Y109803D01*
G01X2131037Y112855D02*
X2132729Y112781D01*
G01Y122007D02*
X2133320D01*
G01X2129068Y120529D02*
X2131037D01*
G01X2129068Y112855D02*
X2131037D01*
G01X2133320Y111377D02*
X2132729D01*
G01Y110590D02*
X2133320D01*
G01Y110000D02*
X2134070D01*
G01X2134411Y109803D02*
X2139304D01*
G01X2131037Y120529D02*
X2132729Y120603D01*
G01X2133320Y123385D02*
G03X2132729Y122795I0J-591D01*
G01X2134411Y123582D02*
X2133320Y122952D01*
G01X2131981Y183720D02*
Y130866D01*
G01X2139304D02*
X2131981D01*
G01X2134411Y123582D02*
X2139304D01*
G01X2134070Y123385D02*
X2133320D01*
G01Y122795D02*
X2132729D01*
G01X2134383Y180472D02*
Y189822D01*
G01X2126115Y183720D02*
Y306066D01*
G01X2124737D02*
Y184507D01*
G01Y187244D02*
X2126115Y186456D01*
G01X2124737Y184507D02*
X2126115Y183720D01*
G01X2124737Y185289D02*
X2126115Y185283D01*
G01X2134383Y186456D02*
X2126115D01*
G01Y185283D02*
X2134383D01*
G01Y183720D02*
X2126115D01*
G01X2134383Y182440D02*
X2138320D01*
G01Y180472D02*
X2134383D01*
G01X2130643Y247007D02*
Y189822D01*
G01D02*
X2139107D01*
G01X2124737Y188031D02*
X2134383D01*
G01X2123871Y237500D02*
G03X2123281Y236909I1J-591D01*
G01X2123282Y233307D02*
G03X2124745Y234877I-3663J4880D01*
G01X2123281Y232066D02*
X2122493Y231279D01*
G01X2123281Y232066D02*
Y236909D01*
G01X2121576Y244374D02*
G03X2121587Y244343I1413J484D01*
G01X2119540Y241437D02*
G03X2121903Y239074I2362J-1D01*
G01X2134777Y253307D02*
Y247007D01*
G01X2130643Y262755D02*
Y253307D01*
G01X2123477Y243124D02*
Y242618D01*
G01X2121509Y259626D02*
Y244305D01*
G01X2119619Y259990D02*
Y247047D01*
G01X2119540Y241437D02*
Y259626D01*
G01X2130643Y253307D02*
X2134777D01*
G01X2121509Y249434D02*
X2124737D01*
G01Y248145D02*
X2121509D01*
G01X2119540Y247047D02*
X2121509D01*
G01X2134777Y247007D02*
X2130643D01*
G01X2121509Y246946D02*
X2124737D01*
G01Y245743D02*
X2121509D01*
G01X2124737Y243124D02*
X2123477D01*
G01Y242618D02*
X2124737D01*
G01Y239074D02*
X2121903D01*
G01X2123871Y237500D02*
X2124737D01*
G01X2121509Y259626D02*
G03X2119540I-985J0D01*
G01X2134777Y269055D02*
Y262755D01*
G01X2130643Y303700D02*
Y269055D01*
G01D02*
X2134777D01*
G01Y262755D02*
X2130643D01*
G01X2121509Y259600D02*
X2124737D01*
G01X2121489Y270567D02*
Y270649D01*
G01Y291594D02*
Y270649D01*
G01X2121391Y291594D02*
Y274566D01*
G01X2119619Y273818D02*
Y270649D01*
G01X2121391Y275098D02*
X2121489D01*
G01Y275061D02*
X2124737D01*
G01Y274442D02*
X2121489D01*
G01Y271187D02*
X2124737D01*
G01Y270567D02*
X2121489D01*
G01X2124147Y291456D02*
Y291594D01*
G01X2123359Y290964D02*
Y291594D01*
G01X2124737Y291456D02*
X2124147D01*
G01X2124737Y290964D02*
X2123359D01*
G01X2135367Y387563D02*
Y316303D01*
G01X2134777Y306066D02*
Y303700D01*
G01X2139304Y316303D02*
X2135367D01*
G01X2134777Y303700D02*
X2130643D01*
G01X2135367Y334205D02*
X2135627Y334108D01*
G01Y347308D02*
X2135367Y347211D01*
G01Y351732D02*
X2139304D01*
G01Y351338D02*
X2135367D01*
G01Y356646D02*
X2135627Y356549D01*
G01X2135367Y352519D02*
X2139304D01*
G01Y352126D02*
X2135367D01*
G01X2135627Y369749D02*
X2135367Y369652D01*
G01X2133005Y425551D02*
Y397799D01*
G01X2131588D02*
Y429488D01*
G01X2125213Y397877D02*
Y397799D01*
G01X2124263D02*
Y397877D01*
G01X2121981D02*
Y430000D01*
G01X2121509Y397877D02*
Y426063D01*
G01X2121294Y397877D02*
Y397799D01*
G01X2120344Y397877D02*
Y397799D01*
G01X2119501Y426063D02*
Y397877D01*
G01X2121294D02*
X2125213D01*
G01X2139304Y387563D02*
X2135367D01*
G01X2121981Y407637D02*
X2131588D01*
G01X2123706Y431720D02*
G03X2126194Y431502I1543J3309D01*
G01X2123290Y430827D02*
G03X2126449Y430551I1959J4202D01*
G01X2128655Y431142D02*
X2128400Y432093D01*
G01X2134422Y430000D02*
Y429488D01*
G01X2120210Y426063D02*
Y430000D01*
G01X2139304Y429488D02*
X2131588D01*
G01X2128400Y432093D02*
X2126194Y431502D01*
G01X2126449Y430551D02*
X2128655Y431142D01*
G01X2130804Y721822D02*
X2139304D01*
G01X2130804Y754822D02*
Y719822D01*
G01Y748822D02*
X2139304D01*
G01X2142965Y1028266D02*
X2128994Y1066618D01*
G01X2132128Y1438719D02*
Y1450126D01*
X2130417Y1447845D01*
G01Y1438719D02*
X2133839D01*
G01X2140827Y1448225D02*
X2141682Y1449365D01*
X2142680Y1449936D01*
X2143821Y1450126D01*
X2145247Y1449746D01*
X2146245Y1448795D01*
X2146531Y1447655D01*
X2146388Y1446514D01*
X2145818Y1445563D01*
X2142966Y1443662D01*
X2141682Y1442331D01*
X2140827Y1440430D01*
X2140541Y1438719D01*
X2146531D01*
G01X2137739Y-4652D02*
G03X2138123Y-3780I-797J872D01*
G01X2145603Y2913D02*
Y995039D01*
G01X2139304Y2913D02*
Y995039D01*
G01Y-2441D02*
Y-630D01*
G01D02*
Y2913D01*
G01X2138123Y-3780D02*
Y-2441D01*
G01X2137729Y-4961D02*
Y-2441D01*
G01X2136745Y-4961D02*
Y-3386D01*
G01X2145603Y6850D02*
X2139304D01*
G01X2145603Y2913D02*
X2139304D01*
G01X2136745Y-3386D02*
X2137729D01*
G01Y-4961D02*
X2136745D01*
G01X2151824Y13031D02*
Y11063D01*
G01Y23031D02*
Y21063D01*
G01X2147371Y23582D02*
Y25551D01*
G01X2138123Y23582D02*
Y17874D01*
G01X2136548D02*
Y24566D01*
G01X2139304Y23582D02*
X2136548D01*
G01X2147371D02*
X2145603D01*
G01X2151824Y23031D02*
X2145603D01*
G01X2151824Y21063D02*
X2145603D01*
G01X2151824Y13031D02*
X2145603D01*
G01Y11063D02*
X2151824D01*
G01X2147371Y23582D02*
X2149147Y23976D01*
G01X2151824Y33326D02*
Y30767D01*
G01X2149265Y40039D02*
Y30984D01*
G01X2149147Y31850D02*
Y33031D01*
G01Y23976D02*
Y25157D01*
G01X2147371Y31456D02*
Y33425D01*
G01X2136942Y38543D02*
Y41889D01*
G01X2149147Y33031D02*
X2147371Y33425D01*
G01X2149147Y25157D02*
X2147371Y25551D01*
G01X2145603Y33425D02*
X2147371D01*
G01X2149265Y33326D02*
X2151824D01*
G01X2147371Y31456D02*
X2145603D01*
G01Y30984D02*
X2149265D01*
G01X2145603Y30767D02*
X2151824D01*
G01X2147371Y31456D02*
X2149147Y31850D01*
G01X2145603Y25551D02*
X2147371D01*
G01X2152303Y46174D02*
G03X2151642Y48249I-971J833D01*
G01X2151663Y48236D02*
G03X2151744Y48359I-6052J4073D01*
G01X2152296Y42283D02*
X2150722Y40511D01*
G01X2149265Y47755D02*
Y46614D01*
G01X2145920D02*
Y43858D01*
G01X2138911Y50157D02*
Y58031D01*
G01X2138123Y46614D02*
Y61574D01*
G01Y41889D02*
Y43858D01*
G01X2136613Y46614D02*
Y43858D01*
G01X2152296Y51811D02*
X2150722Y53582D01*
G01X2151642Y48249D02*
X2147936Y49173D01*
G01X2139304Y55118D02*
X2138911D01*
G01X2145603Y53582D02*
X2150722D01*
G01X2139304Y50157D02*
X2138911D01*
G01X2147936Y49173D02*
X2145603D01*
G01X2138123Y48189D02*
X2139304D01*
G01X2145603Y47755D02*
X2149265D01*
G01X2152296Y46614D02*
X2145920D01*
G01X2149808Y43858D02*
X2145920D01*
G01X2138123Y42677D02*
X2139304D01*
G01Y42480D02*
X2138123D01*
G01X2139304Y40511D02*
X2136942D01*
G01X2150722D02*
X2145603D01*
G01Y40039D02*
X2149265D01*
G01X2149808Y43858D02*
X2152296Y44525D01*
G01X2151838Y73720D02*
Y72342D01*
G01X2145920Y64330D02*
Y61574D01*
G01X2138123Y64330D02*
Y66299D01*
G01X2137729D02*
Y78110D01*
G01X2136613Y64330D02*
Y61574D01*
G01X2152296Y63663D02*
X2149808Y64330D01*
G01X2137729Y72637D02*
X2139304D01*
G01X2145603Y72342D02*
X2151838D01*
G01X2139304Y71850D02*
X2137729D01*
G01X2138123Y65511D02*
X2139304D01*
G01X2149808Y64330D02*
X2145920D01*
G01X2152296Y61574D02*
X2145920D01*
G01X2138123Y60000D02*
X2139304D01*
G01X2138911Y58031D02*
X2139304D01*
G01X2151824Y82834D02*
Y83720D01*
G01X2145920Y82834D02*
Y80078D01*
G01X2138911Y86377D02*
Y94252D01*
G01X2138123Y82834D02*
Y97795D01*
G01Y78110D02*
Y80078D01*
G01X2136613Y82834D02*
Y80078D01*
G01X2138911Y88385D02*
X2139304D01*
G01Y86377D02*
X2138911D01*
G01X2138123Y84409D02*
X2139304D01*
G01X2151824Y83720D02*
X2145603D01*
G01X2152296Y82834D02*
X2145920D01*
G01X2149808Y80078D02*
X2145920D01*
G01X2138123Y78897D02*
X2139304D01*
G01X2145603Y73720D02*
X2151838D01*
G01X2149808Y80078D02*
X2152296Y80745D01*
G01X2145920Y100551D02*
Y97795D01*
G01X2138123Y100551D02*
Y102519D01*
G01X2136613Y100551D02*
Y97795D01*
G01X2152296Y99884D02*
X2149808Y100551D01*
G01X2138123Y101732D02*
X2139304D01*
G01X2149808Y100551D02*
X2145920D01*
G01X2152296Y97795D02*
X2145920D01*
G01X2138123Y96220D02*
X2139304D01*
G01X2138911Y94252D02*
X2139304D01*
G01X2136037Y110393D02*
X2136233Y110590D01*
G01X2138517Y119055D02*
Y121023D01*
G01Y114330D02*
Y112362D01*
G01X2137887Y111220D02*
Y110511D01*
G01X2137375Y110000D02*
Y110590D01*
G01X2136785D02*
Y110000D01*
G01X2136588D02*
Y110590D01*
G01X2135997Y110393D02*
Y110000D01*
G01X2135918Y109803D02*
Y111220D01*
G01X2135958Y110393D02*
X2135918Y110433D01*
G01X2138517Y121023D02*
X2139304D01*
G01Y119055D02*
X2138517D01*
G01Y114330D02*
X2139304D01*
G01Y112362D02*
X2138517D01*
G01X2135918Y111220D02*
X2139304D01*
G01X2137887Y110708D02*
X2139304D01*
G01X2136233Y110590D02*
X2137375D01*
G01X2136155Y110511D02*
X2135918D01*
G01X2137887D02*
X2137375D01*
G01X2135958Y110393D02*
X2136037D01*
G01X2135918Y110000D02*
X2137375D01*
G01X2138562Y123580D02*
G03X2138714Y123976I-439J396D01*
G01X2139236Y123580D02*
G03X2139304Y123976I-1113J395D01*
G01X2135918Y122952D02*
X2135958Y122992D01*
G01X2138714Y123976D02*
Y125551D01*
G01X2137887Y122874D02*
Y122165D01*
G01X2137375Y122795D02*
Y123385D01*
G01X2136785D02*
Y122795D01*
G01X2136588D02*
Y123385D01*
G01X2135997D02*
Y122992D01*
G01X2135918Y122165D02*
Y123582D01*
G01X2136233Y122795D02*
X2136037Y122992D01*
G01X2139304Y125551D02*
X2138714D01*
G01X2135918Y123385D02*
X2137375D01*
G01X2135958Y122992D02*
X2136037D01*
G01X2137375Y122874D02*
X2137887D01*
G01X2135918D02*
X2136155D01*
G01X2136233Y122795D02*
X2137375D01*
G01X2137887Y122677D02*
X2139304D01*
G01Y122165D02*
X2135918D01*
G01X2138320Y180472D02*
Y188248D01*
G01X2139304Y185701D02*
X2138320Y185787D01*
G01Y181456D02*
X2139304Y181542D01*
G01X2138714Y202322D02*
Y203503D01*
G01Y199173D02*
Y200354D01*
G01Y196023D02*
Y197204D01*
G01Y194001D02*
Y194055D01*
G01Y192874D02*
Y193267D01*
G01Y194001D02*
Y193267D01*
G01Y203503D02*
X2139304D01*
G01Y202322D02*
X2138714D01*
G01Y200354D02*
X2139304D01*
G01Y199173D02*
X2138714D01*
G01Y197204D02*
X2139304D01*
G01Y196023D02*
X2138714D01*
G01Y194055D02*
X2139304D01*
G01Y192874D02*
X2138714D01*
G01X2139107Y188248D02*
X2138320D01*
G01X2138714Y218070D02*
Y219252D01*
G01Y214921D02*
Y216102D01*
G01Y211771D02*
Y212952D01*
G01Y208622D02*
Y209803D01*
G01Y205472D02*
Y206653D01*
G01Y219252D02*
X2139304D01*
G01Y218070D02*
X2138714D01*
G01Y216102D02*
X2139304D01*
G01Y214921D02*
X2138714D01*
G01Y212952D02*
X2139304D01*
G01Y211771D02*
X2138714D01*
G01Y209803D02*
X2139304D01*
G01Y208622D02*
X2138714D01*
G01Y206653D02*
X2139304D01*
G01Y205472D02*
X2138714D01*
G01Y236968D02*
Y238149D01*
G01Y233818D02*
Y235000D01*
G01Y227519D02*
Y228700D01*
G01Y230669D02*
Y231850D01*
G01Y224370D02*
Y225551D01*
G01Y221220D02*
Y222401D01*
G01X2139304Y236968D02*
X2138714D01*
G01X2139304Y235905D02*
X2139107D01*
G01X2138714Y235000D02*
X2139304D01*
G01Y233818D02*
X2138714D01*
G01Y231850D02*
X2139304D01*
G01Y230669D02*
X2138714D01*
G01X2139304Y229291D02*
X2139107D01*
G01X2138714Y228700D02*
X2139304D01*
G01Y227519D02*
X2138714D01*
G01Y225551D02*
X2139304D01*
G01Y224370D02*
X2138714D01*
G01Y222401D02*
X2139304D01*
G01Y221220D02*
X2138714D01*
G01X2149934Y241424D02*
G03Y242788I-393J682D01*
G01Y237487D02*
G03Y238851I-393J682D01*
G01Y249298D02*
G03Y250662I-393J682D01*
G01X2149423Y243083D02*
G03X2149029Y243189I-395J-682D01*
G01Y241023D02*
G03X2149423Y241129I-1J787D01*
G01X2149029Y237086D02*
G03X2149423Y237192I-1J787D01*
G01Y250957D02*
G03X2149029Y251063I-395J-682D01*
G01Y248897D02*
G03X2149423Y249003I-1J787D01*
G01Y239146D02*
G03X2149029Y239252I-395J-682D01*
G01X2149934Y237487D02*
X2149423Y237192D01*
G01X2149934Y241424D02*
X2149423Y241129D01*
G01X2149934Y249298D02*
X2149423Y249003D01*
G01X2138714Y252716D02*
Y253897D01*
G01Y246417D02*
Y247598D01*
G01Y249566D02*
Y250748D01*
G01Y243267D02*
Y244448D01*
G01Y240118D02*
Y241299D01*
G01X2149423Y250957D02*
X2149934Y250662D01*
G01X2149423Y243083D02*
X2149934Y242788D01*
G01X2149423Y239146D02*
X2149934Y238851D01*
G01X2139304Y252716D02*
X2138714D01*
G01X2139107Y252244D02*
X2139304D01*
G01Y251063D02*
X2139107D01*
G01X2149029D02*
X2145603D01*
G01X2138714Y250748D02*
X2139304D01*
G01Y249566D02*
X2138714D01*
G01X2145603Y248897D02*
X2149029D01*
G01X2139107D02*
X2139304D01*
G01Y247716D02*
X2139107D01*
G01X2138714Y247598D02*
X2139304D01*
G01Y246417D02*
X2138714D01*
G01Y244448D02*
X2139304D01*
G01Y243267D02*
X2138714D01*
G01X2149029Y243189D02*
X2145603D01*
G01X2138714Y241299D02*
X2139304D01*
G01X2145603Y241023D02*
X2149029D01*
G01X2139304Y240118D02*
X2138714D01*
G01X2139304Y239842D02*
X2139107D01*
G01X2139304Y239252D02*
X2139107D01*
G01X2149029D02*
X2145603D01*
G01X2138714Y238149D02*
X2139304D01*
G01X2145603Y237086D02*
X2149029D01*
G01X2149934Y263077D02*
G03Y264441I-393J682D01*
G01X2149423Y264737D02*
G03X2149029Y264842I-393J-683D01*
G01Y262677D02*
G03X2149423Y262782I1J787D01*
G01X2149934Y263077D02*
X2149423Y262782D01*
G01X2138714Y265315D02*
Y266496D01*
G01Y268464D02*
Y269645D01*
G01Y262165D02*
Y263346D01*
G01Y255866D02*
Y257047D01*
G01Y259015D02*
Y260196D01*
G01X2149423Y264737D02*
X2149934Y264441D01*
G01X2138714Y269645D02*
X2139304D01*
G01Y268464D02*
X2138714D01*
G01Y266496D02*
X2139304D01*
G01Y265315D02*
X2138714D01*
G01X2139304Y264842D02*
X2139107D01*
G01X2149029D02*
X2145603D01*
G01X2138714Y263346D02*
X2139304D01*
G01X2145603Y262677D02*
X2149029D01*
G01X2139304Y262165D02*
X2138714D01*
G01X2139304Y261496D02*
X2139107D01*
G01X2138714Y260196D02*
X2139304D01*
G01Y259015D02*
X2138714D01*
G01Y257047D02*
X2139304D01*
G01Y255866D02*
X2138714D01*
G01Y253897D02*
X2139304D01*
G01X2138714Y284212D02*
Y285393D01*
G01Y281063D02*
Y282244D01*
G01Y274763D02*
Y275944D01*
G01Y277913D02*
Y279094D01*
G01Y271614D02*
Y272795D01*
G01Y285393D02*
X2139304D01*
G01Y284212D02*
X2138714D01*
G01X2139107Y283228D02*
X2139304D01*
G01X2138714Y282244D02*
X2139304D01*
G01Y281063D02*
X2138714D01*
G01Y279094D02*
X2139304D01*
G01Y277913D02*
X2138714D01*
G01Y275944D02*
X2139304D01*
G01Y274763D02*
X2138714D01*
G01X2139107Y274566D02*
X2139304D01*
G01Y273818D02*
X2139107D01*
G01X2153084Y273425D02*
X2145603D01*
G01X2138714Y272795D02*
X2139304D01*
G01Y271614D02*
X2138714D01*
G01X2145603Y271456D02*
X2153084D01*
G01X2139304Y270649D02*
X2139107D01*
G01X2151509Y293759D02*
Y292775D01*
G01Y301633D02*
Y300649D01*
G01X2151076Y293759D02*
Y292775D01*
G01Y301633D02*
Y300649D01*
G01X2138714Y296811D02*
Y297992D01*
G01Y299960D02*
Y301141D01*
G01Y293661D02*
Y294842D01*
G01Y287362D02*
Y288543D01*
G01Y290511D02*
Y291692D01*
G01X2154659Y301929D02*
X2145603D01*
G01Y301633D02*
X2151509D01*
G01X2139107D02*
X2139304D01*
G01X2138714Y301141D02*
X2139304D01*
G01X2151509Y300649D02*
X2145603D01*
G01X2139304Y299960D02*
X2138714D01*
G01Y297992D02*
X2139304D01*
G01Y296811D02*
X2138714D01*
G01X2139304Y295531D02*
X2139107D01*
G01X2138714Y294842D02*
X2139304D01*
G01X2145603Y293759D02*
X2151509D01*
G01X2139304Y293661D02*
X2138714D01*
G01X2151509Y292775D02*
X2145603D01*
G01X2138714Y291692D02*
X2139304D01*
G01Y290511D02*
X2138714D01*
G01X2139107Y288740D02*
X2139304D01*
G01X2138714Y288543D02*
X2139304D01*
G01Y287362D02*
X2138714D01*
G01X2151509Y310492D02*
Y311476D01*
G01Y318366D02*
Y319350D01*
G01X2151076Y311476D02*
Y310492D01*
G01Y319350D02*
Y318366D01*
G01X2138714Y316303D02*
Y316889D01*
G01Y318858D02*
Y320039D01*
G01Y303110D02*
Y304291D01*
G01X2136155Y328820D02*
Y316303D01*
G01X2136137Y333371D02*
Y316303D01*
G01X2139304Y318858D02*
X2138714D01*
G01X2151509Y318366D02*
X2145603D01*
G01X2138714Y316889D02*
X2139304D01*
G01X2145603Y311476D02*
X2151509D01*
G01Y310492D02*
X2145603D01*
G01Y310196D02*
X2154659D01*
G01X2145603Y307823D02*
X2154659D01*
G01Y304302D02*
X2145603D01*
G01X2138714Y304291D02*
X2139304D01*
G01Y303110D02*
X2138714D01*
G01X2136137Y333371D02*
G03X2135627Y334108I-787J0D01*
G01X2137282Y333650D02*
G03X2137492Y333622I208J759D01*
G01X2139133Y330866D02*
G03X2138739Y330760I1J-787D01*
G01X2136559Y329502D02*
G03X2136155Y328820I383J-688D01*
G01X2149935Y330866D02*
X2151510Y331456D01*
G01X2138739Y330760D02*
X2136559Y329502D01*
G01X2151510Y331456D02*
Y333031D01*
G01X2150504Y331079D02*
Y333408D01*
G01X2149827Y330866D02*
Y332100D01*
G01Y332381D02*
Y333622D01*
G01X2148763Y331816D02*
Y332671D01*
G01X2148537Y333622D02*
Y333228D01*
G01Y331259D02*
Y330866D01*
G01X2138714Y334606D02*
Y335787D01*
G01Y325157D02*
Y326338D01*
G01Y328307D02*
Y329488D01*
G01Y322007D02*
Y323189D01*
G01X2149935Y333622D02*
X2151510Y333031D01*
G01X2135626Y334107D02*
X2137282Y333650D01*
G01X2139304Y334606D02*
X2138714D01*
G01X2137492Y333622D02*
X2139304D01*
G01X2149935D02*
X2145603D01*
G01Y333228D02*
X2149021D01*
G01X2139304D02*
X2136137D01*
G01X2145603Y332671D02*
X2149246D01*
G01X2136137D02*
X2139304D01*
G01Y331816D02*
X2136137D01*
G01X2149246D02*
X2145603D01*
G01Y331259D02*
X2149021D01*
G01X2136137D02*
X2139304D01*
G01X2149935Y330866D02*
X2145603D01*
G01X2138714Y329488D02*
X2139304D01*
G01Y328307D02*
X2138714D01*
G01Y326338D02*
X2139304D01*
G01Y325157D02*
X2138714D01*
G01Y323189D02*
X2139304D01*
G01Y322007D02*
X2138714D01*
G01X2139304Y320551D02*
X2139107D01*
G01X2138714Y320039D02*
X2139304D01*
G01X2145603Y319350D02*
X2151509D01*
G01X2135627Y347308D02*
G03X2136137Y348045I-277J737D01*
G01X2136925Y350551D02*
G03X2136137Y349763I0J-788D01*
G01X2151509Y351141D02*
X2149935Y350551D01*
G01X2151509Y351141D02*
Y352716D01*
G01X2149488Y353307D02*
Y350551D01*
G01X2148294D02*
Y353307D01*
G01X2148265Y350551D02*
Y353307D01*
G01X2146383Y351338D02*
Y350551D01*
G01X2146186Y351732D02*
Y352126D01*
G01X2138714Y350354D02*
Y350551D01*
G01Y344055D02*
Y345236D01*
G01Y347204D02*
Y348385D01*
G01Y340905D02*
Y342086D01*
G01Y337755D02*
Y338937D01*
G01X2136137Y348045D02*
Y349763D01*
G01X2145603Y351732D02*
X2148078D01*
G01X2147855Y351338D02*
X2145603D01*
G01Y350551D02*
X2149935D01*
G01X2139304D02*
X2136925D01*
G01X2139304Y350354D02*
X2138714D01*
G01Y348385D02*
X2139304D01*
G01Y347204D02*
X2138714D01*
G01Y345236D02*
X2139304D01*
G01Y344055D02*
X2138714D01*
G01Y342086D02*
X2139304D01*
G01Y340905D02*
X2138714D01*
G01Y338937D02*
X2139304D01*
G01Y337755D02*
X2138714D01*
G01Y335787D02*
X2139304D01*
G01X2147856Y351338D02*
X2147855D01*
G01X2148182Y352210D02*
G03X2148168Y352229I-434J-305D01*
G01X2148060Y352280D02*
G03X2148043Y352337I-526J-126D01*
G01X2148240Y352168D02*
G03X2148231Y352203I-699J-161D01*
G01X2136137Y354094D02*
G03X2136925Y353307I787J0D01*
G01X2136137Y355812D02*
G03X2135627Y356549I-787J0D01*
G01X2148259Y352048D02*
G03X2148255Y352086I-1078J-94D01*
G01Y352057D02*
G03X2148250Y352102I-1673J-163D01*
G01D02*
G03X2148242Y352152I-1861J-272D01*
G01D02*
G03X2148233Y352204I-2045J-327D01*
G01X2148116Y352614D02*
G03X2148103Y352650I-2154J-758D01*
G01X2148233Y352204D02*
G03X2148213Y352296I-2283J-448D01*
G01X2148177Y352433D02*
G03X2148116Y352614I-2428J-718D01*
G01X2148213Y352296D02*
G03X2148177Y352433I-2507J-586D01*
G01X2146383Y353307D02*
Y352519D01*
G01X2138714Y362952D02*
Y364133D01*
G01Y366102D02*
Y367283D01*
G01Y359803D02*
Y360984D01*
G01Y353503D02*
Y354685D01*
G01Y356653D02*
Y357834D01*
G01X2136137Y355812D02*
Y354094D01*
G01X2149935Y353307D02*
X2151509Y352716D01*
G01X2138714Y367283D02*
X2139304D01*
G01Y366102D02*
X2138714D01*
G01Y364133D02*
X2139304D01*
G01Y362952D02*
X2138714D01*
G01Y360984D02*
X2139304D01*
G01Y359803D02*
X2138714D01*
G01Y357834D02*
X2139304D01*
G01Y356653D02*
X2138714D01*
G01Y354685D02*
X2139304D01*
G01Y353503D02*
X2138714D01*
G01X2136925Y353307D02*
X2139304D01*
G01X2149935D02*
X2145603D01*
G01Y352519D02*
X2147855D01*
G01X2148078Y352126D02*
X2145603D01*
G01X2135627Y369749D02*
G03X2136137Y370486I-277J737D01*
G01X2138030Y373097D02*
G03X2138424Y372992I393J682D01*
G01X2137492Y370236D02*
G03X2137282Y370207I2J-787D01*
G01X2151510Y370826D02*
X2149935Y370236D01*
G01X2151510Y370826D02*
Y372401D01*
G01X2150504Y370449D02*
Y372778D01*
G01X2149827Y371751D02*
Y372992D01*
G01Y370236D02*
Y371470D01*
G01X2148763Y371186D02*
Y372041D01*
G01X2148537Y370629D02*
Y370236D01*
G01Y372992D02*
Y372598D01*
G01X2138714Y378700D02*
Y379881D01*
G01Y372992D02*
Y373582D01*
G01Y375551D02*
Y376732D01*
G01Y369252D02*
Y370236D01*
G01X2138320Y384507D02*
Y387563D01*
G01X2136137D02*
Y370486D01*
G01Y374190D02*
X2138030Y373097D01*
G01X2149935Y372992D02*
X2151510Y372401D01*
G01X2138320Y384507D02*
X2139107D01*
G01Y382933D02*
X2136137D01*
G01X2138714Y379881D02*
X2139304D01*
G01X2138714Y378700D02*
X2139304D01*
G01X2138714Y376732D02*
X2139304D01*
G01Y375551D02*
X2138714D01*
G01Y373582D02*
X2139304D01*
G01X2138424Y372992D02*
X2139304D01*
G01X2149935D02*
X2145603D01*
G01Y372598D02*
X2149021D01*
G01X2139304D02*
X2136137D01*
G01X2145603Y372041D02*
X2149246D01*
G01X2136137D02*
X2139304D01*
G01Y371186D02*
X2136137D01*
G01X2149246D02*
X2145603D01*
G01Y370629D02*
X2149021D01*
G01X2136137D02*
X2139304D01*
G01Y370236D02*
X2137492D01*
G01X2149935D02*
X2145603D01*
G01X2139304Y369252D02*
X2138714D01*
G01X2137282Y370207D02*
X2135626Y369750D01*
G01X2138320Y387165D02*
X2138718Y387563D01*
G01X2139304Y725822D02*
X2137304D01*
G01Y748822D02*
Y725822D01*
G01X2145603Y743572D02*
X2151942D01*
G01X2145603Y741072D02*
X2151942D01*
G01X2145603Y733572D02*
X2151942D01*
G01X2145603Y731072D02*
X2151942D01*
G01X2145603Y971417D02*
X2139304D01*
G01X2145603Y991102D02*
X2139304D01*
G01Y990704D02*
Y991102D01*
G01Y995039D02*
X2145603D01*
G01D02*
Y1021023D01*
G01X2139304Y995039D02*
Y1021023D01*
G01X2145603Y1024960D02*
Y1042215D01*
G01X2139304Y1024960D02*
Y1042215D01*
G01X2145603Y1024960D02*
Y1069549D01*
G01X2140594Y1024566D02*
X2144313D01*
G01X2145603Y1021023D02*
X2143596Y1026535D01*
G01X2139304Y1021023D02*
X2141311Y1026535D01*
G01D02*
X2143596D01*
G01X2139304Y1033976D02*
Y1029173D01*
G01X2147148Y1052124D02*
X2147798Y1052989D01*
X2148555Y1053423D01*
X2149422Y1053567D01*
X2150504Y1053278D01*
X2151262Y1052557D01*
X2151479Y1051691D01*
X2151370Y1050824D01*
X2150937Y1050103D01*
X2148772Y1048659D01*
X2147798Y1047649D01*
X2147148Y1046205D01*
X2146931Y1044906D01*
X2151479D01*
G01X2157866Y1053567D02*
X2157000Y1053278D01*
X2156350Y1052557D01*
X2155917Y1051691D01*
X2155592Y1050536D01*
X2155484Y1049236D01*
X2155592Y1047937D01*
X2155917Y1046782D01*
X2156350Y1045916D01*
X2157000Y1045195D01*
X2157866Y1044906D01*
X2158732Y1045195D01*
X2159382Y1045916D01*
X2159815Y1046782D01*
X2160140Y1047937D01*
X2160248Y1049236D01*
X2160140Y1050536D01*
X2159815Y1051691D01*
X2159382Y1052557D01*
X2158732Y1053278D01*
X2157866Y1053567D01*
G01X2166527Y1044617D02*
X2166310Y1044762D01*
Y1045050D01*
X2166527Y1045195D01*
X2166744Y1045050D01*
Y1044762D01*
X2166527Y1044617D01*
G01X2175188Y1053567D02*
X2174322Y1053278D01*
X2173672Y1052557D01*
X2173239Y1051691D01*
X2172914Y1050536D01*
X2172806Y1049236D01*
X2172914Y1047937D01*
X2173239Y1046782D01*
X2173672Y1045916D01*
X2174322Y1045195D01*
X2175188Y1044906D01*
X2176054Y1045195D01*
X2176704Y1045916D01*
X2177137Y1046782D01*
X2177462Y1047937D01*
X2177570Y1049236D01*
X2177462Y1050536D01*
X2177137Y1051691D01*
X2176704Y1052557D01*
X2176054Y1053278D01*
X2175188Y1053567D01*
G01X2176084Y1053568D02*
G03X2145603Y1065613I-30481J-32545D01*
G01X2152296Y47836D02*
Y51810D01*
G01Y42283D02*
Y44525D01*
G01Y46614D02*
Y44525D01*
G01Y63663D02*
Y61574D01*
G01Y82834D02*
Y80745D01*
G01Y99884D02*
Y97795D01*
G01X2153084Y271456D02*
Y273425D01*
G01X2156627Y303110D02*
X2154659Y301929D01*
G01Y304302D02*
Y301929D01*
G01X2156627Y309015D02*
Y303110D01*
G01X2154659Y310196D02*
Y307823D01*
G01X2156627Y309015D02*
X2154659Y310196D01*
G01X2152808Y743072D02*
X2151942Y743572D01*
G01X2152808Y733072D02*
X2151942Y733572D01*
G01X2152808Y741572D02*
Y743072D01*
G01Y731572D02*
Y733072D01*
G01X2151942Y741072D02*
Y743572D01*
G01Y731072D02*
Y733572D01*
G01X2152808Y731572D02*
X2151942Y731072D01*
G01X2152808Y741572D02*
X2151942Y741072D01*
G01X2155840Y1038278D02*
X2216005D01*
G01X2173492Y1042176D02*
Y1050837D01*
X2172193Y1049105D01*
G01Y1042176D02*
X2174791D01*
G01X2182153Y1041887D02*
X2181936Y1042032D01*
Y1042320D01*
X2182153Y1042465D01*
X2182370Y1042320D01*
Y1042032D01*
X2182153Y1041887D01*
G01X2188757Y1045785D02*
X2189515Y1046795D01*
X2190164Y1047373D01*
X2191031Y1047661D01*
X2191788Y1047373D01*
X2192330Y1046795D01*
X2192763Y1045929D01*
X2192871Y1044919D01*
X2192763Y1044052D01*
X2192330Y1043186D01*
X2191680Y1042465D01*
X2190922Y1042176D01*
X2190056Y1042465D01*
X2189298Y1043331D01*
X2188865Y1044630D01*
X2188757Y1046073D01*
X2188973Y1047950D01*
X2189298Y1048961D01*
X2189840Y1049971D01*
X2190597Y1050693D01*
X2191355Y1050837D01*
X2192113Y1050548D01*
X2192655Y1049827D01*
G01X2199475Y1050837D02*
X2198609Y1050548D01*
X2197959Y1049827D01*
X2197526Y1048961D01*
X2197201Y1047806D01*
X2197093Y1046506D01*
X2197201Y1045207D01*
X2197526Y1044052D01*
X2197959Y1043186D01*
X2198609Y1042465D01*
X2199475Y1042176D01*
X2200341Y1042465D01*
X2200991Y1043186D01*
X2201424Y1044052D01*
X2201749Y1045207D01*
X2201857Y1046506D01*
X2201749Y1047806D01*
X2201424Y1048961D01*
X2200991Y1049827D01*
X2200341Y1050548D01*
X2199475Y1050837D01*
G01X2186593Y1052702D02*
X2185943Y1053784D01*
Y1054434D01*
X2186431D01*
Y1053784D01*
X2185943D01*
G01X2177426Y1047793D02*
X2178509Y1050680D01*
X2179591D01*
X2181757Y1044906D01*
X2182839D01*
X2183922Y1047793D01*
G01X2201931Y1045640D02*
X2201411Y1045467D01*
X2201021Y1045034D01*
X2200762Y1044514D01*
X2200567Y1043821D01*
X2200502Y1043041D01*
X2200567Y1042262D01*
X2200762Y1041569D01*
X2201021Y1041049D01*
X2201411Y1040616D01*
X2201931Y1040443D01*
X2202451Y1040616D01*
X2202841Y1041049D01*
X2203100Y1041569D01*
X2203295Y1042262D01*
X2203360Y1043041D01*
X2203295Y1043821D01*
X2203100Y1044514D01*
X2202841Y1045034D01*
X2202451Y1045467D01*
X2201931Y1045640D01*
G01X2207128Y1040270D02*
X2206998Y1040356D01*
Y1040530D01*
X2207128Y1040616D01*
X2207258Y1040530D01*
Y1040356D01*
X2207128Y1040270D01*
G01X2212325Y1045640D02*
X2211805Y1045467D01*
X2211415Y1045034D01*
X2211156Y1044514D01*
X2210961Y1043821D01*
X2210896Y1043041D01*
X2210961Y1042262D01*
X2211156Y1041569D01*
X2211415Y1041049D01*
X2211805Y1040616D01*
X2212325Y1040443D01*
X2212845Y1040616D01*
X2213235Y1041049D01*
X2213494Y1041569D01*
X2213689Y1042262D01*
X2213754Y1043041D01*
X2213689Y1043821D01*
X2213494Y1044514D01*
X2213235Y1045034D01*
X2212845Y1045467D01*
X2212325Y1045640D01*
G01X2217522D02*
X2217002Y1045467D01*
X2216612Y1045034D01*
X2216353Y1044514D01*
X2216158Y1043821D01*
X2216093Y1043041D01*
X2216158Y1042262D01*
X2216353Y1041569D01*
X2216612Y1041049D01*
X2217002Y1040616D01*
X2217522Y1040443D01*
X2218042Y1040616D01*
X2218432Y1041049D01*
X2218691Y1041569D01*
X2218886Y1042262D01*
X2218951Y1043041D01*
X2218886Y1043821D01*
X2218691Y1044514D01*
X2218432Y1045034D01*
X2218042Y1045467D01*
X2217522Y1045640D01*
G01X2196019Y1049104D02*
X2197579D01*
G01X2196734Y1050230D02*
Y1047978D01*
G01X2201931Y1052569D02*
X2201411Y1052396D01*
X2201021Y1051963D01*
X2200762Y1051443D01*
X2200567Y1050750D01*
X2200502Y1049970D01*
X2200567Y1049191D01*
X2200762Y1048498D01*
X2201021Y1047978D01*
X2201411Y1047545D01*
X2201931Y1047372D01*
X2202451Y1047545D01*
X2202841Y1047978D01*
X2203100Y1048498D01*
X2203295Y1049191D01*
X2203360Y1049970D01*
X2203295Y1050750D01*
X2203100Y1051443D01*
X2202841Y1051963D01*
X2202451Y1052396D01*
X2201931Y1052569D01*
G01X2207128Y1047199D02*
X2206998Y1047285D01*
Y1047459D01*
X2207128Y1047545D01*
X2207258Y1047459D01*
Y1047285D01*
X2207128Y1047199D01*
G01X2212325Y1052569D02*
X2211805Y1052396D01*
X2211415Y1051963D01*
X2211156Y1051443D01*
X2210961Y1050750D01*
X2210896Y1049970D01*
X2210961Y1049191D01*
X2211156Y1048498D01*
X2211415Y1047978D01*
X2211805Y1047545D01*
X2212325Y1047372D01*
X2212845Y1047545D01*
X2213235Y1047978D01*
X2213494Y1048498D01*
X2213689Y1049191D01*
X2213754Y1049970D01*
X2213689Y1050750D01*
X2213494Y1051443D01*
X2213235Y1051963D01*
X2212845Y1052396D01*
X2212325Y1052569D01*
G01X2216093Y1048151D02*
X2216482Y1047718D01*
X2216937Y1047459D01*
X2217522Y1047372D01*
X2218107Y1047545D01*
X2218561Y1047892D01*
X2218886Y1048498D01*
X2218951Y1049191D01*
X2218821Y1049884D01*
X2218496Y1050317D01*
X2218042Y1050663D01*
X2217587Y1050750D01*
X2217132Y1050663D01*
X2216548Y1050317D01*
X2216742Y1052569D01*
X2218496D01*
G01X2189235Y1050016D02*
X2189624Y1049583D01*
X2190079Y1049324D01*
X2190664Y1049237D01*
X2191249Y1049410D01*
X2191703Y1049757D01*
X2192028Y1050363D01*
X2192093Y1051056D01*
X2191963Y1051749D01*
X2191638Y1052182D01*
X2191184Y1052528D01*
X2190729Y1052615D01*
X2190274Y1052528D01*
X2189690Y1052182D01*
X2189884Y1054434D01*
X2191638D01*
G01X2195861Y1049064D02*
X2195731Y1049150D01*
Y1049324D01*
X2195861Y1049410D01*
X2195991Y1049324D01*
Y1049150D01*
X2195861Y1049064D01*
G01X2201058Y1054434D02*
X2200538Y1054261D01*
X2200148Y1053828D01*
X2199889Y1053308D01*
X2199694Y1052615D01*
X2199629Y1051835D01*
X2199694Y1051056D01*
X2199889Y1050363D01*
X2200148Y1049843D01*
X2200538Y1049410D01*
X2201058Y1049237D01*
X2201578Y1049410D01*
X2201968Y1049843D01*
X2202227Y1050363D01*
X2202422Y1051056D01*
X2202487Y1051835D01*
X2202422Y1052615D01*
X2202227Y1053308D01*
X2201968Y1053828D01*
X2201578Y1054261D01*
X2201058Y1054434D01*
G01X2201880Y1050969D02*
X2202530Y1052702D01*
X2203179D01*
X2204479Y1049237D01*
X2205128D01*
X2205778Y1050969D01*
G01X2245725Y-1837784D02*
Y-1856796D01*
G01Y1453929D02*
Y1434916D01*
G01X2352669Y-1852994D02*
Y-1841587D01*
X2350958Y-1843868D01*
G01Y-1852994D02*
X2354380D01*
G01X2360940Y-1850713D02*
X2361795Y-1852044D01*
X2362936Y-1852804D01*
X2364220Y-1852994D01*
X2365361Y-1852804D01*
X2366501Y-1851854D01*
X2367214Y-1850713D01*
X2367357Y-1849572D01*
X2367072Y-1848241D01*
X2366073Y-1847291D01*
X2365075Y-1846910D01*
X2363792D01*
G01X2365075D02*
X2365931Y-1846340D01*
X2366644Y-1845390D01*
X2366929Y-1844249D01*
X2366644Y-1843108D01*
X2365931Y-1842158D01*
X2364647Y-1841587D01*
X2363364Y-1841777D01*
X2362081Y-1842538D01*
G01X2352669Y1438719D02*
Y1450126D01*
X2350958Y1447845D01*
G01Y1438719D02*
X2354380D01*
G01X2360940Y1441000D02*
X2361795Y1439669D01*
X2362936Y1438909D01*
X2364220Y1438719D01*
X2365361Y1438909D01*
X2366501Y1439859D01*
X2367214Y1441000D01*
X2367357Y1442141D01*
X2367072Y1443472D01*
X2366073Y1444422D01*
X2365075Y1444803D01*
X2363792D01*
G01X2365075D02*
X2365931Y1445373D01*
X2366644Y1446323D01*
X2366929Y1447464D01*
X2366644Y1448605D01*
X2365931Y1449555D01*
X2364647Y1450126D01*
X2363364Y1449936D01*
X2362081Y1449175D01*
G01X2427904Y1096174D02*
X2428554Y1097039D01*
X2429311Y1097473D01*
X2430178Y1097617D01*
X2431260Y1097328D01*
X2432018Y1096607D01*
X2432235Y1095741D01*
X2432126Y1094874D01*
X2431693Y1094153D01*
X2429528Y1092709D01*
X2428554Y1091699D01*
X2427904Y1090255D01*
X2427687Y1088956D01*
X2432235D01*
G01X2436240Y1090255D02*
X2436890Y1089533D01*
X2437648Y1089100D01*
X2438622Y1088956D01*
X2439596Y1089245D01*
X2440354Y1089822D01*
X2440896Y1090832D01*
X2441004Y1091987D01*
X2440787Y1093142D01*
X2440246Y1093864D01*
X2439488Y1094441D01*
X2438730Y1094586D01*
X2437972Y1094441D01*
X2436998Y1093864D01*
X2437323Y1097617D01*
X2440246D01*
G01X2445226Y1096174D02*
X2445876Y1097039D01*
X2446633Y1097473D01*
X2447500Y1097617D01*
X2448582Y1097328D01*
X2449340Y1096607D01*
X2449557Y1095741D01*
X2449448Y1094874D01*
X2449015Y1094153D01*
X2446850Y1092709D01*
X2445876Y1091699D01*
X2445226Y1090255D01*
X2445009Y1088956D01*
X2449557D01*
G01X2455944Y1088667D02*
X2455727Y1088812D01*
Y1089100D01*
X2455944Y1089245D01*
X2456161Y1089100D01*
Y1088812D01*
X2455944Y1088667D01*
G01X2462223Y1090255D02*
X2462873Y1089533D01*
X2463631Y1089100D01*
X2464605Y1088956D01*
X2465579Y1089245D01*
X2466337Y1089822D01*
X2466879Y1090832D01*
X2466987Y1091987D01*
X2466770Y1093142D01*
X2466229Y1093864D01*
X2465471Y1094441D01*
X2464713Y1094586D01*
X2463955Y1094441D01*
X2462981Y1093864D01*
X2463306Y1097617D01*
X2466229D01*
G01X2470884Y1090255D02*
X2471534Y1089533D01*
X2472292Y1089100D01*
X2473266Y1088956D01*
X2474240Y1089245D01*
X2474998Y1089822D01*
X2475540Y1090832D01*
X2475648Y1091987D01*
X2475431Y1093142D01*
X2474890Y1093864D01*
X2474132Y1094441D01*
X2473374Y1094586D01*
X2472616Y1094441D01*
X2471642Y1093864D01*
X2471967Y1097617D01*
X2474890D01*
G01X2429508Y1125505D02*
X2430158Y1126370D01*
X2430915Y1126804D01*
X2431782Y1126948D01*
X2432864Y1126659D01*
X2433622Y1125938D01*
X2433839Y1125072D01*
X2433730Y1124205D01*
X2433297Y1123484D01*
X2431132Y1122040D01*
X2430158Y1121030D01*
X2429508Y1119586D01*
X2429291Y1118287D01*
X2433839D01*
G01X2438169Y1121896D02*
X2438927Y1122906D01*
X2439576Y1123484D01*
X2440443Y1123772D01*
X2441200Y1123484D01*
X2441742Y1122906D01*
X2442175Y1122040D01*
X2442283Y1121030D01*
X2442175Y1120163D01*
X2441742Y1119297D01*
X2441092Y1118576D01*
X2440334Y1118287D01*
X2439468Y1118576D01*
X2438710Y1119442D01*
X2438277Y1120741D01*
X2438169Y1122184D01*
X2438385Y1124061D01*
X2438710Y1125072D01*
X2439252Y1126082D01*
X2440009Y1126804D01*
X2440767Y1126948D01*
X2441525Y1126659D01*
X2442067Y1125938D01*
G01X2448887Y1126948D02*
X2448021Y1126659D01*
X2447371Y1125938D01*
X2446938Y1125072D01*
X2446613Y1123917D01*
X2446505Y1122617D01*
X2446613Y1121318D01*
X2446938Y1120163D01*
X2447371Y1119297D01*
X2448021Y1118576D01*
X2448887Y1118287D01*
X2449753Y1118576D01*
X2450403Y1119297D01*
X2450836Y1120163D01*
X2451161Y1121318D01*
X2451269Y1122617D01*
X2451161Y1123917D01*
X2450836Y1125072D01*
X2450403Y1125938D01*
X2449753Y1126659D01*
X2448887Y1126948D01*
G01X2457548Y1117998D02*
X2457331Y1118143D01*
Y1118431D01*
X2457548Y1118576D01*
X2457765Y1118431D01*
Y1118143D01*
X2457548Y1117998D01*
G01X2466209Y1126948D02*
X2465343Y1126659D01*
X2464693Y1125938D01*
X2464260Y1125072D01*
X2463935Y1123917D01*
X2463827Y1122617D01*
X2463935Y1121318D01*
X2464260Y1120163D01*
X2464693Y1119297D01*
X2465343Y1118576D01*
X2466209Y1118287D01*
X2467075Y1118576D01*
X2467725Y1119297D01*
X2468158Y1120163D01*
X2468483Y1121318D01*
X2468591Y1122617D01*
X2468483Y1123917D01*
X2468158Y1125072D01*
X2467725Y1125938D01*
X2467075Y1126659D01*
X2466209Y1126948D01*
G01X2474870D02*
X2474004Y1126659D01*
X2473354Y1125938D01*
X2472921Y1125072D01*
X2472596Y1123917D01*
X2472488Y1122617D01*
X2472596Y1121318D01*
X2472921Y1120163D01*
X2473354Y1119297D01*
X2474004Y1118576D01*
X2474870Y1118287D01*
X2475736Y1118576D01*
X2476386Y1119297D01*
X2476819Y1120163D01*
X2477144Y1121318D01*
X2477252Y1122617D01*
X2477144Y1123917D01*
X2476819Y1125072D01*
X2476386Y1125938D01*
X2475736Y1126659D01*
X2474870Y1126948D01*
G01X2439979Y103326D02*
X2439113Y103037D01*
X2438463Y102316D01*
X2438030Y101450D01*
X2437705Y100295D01*
X2437597Y98995D01*
X2437705Y97696D01*
X2438030Y96541D01*
X2438463Y95675D01*
X2439113Y94954D01*
X2439979Y94665D01*
X2440845Y94954D01*
X2441495Y95675D01*
X2441928Y96541D01*
X2442253Y97696D01*
X2442361Y98995D01*
X2442253Y100295D01*
X2441928Y101450D01*
X2441495Y102316D01*
X2440845Y103037D01*
X2439979Y103326D01*
G01X2448640Y94376D02*
X2448423Y94521D01*
Y94809D01*
X2448640Y94954D01*
X2448857Y94809D01*
Y94521D01*
X2448640Y94376D01*
G01X2457301Y103326D02*
X2456435Y103037D01*
X2455785Y102316D01*
X2455352Y101450D01*
X2455027Y100295D01*
X2454919Y98995D01*
X2455027Y97696D01*
X2455352Y96541D01*
X2455785Y95675D01*
X2456435Y94954D01*
X2457301Y94665D01*
X2458167Y94954D01*
X2458817Y95675D01*
X2459250Y96541D01*
X2459575Y97696D01*
X2459683Y98995D01*
X2459575Y100295D01*
X2459250Y101450D01*
X2458817Y102316D01*
X2458167Y103037D01*
X2457301Y103326D01*
G01X2465962D02*
X2465096Y103037D01*
X2464446Y102316D01*
X2464013Y101450D01*
X2463688Y100295D01*
X2463580Y98995D01*
X2463688Y97696D01*
X2464013Y96541D01*
X2464446Y95675D01*
X2465096Y94954D01*
X2465962Y94665D01*
X2466828Y94954D01*
X2467478Y95675D01*
X2467911Y96541D01*
X2468236Y97696D01*
X2468344Y98995D01*
X2468236Y100295D01*
X2467911Y101450D01*
X2467478Y102316D01*
X2466828Y103037D01*
X2465962Y103326D01*
G01X2439821D02*
X2438955Y103037D01*
X2438305Y102316D01*
X2437872Y101450D01*
X2437547Y100295D01*
X2437439Y98995D01*
X2437547Y97696D01*
X2437872Y96541D01*
X2438305Y95675D01*
X2438955Y94954D01*
X2439821Y94665D01*
X2440687Y94954D01*
X2441337Y95675D01*
X2441770Y96541D01*
X2442095Y97696D01*
X2442203Y98995D01*
X2442095Y100295D01*
X2441770Y101450D01*
X2441337Y102316D01*
X2440687Y103037D01*
X2439821Y103326D01*
G01X2448482Y94376D02*
X2448265Y94521D01*
Y94809D01*
X2448482Y94954D01*
X2448699Y94809D01*
Y94521D01*
X2448482Y94376D01*
G01X2457143Y103326D02*
X2456277Y103037D01*
X2455627Y102316D01*
X2455194Y101450D01*
X2454869Y100295D01*
X2454761Y98995D01*
X2454869Y97696D01*
X2455194Y96541D01*
X2455627Y95675D01*
X2456277Y94954D01*
X2457143Y94665D01*
X2458009Y94954D01*
X2458659Y95675D01*
X2459092Y96541D01*
X2459417Y97696D01*
X2459525Y98995D01*
X2459417Y100295D01*
X2459092Y101450D01*
X2458659Y102316D01*
X2458009Y103037D01*
X2457143Y103326D01*
G01X2465804D02*
X2464938Y103037D01*
X2464288Y102316D01*
X2463855Y101450D01*
X2463530Y100295D01*
X2463422Y98995D01*
X2463530Y97696D01*
X2463855Y96541D01*
X2464288Y95675D01*
X2464938Y94954D01*
X2465804Y94665D01*
X2466670Y94954D01*
X2467320Y95675D01*
X2467753Y96541D01*
X2468078Y97696D01*
X2468186Y98995D01*
X2468078Y100295D01*
X2467753Y101450D01*
X2467320Y102316D01*
X2466670Y103037D01*
X2465804Y103326D01*
G01X2466266Y-1837784D02*
Y-1856796D01*
G01X2520563Y92500D02*
X2473541D01*
G01X2520563D02*
X2473382D01*
G01X2466266Y1453929D02*
Y1434916D01*
G01X2487500Y-1293500D02*
X2499311D01*
G01X2487500Y-1281689D02*
Y-1293500D01*
G01Y-974563D02*
G03X2499311Y-986374I11811J0D01*
G01X2487500Y-324996D02*
Y-974563D01*
G01X2503248Y-864366D02*
X2487500D01*
G01X2500059Y-646413D02*
X2492185D01*
G01D02*
Y-645429D01*
G01X2495535Y-633782D02*
X2496708D01*
G01X2495368Y-634602D02*
X2496875D01*
G01X2494698Y-635915D02*
X2495368D01*
G01Y-638539D02*
X2494698D01*
G01X2492185Y-639852D02*
X2500059D01*
G01X2495368Y-640836D02*
X2492185D01*
G01X2500059D02*
X2496373D01*
G01Y-645429D02*
X2500059D01*
G01X2492185D02*
X2495368D01*
G01X2494530Y-634438D02*
X2495368Y-634602D01*
G01X2494530Y-633618D02*
X2495535Y-633782D01*
G01X2494027Y-634274D02*
X2494530Y-634438D01*
G01X2493357Y-633946D02*
X2494027Y-634274D01*
G01X2493525Y-632962D02*
X2494530Y-633618D01*
G01X2492855Y-633454D02*
X2493357Y-633946D01*
G01X2492352Y-632633D02*
X2492855Y-633454D01*
G01X2496373Y-640836D02*
Y-645429D01*
G01X2495368D02*
Y-640836D01*
G01Y-635915D02*
Y-638539D01*
G01X2494698D02*
Y-635915D01*
G01X2492185Y-640836D02*
Y-639852D01*
G01X2495535Y-629517D02*
X2494530Y-629681D01*
G01X2496708Y-629517D02*
X2495535D01*
G01X2493190Y-632470D02*
X2493525Y-632962D01*
G01X2494530Y-628861D02*
X2494027Y-629025D01*
G01D02*
X2493357Y-629353D01*
G01X2494530Y-629681D02*
X2493525Y-630337D01*
G01X2492185Y-631649D02*
X2492352Y-632633D01*
G01X2493022Y-631649D02*
X2493190Y-632470D01*
G01X2493357Y-629353D02*
X2492855Y-629845D01*
G01X2493525Y-630337D02*
X2493190Y-630829D01*
G01X2492855Y-629845D02*
X2492352Y-630665D01*
G01X2493190Y-630829D02*
X2493022Y-631649D01*
G01X2492352Y-630665D02*
X2492185Y-631649D01*
G01X2495368Y-628696D02*
X2494530Y-628861D01*
G01X2500059Y-617378D02*
X2496038D01*
G01X2495870Y-619182D02*
X2500059D01*
G01X2494698D02*
X2495200D01*
G01X2500059Y-620002D02*
X2494698D01*
G01X2496038Y-621315D02*
X2500059D01*
G01Y-622135D02*
X2496038D01*
G01Y-623939D02*
X2500059D01*
G01Y-624759D02*
X2496038D01*
G01X2495870Y-626564D02*
X2500059D01*
G01X2494698D02*
X2495200D01*
G01X2500059Y-627384D02*
X2494698D01*
G01X2496875Y-628696D02*
X2495368D01*
G01X2495703Y-623775D02*
X2496038Y-623939D01*
G01X2495368Y-616722D02*
X2494865Y-616229D01*
G01X2495535Y-618854D02*
X2495870Y-619182D01*
G01X2495200D02*
X2494865Y-618854D01*
G01X2495535Y-623611D02*
X2495703Y-623775D01*
G01X2495368Y-624104D02*
X2494865Y-623611D01*
G01X2495535Y-626236D02*
X2495870Y-626564D01*
G01X2495200D02*
X2494865Y-626236D01*
G01X2495200Y-621643D02*
X2496038Y-621315D01*
G01X2495368Y-623283D02*
X2495535Y-623611D01*
G01X2496038Y-624759D02*
X2495703Y-624924D01*
G01X2496038Y-622135D02*
X2495703Y-622299D01*
G01X2496038Y-617378D02*
X2495703Y-617542D01*
G01X2495368Y-618362D02*
X2495535Y-618854D01*
G01X2494865D02*
X2494698Y-618362D01*
G01X2494865Y-623611D02*
X2494698Y-623119D01*
G01X2495368Y-625744D02*
X2495535Y-626236D01*
G01X2494865D02*
X2494698Y-625744D01*
G01X2495703Y-624924D02*
X2495535Y-625088D01*
G01X2494865Y-624596D02*
X2495368Y-624104D01*
G01X2495703Y-622299D02*
X2495535Y-622463D01*
G01X2494865Y-621971D02*
X2495200Y-621643D01*
G01X2495703Y-617542D02*
X2495535Y-617706D01*
G01X2494865Y-617214D02*
X2495368Y-616722D01*
G01X2495535Y-625088D02*
X2495368Y-625416D01*
G01X2495535Y-622463D02*
X2495368Y-622791D01*
G01X2495535Y-617706D02*
X2495368Y-618034D01*
G01Y-625416D02*
Y-625744D01*
G01Y-622791D02*
Y-623283D01*
G01Y-618034D02*
Y-618362D01*
G01X2494698D02*
Y-617706D01*
G01Y-620002D02*
Y-619182D01*
G01Y-623119D02*
Y-622463D01*
G01Y-625744D02*
Y-625088D01*
G01Y-627384D02*
Y-626564D01*
G01Y-625088D02*
X2494865Y-624596D01*
G01X2494698Y-622463D02*
X2494865Y-621971D01*
G01X2494698Y-617706D02*
X2494865Y-617214D01*
G01X2496038Y-613933D02*
X2500059D01*
G01Y-614753D02*
X2496038D01*
G01Y-616557D02*
X2500059D01*
G01X2495703Y-616393D02*
X2496038Y-616557D01*
G01X2495535Y-616229D02*
X2495703Y-616393D01*
G01X2495368Y-615901D02*
X2495535Y-616229D01*
G01X2495200Y-614261D02*
X2496038Y-613933D01*
G01Y-614753D02*
X2495703Y-614917D01*
G01X2494865Y-616229D02*
X2494698Y-615737D01*
G01X2495703Y-614917D02*
X2495535Y-615081D01*
G01X2494865Y-614589D02*
X2495200Y-614261D01*
G01X2495535Y-615081D02*
X2495368Y-615409D01*
G01D02*
Y-615901D01*
G01X2494698Y-615737D02*
Y-615081D01*
G01D02*
X2494865Y-614589D01*
G01X2507185Y-305311D02*
G03X2487500Y-324996I0J-19685D01*
G01X2660326Y1086791D02*
X2480845D01*
G01X2630208Y1116122D02*
X2482448D01*
G01X2587893Y-986374D02*
X2499311D01*
G01X2514665Y-955704D02*
G03I-7874J0D01*
G01X2516633D02*
G03I-9842J0D01*
G01X2511712D02*
G03I-4921J0D01*
G01X2511771Y-920271D02*
G03I-3051J0D01*
G01X2511712Y-896649D02*
G03I-4921J0D01*
G01X2514665D02*
G03I-7874J0D01*
G01X2516633D02*
G03I-9842J0D01*
G01X2503248Y-305709D02*
Y-864366D01*
G01X2500059Y-645429D02*
Y-646413D01*
G01X2496708Y-633782D02*
X2497713Y-633618D01*
G01X2496875Y-634602D02*
X2497713Y-634438D01*
G01X2496708Y-635915D02*
X2497378D01*
G01Y-638539D02*
X2496708D01*
G01X2497713Y-634438D02*
X2498216Y-634274D01*
G01D02*
X2498886Y-633946D01*
G01X2497713Y-633618D02*
X2498718Y-632962D01*
G01X2498886Y-633946D02*
X2499388Y-633454D01*
G01D02*
X2499891Y-632633D01*
G01X2500059Y-639852D02*
Y-640836D01*
G01X2497378Y-635915D02*
Y-638539D01*
G01X2496708D02*
Y-635915D01*
G01X2497713Y-629681D02*
X2496708Y-629517D01*
G01X2498216Y-629025D02*
X2497713Y-628861D01*
G01X2498886Y-629353D02*
X2498216Y-629025D01*
G01X2498718Y-630337D02*
X2497713Y-629681D01*
G01X2499388Y-629845D02*
X2498886Y-629353D01*
G01X2499891Y-630665D02*
X2499388Y-629845D01*
G01X2499053Y-630829D02*
X2498718Y-630337D01*
G01X2500059Y-631649D02*
X2499891Y-630665D01*
G01X2499221Y-631649D02*
X2499053Y-630829D01*
G01X2498718Y-632962D02*
X2499053Y-632470D01*
G01D02*
X2499221Y-631649D01*
G01X2499891Y-632633D02*
X2500059Y-631649D01*
G01X2497713Y-628861D02*
X2496875Y-628696D01*
G01X2500059Y-623939D02*
Y-624759D01*
G01Y-626564D02*
Y-627384D01*
G01Y-619182D02*
Y-620002D01*
G01Y-621315D02*
Y-622135D01*
G01Y-616557D02*
Y-617378D01*
G01Y-613933D02*
Y-614753D01*
G01X2591240Y-305311D02*
X2507185D01*
G01X2513673Y-5040D02*
X2513962Y-5906D01*
X2514683Y-6556D01*
X2515549Y-6989D01*
X2516704Y-7314D01*
X2518004Y-7422D01*
X2519303Y-7314D01*
X2520458Y-6989D01*
X2521324Y-6556D01*
X2522045Y-5906D01*
X2522334Y-5040D01*
X2522045Y-4174D01*
X2521324Y-3524D01*
X2520458Y-3091D01*
X2519303Y-2766D01*
X2518004Y-2658D01*
X2516704Y-2766D01*
X2515549Y-3091D01*
X2514683Y-3524D01*
X2513962Y-4174D01*
X2513673Y-5040D01*
G01X2522623Y3621D02*
X2522478Y3404D01*
X2522190D01*
X2522045Y3621D01*
X2522190Y3838D01*
X2522478D01*
X2522623Y3621D01*
G01X2513673Y12282D02*
X2513962Y11416D01*
X2514683Y10766D01*
X2515549Y10333D01*
X2516704Y10008D01*
X2518004Y9900D01*
X2519303Y10008D01*
X2520458Y10333D01*
X2521324Y10766D01*
X2522045Y11416D01*
X2522334Y12282D01*
X2522045Y13148D01*
X2521324Y13798D01*
X2520458Y14231D01*
X2519303Y14556D01*
X2518004Y14664D01*
X2516704Y14556D01*
X2515549Y14231D01*
X2514683Y13798D01*
X2513962Y13148D01*
X2513673Y12282D01*
G01Y20943D02*
X2513962Y20077D01*
X2514683Y19427D01*
X2515549Y18994D01*
X2516704Y18669D01*
X2518004Y18561D01*
X2519303Y18669D01*
X2520458Y18994D01*
X2521324Y19427D01*
X2522045Y20077D01*
X2522334Y20943D01*
X2522045Y21809D01*
X2521324Y22459D01*
X2520458Y22892D01*
X2519303Y23217D01*
X2518004Y23325D01*
X2516704Y23217D01*
X2515549Y22892D01*
X2514683Y22459D01*
X2513962Y21809D01*
X2513673Y20943D01*
G01Y-5040D02*
X2513962Y-5906D01*
X2514683Y-6556D01*
X2515549Y-6989D01*
X2516704Y-7314D01*
X2518004Y-7422D01*
X2519303Y-7314D01*
X2520458Y-6989D01*
X2521324Y-6556D01*
X2522045Y-5906D01*
X2522334Y-5040D01*
X2522045Y-4174D01*
X2521324Y-3524D01*
X2520458Y-3091D01*
X2519303Y-2766D01*
X2518004Y-2658D01*
X2516704Y-2766D01*
X2515549Y-3091D01*
X2514683Y-3524D01*
X2513962Y-4174D01*
X2513673Y-5040D01*
G01X2522623Y3621D02*
X2522478Y3404D01*
X2522190D01*
X2522045Y3621D01*
X2522190Y3838D01*
X2522478D01*
X2522623Y3621D01*
G01X2513673Y12282D02*
X2513962Y11416D01*
X2514683Y10766D01*
X2515549Y10333D01*
X2516704Y10008D01*
X2518004Y9900D01*
X2519303Y10008D01*
X2520458Y10333D01*
X2521324Y10766D01*
X2522045Y11416D01*
X2522334Y12282D01*
X2522045Y13148D01*
X2521324Y13798D01*
X2520458Y14231D01*
X2519303Y14556D01*
X2518004Y14664D01*
X2516704Y14556D01*
X2515549Y14231D01*
X2514683Y13798D01*
X2513962Y13148D01*
X2513673Y12282D01*
G01Y20943D02*
X2513962Y20077D01*
X2514683Y19427D01*
X2515549Y18994D01*
X2516704Y18669D01*
X2518004Y18561D01*
X2519303Y18669D01*
X2520458Y18994D01*
X2521324Y19427D01*
X2522045Y20077D01*
X2522334Y20943D01*
X2522045Y21809D01*
X2521324Y22459D01*
X2520458Y22892D01*
X2519303Y23217D01*
X2518004Y23325D01*
X2516704Y23217D01*
X2515549Y22892D01*
X2514683Y22459D01*
X2513962Y21809D01*
X2513673Y20943D01*
G01X2524500Y88563D02*
Y28521D01*
G01Y88563D02*
Y28521D01*
G01Y92500D02*
X2536311D01*
G01X2524500Y104311D02*
Y92500D01*
G01Y411437D02*
G03X2536311Y399626I11811J0D01*
G01X2524500Y1061004D02*
Y411437D01*
G01X2536665Y745492D02*
X2528791D01*
G01D02*
Y746476D01*
G01Y752054D02*
X2536665D01*
G01X2531974Y751069D02*
X2528791D01*
G01Y746476D02*
X2531974D01*
G01X2528791Y751069D02*
Y752054D01*
G01X2528959Y759271D02*
X2529461Y758451D01*
G01X2528791Y760256D02*
X2528959Y759271D01*
G01X2529461Y762060D02*
X2528959Y761240D01*
G01D02*
X2528791Y760256D01*
G01X2544185Y1080689D02*
G03X2524500Y1061004I0J-19685D01*
G01X2527115Y1070807D02*
X2600466Y1028681D01*
G01X2621429Y368130D02*
X2545681D01*
G01D02*
X2546862Y366948D01*
G01X2545681Y394507D02*
Y368130D01*
G01X2628732Y394507D02*
X2538378D01*
G01X2541921Y398444D02*
Y394507D01*
G01X2538378Y519586D02*
Y394507D01*
G01X2624893Y399626D02*
X2536311D01*
G01X2538378Y398444D02*
X2546549D01*
G01X2544775D02*
Y519586D01*
G01X2543988D02*
Y398444D01*
G01X2542807Y519586D02*
Y398444D01*
G01X2542748D02*
Y422421D01*
G01X2546547Y401555D02*
X2541606D01*
G01Y515649D02*
Y401555D01*
G01X2545582D02*
Y515649D01*
G01X2543614D02*
Y401555D01*
G01X2542590Y515649D02*
Y401555D01*
G01X2547728Y430295D02*
G03I-3937J0D01*
G01X2548712D02*
G03I-4921J0D01*
G01X2551665D02*
G03I-7874J0D01*
G01X2542748Y422421D02*
X2538378D01*
G01X2542748Y438169D02*
X2538378D01*
G01X2542748D02*
Y481476D01*
G01X2547610Y465728D02*
G03I-1890J0D01*
G01X2548594D02*
G03I-2874J0D01*
G01X2548771D02*
G03I-3051J0D01*
G01X2551665Y489350D02*
G03I-7874J0D01*
G01X2542748Y481476D02*
X2538378D01*
G01X2547728Y489350D02*
G03I-3937J0D01*
G01X2548712D02*
G03I-4921J0D01*
G01X2542748Y497224D02*
X2538378D01*
G01X2542748Y519586D02*
Y497224D01*
G01X2549677Y515649D02*
X2541606D01*
G01X2540248Y521633D02*
X3409145D01*
G01X2538378Y519586D02*
X2628732D01*
G01X2540248Y1080291D02*
Y521633D01*
G01X2536665Y746476D02*
Y745492D01*
G01X2533315Y755991D02*
X2533985D01*
G01X2531304D02*
X2531974D01*
G01X2533985Y753366D02*
X2533315D01*
G01X2531974D02*
X2531304D01*
G01X2536665Y751069D02*
X2532980D01*
G01Y746476D02*
X2536665D01*
G01Y752054D02*
Y751069D01*
G01X2533985Y755991D02*
Y753366D01*
G01X2533315D02*
Y755991D01*
G01X2532980Y751069D02*
Y746476D01*
G01X2531974D02*
Y751069D01*
G01Y755991D02*
Y753366D01*
G01X2531304D02*
Y755991D01*
G01X2532142Y762388D02*
X2531137Y762224D01*
G01X2533315Y758123D02*
X2534320Y758287D01*
G01X2533482Y757303D02*
X2534320Y757467D01*
G01X2532142Y758123D02*
X2533315D01*
G01X2531974Y757303D02*
X2533482D01*
G01X2531137Y757467D02*
X2531974Y757303D01*
G01X2534320Y762224D02*
X2533315Y762388D01*
G01X2531137Y758287D02*
X2532142Y758123D01*
G01X2530634Y757631D02*
X2531137Y757467D01*
G01X2529964Y757959D02*
X2530634Y757631D01*
G01X2535325Y761568D02*
X2534320Y762224D01*
G01X2530132Y758943D02*
X2531137Y758287D01*
G01X2535995Y762060D02*
X2535493Y762552D01*
G01X2529461Y758451D02*
X2529964Y757959D01*
G01X2536498Y761240D02*
X2535995Y762060D01*
G01X2535660Y761076D02*
X2535325Y761568D01*
G01X2529796Y759435D02*
X2530132Y758943D01*
G01X2534320Y757467D02*
X2534822Y757631D01*
G01D02*
X2535493Y757959D01*
G01X2534320Y758287D02*
X2535325Y758943D01*
G01X2531137Y762224D02*
X2530132Y761568D01*
G01X2536665Y760256D02*
X2536498Y761240D01*
G01X2535828Y760256D02*
X2535660Y761076D01*
G01X2529629Y760256D02*
X2529796Y759435D01*
G01X2535493Y757959D02*
X2535995Y758451D01*
G01X2529964Y762552D02*
X2529461Y762060D01*
G01X2535325Y758943D02*
X2535660Y759435D01*
G01X2530132Y761568D02*
X2529796Y761076D01*
G01X2535995Y758451D02*
X2536498Y759271D01*
G01X2535660Y759435D02*
X2535828Y760256D01*
G01X2529796Y761076D02*
X2529629Y760256D01*
G01X2536498Y759271D02*
X2536665Y760256D01*
G01X2531974Y763208D02*
X2531137Y763044D01*
G01X2531304Y772723D02*
X2531807D01*
G01X2532477D02*
X2536665D01*
G01Y771902D02*
X2531304D01*
G01X2532645Y770590D02*
X2536665D01*
G01Y769770D02*
X2532645D01*
G01Y767965D02*
X2536665D01*
G01Y767145D02*
X2532645D01*
G01X2531304Y765341D02*
X2531807D01*
G01X2532477D02*
X2536665D01*
G01Y764520D02*
X2531304D01*
G01X2533482Y763208D02*
X2531974D01*
G01X2533315Y762388D02*
X2532142D01*
G01X2534320Y763044D02*
X2533482Y763208D01*
G01X2534822Y762880D02*
X2534320Y763044D01*
G01X2532309Y768130D02*
X2532645Y767965D01*
G01X2535493Y762552D02*
X2534822Y762880D01*
G01X2532142Y773051D02*
X2532477Y772723D01*
G01X2531807D02*
X2531472Y773051D01*
G01X2532142Y768294D02*
X2532309Y768130D01*
G01X2531974Y767802D02*
X2531472Y768294D01*
G01X2532142Y765669D02*
X2532477Y765341D01*
G01X2531807D02*
X2531472Y765669D01*
G01X2531137Y763044D02*
X2530634Y762880D01*
G01X2531974Y768622D02*
X2532142Y768294D01*
G01X2531807Y770262D02*
X2532645Y770590D01*
G01X2530634Y762880D02*
X2529964Y762552D01*
G01X2532645Y767145D02*
X2532309Y766981D01*
G01X2532645Y769770D02*
X2532309Y769606D01*
G01X2531974Y773543D02*
X2532142Y773051D01*
G01X2531472D02*
X2531304Y773543D01*
G01X2531472Y768294D02*
X2531304Y768786D01*
G01X2531974Y766161D02*
X2532142Y765669D01*
G01X2531472D02*
X2531304Y766161D01*
G01X2532309Y766981D02*
X2532142Y766817D01*
G01X2531472Y767309D02*
X2531974Y767802D01*
G01X2532309Y769606D02*
X2532142Y769442D01*
G01X2531472Y769934D02*
X2531807Y770262D01*
G01X2532142Y766817D02*
X2531974Y766489D01*
G01X2532142Y769442D02*
X2531974Y769114D01*
G01X2536665Y765341D02*
Y764520D01*
G01Y770590D02*
Y769770D01*
G01Y767965D02*
Y767145D01*
G01Y772723D02*
Y771902D01*
G01X2531974Y766489D02*
Y766161D01*
G01Y769114D02*
Y768622D01*
G01X2531304Y771902D02*
Y772723D01*
G01Y766161D02*
Y766817D01*
G01Y768786D02*
Y769442D01*
G01Y764520D02*
Y765341D01*
G01Y766817D02*
X2531472Y767309D01*
G01X2531304Y769442D02*
X2531472Y769934D01*
G01X2532645Y777972D02*
X2536665D01*
G01Y777152D02*
X2532645D01*
G01Y775347D02*
X2536665D01*
G01Y774527D02*
X2532645D01*
G01X2532309Y775511D02*
X2532645Y775347D01*
G01X2532142Y775676D02*
X2532309Y775511D01*
G01X2531974Y775183D02*
X2531472Y775676D01*
G01X2531974Y776004D02*
X2532142Y775676D01*
G01X2531807Y777644D02*
X2532645Y777972D01*
G01Y774527D02*
X2532309Y774363D01*
G01X2532645Y777152D02*
X2532309Y776988D01*
G01X2531472Y775676D02*
X2531304Y776168D01*
G01X2532309Y774363D02*
X2532142Y774199D01*
G01X2531472Y774691D02*
X2531974Y775183D01*
G01X2532309Y776988D02*
X2532142Y776824D01*
G01X2531472Y777316D02*
X2531807Y777644D01*
G01X2536665Y775347D02*
Y774527D01*
G01Y777972D02*
Y777152D01*
G01X2531974Y773871D02*
Y773543D01*
G01Y776496D02*
Y776004D01*
G01X2531304Y776168D02*
Y776824D01*
G01Y773543D02*
Y774199D01*
G01X2532142D02*
X2531974Y773871D01*
G01X2532142Y776824D02*
X2531974Y776496D01*
G01X2531304Y774199D02*
X2531472Y774691D01*
G01X2531304Y776824D02*
X2531472Y777316D01*
G01X2544185Y1080689D02*
G03X2540248Y1080291I1J-19685D01*
G01X3409145Y1080689D02*
X2544185D01*
G01X2628240D02*
X2544185D01*
G01X2620248Y366948D02*
X2546862D01*
G01X2550602Y405492D02*
Y366948D01*
G01X2548633Y405492D02*
Y366948D01*
G01X2550208Y370885D02*
G03X2551783Y372460I0J1575D01*
G01D02*
X2548633D01*
G01X2550208Y370885D02*
X2548633D01*
G01X2551783Y405492D02*
Y372460D01*
G01X2546763Y394507D02*
Y398444D01*
G01X2620563Y400413D02*
X2546547D01*
G01X2620563Y399429D02*
X2546547D01*
G01X2546763Y398444D02*
X2620346D01*
G01X2546549D02*
X2546763D01*
G01X2546547Y401555D02*
Y398444D01*
G01X2546271Y519586D02*
Y398444D01*
G01X2618476Y405492D02*
X2548633D01*
G01X2618476Y416122D02*
X2548633D01*
G01Y511279D02*
Y416122D01*
G01X2557177Y459455D02*
X2562439D01*
G01Y458077D02*
X2557177D01*
G01X2609933Y454297D02*
X2557177D01*
G01X2560326Y457797D02*
X2557726Y454297D01*
G01X2557177Y499591D02*
Y454297D01*
G01X2561795Y466833D02*
G03Y464623I-1862J-1105D01*
G01X2557283Y464970D02*
G03X2561795Y463696I2650J758D01*
G01Y467759D02*
G03X2557283Y466486I-1863J-2031D01*
G01Y464970D02*
Y466486D01*
G01X2607163Y457287D02*
X2559947D01*
G01X2560326Y478419D02*
Y457797D01*
G01X2561795Y467759D02*
Y463696D01*
G01X2562439Y469592D02*
X2557177D01*
G01X2562439Y469413D02*
X2557177D01*
G01X2606783Y477632D02*
X2560326D01*
G01X2606783Y478419D02*
X2560326D01*
G01X2557177Y493299D02*
X2560130D01*
G01Y492906D02*
X2557177D01*
G01Y492512D02*
X2560130D01*
G01X2557177Y491724D02*
X2609933D01*
G01Y485682D02*
X2557177D01*
G01X2609933Y483372D02*
X2557177D01*
G01X2560130Y499591D02*
X2557177D01*
G01X2575431Y488074D02*
X2560130D01*
G01X2576218Y487287D02*
X2560130D01*
G01X2606980Y486500D02*
X2560130D01*
G01Y499591D02*
Y486500D01*
G01Y495868D02*
X2606980D01*
G01X2618476Y507342D02*
X2548633D01*
G01Y511279D02*
X2565641D01*
G01X2549677Y524941D02*
Y515649D01*
G01Y524941D02*
X2617433D01*
G01Y524506D02*
X2549677D01*
G01Y523956D02*
X2617433D01*
G01X2549677Y523614D02*
X2617433D01*
G01X2549677Y521680D02*
X2617433D01*
G01X2549677Y521306D02*
X2617433D01*
G01Y521089D02*
X2549677D01*
G01Y520964D02*
X2617433D01*
G01Y520729D02*
X2549677D01*
G01X2617433Y520414D02*
X2549677D01*
G01X2617433Y520305D02*
X2549677D01*
G01Y520138D02*
X2617433D01*
G01X2549677Y519980D02*
X2617433D01*
G01X2573210Y-1852994D02*
Y-1841587D01*
X2571499Y-1843868D01*
G01Y-1852994D02*
X2574921D01*
G01X2586329D02*
Y-1841587D01*
X2581053Y-1849762D01*
X2588183D01*
G01X2596161Y-955704D02*
G03I-9843J0D01*
G01X2594192D02*
G03I-7874J0D01*
G01Y-896649D02*
G03I-7874J0D01*
G01X2596161D02*
G03I-9843J0D01*
G01X2567268Y235548D02*
Y244209D01*
X2572248Y235548D01*
Y244209D01*
G01X2578419Y235548D02*
X2577769Y235692D01*
X2577120Y236270D01*
X2576687Y237280D01*
X2576470Y238435D01*
X2576687Y239590D01*
X2577120Y240600D01*
X2577769Y241178D01*
X2578419Y241322D01*
X2579069Y241178D01*
X2579718Y240600D01*
X2580151Y239590D01*
X2580260Y238435D01*
X2580151Y237280D01*
X2579718Y236270D01*
X2579069Y235692D01*
X2578419Y235548D01*
G01X2595741Y244209D02*
Y235548D01*
G01X2594225Y241322D02*
X2597257D01*
G01X2602886Y235548D02*
Y241322D01*
G01Y240167D02*
X2603428Y240745D01*
X2603969Y241178D01*
X2604727Y241322D01*
X2605268Y241178D01*
X2605918Y240745D01*
G01X2615012Y235548D02*
Y241322D01*
G01Y240312D02*
X2614579Y240889D01*
X2613929Y241178D01*
X2613171Y241322D01*
X2612413Y241033D01*
X2611764Y240456D01*
X2611331Y239590D01*
X2611114Y238435D01*
X2611331Y237280D01*
X2611764Y236414D01*
X2612413Y235837D01*
X2613171Y235548D01*
X2613929Y235692D01*
X2614579Y236125D01*
X2615012Y236703D01*
G01X2623456Y240600D02*
X2622698Y241178D01*
X2622049Y241322D01*
X2621183Y241033D01*
X2620533Y240456D01*
X2620100Y239445D01*
X2619992Y238435D01*
X2620100Y237424D01*
X2620533Y236558D01*
X2621183Y235837D01*
X2622049Y235548D01*
X2622807Y235837D01*
X2623456Y236414D01*
G01X2628761Y239445D02*
X2632226D01*
X2631901Y240456D01*
X2631359Y241033D01*
X2630602Y241322D01*
X2629844Y241178D01*
X2629194Y240745D01*
X2628761Y239734D01*
X2628544Y238868D01*
Y238002D01*
X2628761Y237136D01*
X2629302Y236270D01*
X2629952Y235692D01*
X2630710Y235548D01*
X2631468Y235837D01*
X2632226Y236703D01*
G01X2649656Y235548D02*
Y241322D01*
G01Y240312D02*
X2649223Y240889D01*
X2648573Y241178D01*
X2647815Y241322D01*
X2647057Y241033D01*
X2646408Y240456D01*
X2645975Y239590D01*
X2645758Y238435D01*
X2645975Y237280D01*
X2646408Y236414D01*
X2647057Y235837D01*
X2647815Y235548D01*
X2648573Y235692D01*
X2649223Y236125D01*
X2649656Y236703D01*
G01X2656368Y244209D02*
Y235548D01*
G01X2654852Y241322D02*
X2657884D01*
G01X2672066Y236558D02*
X2672607Y235981D01*
X2673365Y235548D01*
X2674015D01*
X2674664Y235837D01*
X2675097Y236270D01*
X2675314Y236847D01*
X2675206Y237713D01*
X2674773Y238146D01*
X2672824Y239012D01*
X2672391Y240023D01*
X2672607Y240745D01*
X2673040Y241178D01*
X2673690Y241322D01*
X2674340Y241178D01*
X2674989Y240745D01*
G01X2680510Y241322D02*
Y237280D01*
X2680944Y236270D01*
X2681593Y235692D01*
X2682351Y235548D01*
X2683109Y235692D01*
X2683758Y236270D01*
X2684192Y237280D01*
G01Y235548D02*
Y241322D01*
G01X2689496Y235548D02*
Y241322D01*
G01Y240167D02*
X2690038Y240745D01*
X2690579Y241178D01*
X2691337Y241322D01*
X2691878Y241178D01*
X2692528Y240745D01*
G01X2699023Y235548D02*
Y242910D01*
X2699240Y243631D01*
X2699673Y244065D01*
X2700323Y244209D01*
X2700972Y243920D01*
X2701297Y243199D01*
G01X2699998Y240745D02*
X2697832D01*
G01X2710283Y235548D02*
Y241322D01*
G01Y240312D02*
X2709850Y240889D01*
X2709200Y241178D01*
X2708442Y241322D01*
X2707684Y241033D01*
X2707035Y240456D01*
X2706602Y239590D01*
X2706385Y238435D01*
X2706602Y237280D01*
X2707035Y236414D01*
X2707684Y235837D01*
X2708442Y235548D01*
X2709200Y235692D01*
X2709850Y236125D01*
X2710283Y236703D01*
G01X2718727Y240600D02*
X2717969Y241178D01*
X2717320Y241322D01*
X2716454Y241033D01*
X2715804Y240456D01*
X2715371Y239445D01*
X2715263Y238435D01*
X2715371Y237424D01*
X2715804Y236558D01*
X2716454Y235837D01*
X2717320Y235548D01*
X2718078Y235837D01*
X2718727Y236414D01*
G01X2724032Y239445D02*
X2727497D01*
X2727172Y240456D01*
X2726630Y241033D01*
X2725873Y241322D01*
X2725115Y241178D01*
X2724465Y240745D01*
X2724032Y239734D01*
X2723815Y238868D01*
Y238002D01*
X2724032Y237136D01*
X2724573Y236270D01*
X2725223Y235692D01*
X2725981Y235548D01*
X2726739Y235837D01*
X2727497Y236703D01*
G01X2569382Y378759D02*
X2563476D01*
G01Y370885D02*
X2569382D01*
G01Y378759D02*
Y370885D01*
G01X2563476Y378759D02*
Y370885D01*
G01X2574500Y461032D02*
X2575287D01*
G01X2571350D02*
X2572137D01*
G01X2568200D02*
X2568988D01*
G01X2565051D02*
X2565838D01*
G01X2567413D02*
X2566626D01*
G01X2564263D02*
X2563476D01*
G01X2570563D02*
X2569775D01*
G01X2573712D02*
X2572925D01*
G01X2575287Y469309D02*
Y461032D01*
G01X2574500Y469309D02*
Y461032D01*
G01X2573712Y469309D02*
Y461032D01*
G01X2572925Y469309D02*
Y461032D01*
G01X2572137Y469309D02*
Y461032D01*
G01X2571350Y469309D02*
Y461032D01*
G01X2570563Y469309D02*
Y461032D01*
G01X2569775Y469309D02*
Y461032D01*
G01X2568988Y469309D02*
Y461032D01*
G01X2568200Y469309D02*
Y461032D01*
G01X2567413Y469309D02*
Y461032D01*
G01X2566626Y469309D02*
Y461032D01*
G01X2565838Y469309D02*
Y461032D01*
G01X2565051Y469309D02*
Y461032D01*
G01X2564263Y469309D02*
Y461032D01*
G01X2563476Y469309D02*
Y461032D01*
G01X2562439Y469592D02*
Y454297D01*
G01X2563870Y465997D02*
X2603240D01*
G01X2574500Y464796D02*
X2575287D01*
G01X2571350D02*
X2572137D01*
G01X2568200D02*
X2568988D01*
G01X2565051D02*
X2565838D01*
G01X2567413D02*
X2566626D01*
G01X2564263D02*
X2563476D01*
G01X2570563D02*
X2569775D01*
G01X2573712D02*
X2572925D01*
G01X2563870Y485682D02*
Y465997D01*
G01X2577649Y461032D02*
X2578437D01*
G01X2576862D02*
X2576074D01*
G01X2578437Y469309D02*
Y461032D01*
G01X2577649Y469309D02*
Y461032D01*
G01X2576862Y469309D02*
Y461032D01*
G01X2576074Y469309D02*
Y461032D01*
G01X2577649Y464796D02*
X2578437D01*
G01X2576862D02*
X2576074D01*
G01X2572925Y469309D02*
X2573712D01*
G01X2569775D02*
X2570563D01*
G01X2566626D02*
X2567413D01*
G01X2563476D02*
X2564263D01*
G01X2565838D02*
X2565051D01*
G01X2572137D02*
X2571350D01*
G01X2568988D02*
X2568200D01*
G01X2575287D02*
X2574500D01*
G01X2572925Y468342D02*
X2573712D01*
G01X2569775D02*
X2570563D01*
G01X2566626D02*
X2567413D01*
G01X2563476D02*
X2564263D01*
G01X2565838D02*
X2565051D01*
G01X2572137D02*
X2571350D01*
G01X2568988D02*
X2568200D01*
G01X2575287D02*
X2574500D01*
G01Y467438D02*
X2575287D01*
G01X2571350D02*
X2572137D01*
G01X2568200D02*
X2568988D01*
G01X2565051D02*
X2565838D01*
G01X2567413D02*
X2566626D01*
G01X2564263D02*
X2563476D01*
G01X2570563D02*
X2569775D01*
G01X2573712D02*
X2572925D01*
G01X2565165Y482638D02*
X2565707D01*
G01Y478307D02*
X2565165D01*
G01X2566248Y478953D02*
X2565707Y478307D01*
G01Y479045D02*
X2566248Y479690D01*
G01D02*
Y478953D01*
G01X2565707Y482638D02*
Y479045D01*
G01X2565165Y478307D02*
Y482638D01*
G01X2576074Y469309D02*
X2576862D01*
G01X2578437D02*
X2577649D01*
G01X2576074Y468342D02*
X2576862D01*
G01X2578437D02*
X2577649D01*
G01Y467438D02*
X2578437D01*
G01X2576862D02*
X2576074D01*
G01X2567413Y493890D02*
X2566626D01*
G01X2564263D02*
X2563476D01*
G01X2570563D02*
X2569775D01*
G01X2573712D02*
X2572925D01*
G01X2574500Y488701D02*
X2575287D01*
G01X2568200D02*
X2568988D01*
G01X2571350D02*
X2572137D01*
G01X2565051D02*
X2565838D01*
G01X2568200Y488690D02*
X2568988D01*
G01X2571350D02*
X2572137D01*
G01X2565051D02*
X2565838D01*
G01X2574500D02*
X2575287D01*
G01X2563476Y488669D02*
X2602059D01*
G01X2565838Y488468D02*
X2565051D01*
G01X2568988D02*
X2568200D01*
G01X2572137D02*
X2571350D01*
G01X2575287D02*
X2574500D01*
G01Y488190D02*
X2575287D01*
G01X2568200D02*
X2568988D01*
G01X2571350D02*
X2572137D01*
G01X2565051D02*
X2565838D01*
G01Y488118D02*
X2565051D01*
G01X2568988D02*
X2568200D01*
G01X2572137D02*
X2571350D01*
G01X2575287D02*
X2574500D01*
G01X2565838Y487830D02*
X2565051D01*
G01X2568988D02*
X2568200D01*
G01X2572137D02*
X2571350D01*
G01X2575287D02*
X2574500D01*
G01Y487552D02*
X2575287D01*
G01X2568200D02*
X2568988D01*
G01X2571350D02*
X2572137D01*
G01X2565051D02*
X2565838D01*
G01Y487535D02*
X2565051D01*
G01X2568988D02*
X2568200D01*
G01X2572137D02*
X2571350D01*
G01X2575287D02*
X2574500D01*
G01X2565838Y486076D02*
X2565051D01*
G01X2568988D02*
X2568200D01*
G01X2572137D02*
X2571350D01*
G01X2575287D02*
X2574500D01*
G01Y485041D02*
X2575287D01*
G01X2568200D02*
X2568988D01*
G01X2571350D02*
X2572137D01*
G01X2565051D02*
X2565838D01*
G01Y484441D02*
X2565051D01*
G01X2568988D02*
X2568200D01*
G01X2572137D02*
X2571350D01*
G01X2575287D02*
X2574500D01*
G01X2575287Y488701D02*
Y484441D01*
G01X2574500Y488701D02*
Y484441D01*
G01X2573712Y498071D02*
Y493890D01*
G01X2572925Y498071D02*
Y493890D01*
G01X2572137Y488701D02*
Y484441D01*
G01X2571350Y488701D02*
Y484441D01*
G01X2570563Y498071D02*
Y493890D01*
G01X2569775Y498071D02*
Y493890D01*
G01X2568988Y488701D02*
Y484441D01*
G01X2568200Y488701D02*
Y484441D01*
G01X2567413Y498071D02*
Y493890D01*
G01X2566626Y498071D02*
Y493890D01*
G01X2565838Y488701D02*
Y484441D01*
G01X2565051Y488701D02*
Y484441D01*
G01X2564263Y498071D02*
Y493890D01*
G01X2563476Y498071D02*
Y485682D01*
G01X2567413Y498071D02*
X2566626D01*
G01X2564263D02*
X2563476D01*
G01X2570563D02*
X2569775D01*
G01X2573712D02*
X2572925D01*
G01X2567413Y497471D02*
X2566626D01*
G01X2564263D02*
X2563476D01*
G01X2570563D02*
X2569775D01*
G01X2573712D02*
X2572925D01*
G01X2567413Y496065D02*
X2566626D01*
G01X2564263D02*
X2563476D01*
G01X2570563D02*
X2569775D01*
G01X2573712D02*
X2572925D01*
G01Y495501D02*
X2573712D01*
G01X2569775D02*
X2570563D01*
G01X2566626D02*
X2567413D01*
G01X2563476D02*
X2564263D01*
G01X2572925Y494490D02*
X2573712D01*
G01X2569775D02*
X2570563D01*
G01X2566626D02*
X2567413D01*
G01X2563476D02*
X2564263D01*
G01X2576862Y493890D02*
X2576074D01*
G01X2577649Y488701D02*
X2578437D01*
G01X2577649Y488690D02*
X2578437D01*
G01Y488468D02*
X2577649D01*
G01Y488190D02*
X2578437D01*
G01Y488118D02*
X2577649D01*
G01X2588029Y488074D02*
X2577506D01*
G01X2578437Y487830D02*
X2577649D01*
G01Y487552D02*
X2578437D01*
G01Y487535D02*
X2577649D01*
G01X2588817Y487287D02*
X2576718D01*
G01X2578437Y486076D02*
X2577649D01*
G01Y485041D02*
X2578437D01*
G01Y484441D02*
X2577649D01*
G01X2575431Y488074D02*
X2576218Y487287D01*
G01X2576718D02*
X2577506Y488074D01*
G01X2578437Y488701D02*
Y484441D01*
G01X2577649Y488701D02*
Y484441D01*
G01X2577506Y491724D02*
Y488074D01*
G01X2576862Y498071D02*
Y493890D01*
G01X2576718Y487287D02*
Y491724D01*
G01X2576218D02*
Y487287D01*
G01X2576074Y498071D02*
Y493890D01*
G01X2575431Y491724D02*
Y488074D01*
G01X2576862Y498071D02*
X2576074D01*
G01X2576862Y497471D02*
X2576074D01*
G01X2576862Y496065D02*
X2576074D01*
G01Y495501D02*
X2576862D01*
G01X2576074Y494490D02*
X2576862D01*
G01X2575090Y508130D02*
X2580996D01*
G01X2565641D02*
X2571547D01*
G01X2575090Y519586D02*
Y508130D01*
G01X2571547Y519586D02*
Y508130D01*
G01X2565641Y519586D02*
Y508130D01*
G01X2571547Y511279D02*
X2575090D01*
G01X2575903Y1046782D02*
X2576107Y1045833D01*
X2576548Y1045080D01*
X2577321Y1044469D01*
X2578310Y1044234D01*
X2579255Y1044358D01*
X2580228Y1044964D01*
X2580897Y1045912D01*
X2581284Y1047021D01*
X2581174Y1047917D01*
X2580804Y1048795D01*
X2580219Y1049297D01*
X2579490Y1049549D01*
X2578358Y1049534D01*
X2580508Y1052627D01*
X2583043Y1051171D01*
G01X2584689Y1039906D02*
X2584573Y1040139D01*
X2584717Y1040389D01*
X2584976Y1040407D01*
X2585092Y1040174D01*
X2584948Y1039923D01*
X2584689Y1039906D01*
G01X2596657Y1043354D02*
X2595762Y1043535D01*
X2594839Y1043233D01*
X2594032Y1042697D01*
X2593176Y1041857D01*
X2592435Y1040785D01*
X2591882Y1039604D01*
X2591588Y1038441D01*
X2591532Y1037474D01*
X2591736Y1036525D01*
X2592343Y1035843D01*
X2593238Y1035662D01*
X2594161Y1035965D01*
X2594968Y1036500D01*
X2595825Y1037340D01*
X2596566Y1038412D01*
X2597119Y1039593D01*
X2597412Y1040756D01*
X2597468Y1041723D01*
X2597264Y1042672D01*
X2596657Y1043354D01*
G01X2604168Y1039041D02*
X2603273Y1039222D01*
X2602350Y1038920D01*
X2601543Y1038384D01*
X2600687Y1037544D01*
X2599946Y1036472D01*
X2599393Y1035291D01*
X2599099Y1034128D01*
X2599043Y1033161D01*
X2599247Y1032212D01*
X2599854Y1031530D01*
X2600749Y1031349D01*
X2601672Y1031652D01*
X2602479Y1032187D01*
X2603336Y1033027D01*
X2604077Y1034099D01*
X2604630Y1035280D01*
X2604923Y1036443D01*
X2604979Y1037410D01*
X2604775Y1038359D01*
X2604168Y1039041D01*
G01X2568684Y1049431D02*
X2572997Y1056941D01*
X2575344Y1055593D01*
X2575880Y1054786D01*
X2576062Y1054016D01*
X2575674Y1052907D01*
X2574911Y1052013D01*
X2573989Y1051711D01*
X2573116Y1051713D01*
X2570769Y1053061D01*
G01X2573116Y1051713D02*
X2572439Y1047274D01*
G01X2573210Y1438719D02*
Y1450126D01*
X2571499Y1447845D01*
G01Y1438719D02*
X2574921D01*
G01X2586329D02*
Y1450126D01*
X2581053Y1441951D01*
X2588183D01*
G01X2595767Y-994248D02*
G03X2587893Y-986374I-7874J0D01*
G01X2591240Y-955704D02*
G03I-4922J0D01*
G01X2589848Y-952275D02*
X2610734Y-931977D01*
G01X2591762Y-947504D02*
X2613270Y-915105D01*
G01X2593625Y-952770D02*
X2611238Y-945695D01*
G01X2586738Y-918324D02*
X2617357Y-892939D01*
G01X2587440Y-920271D02*
G03I-3051J0D01*
G01X2591240Y-896649D02*
G03I-4922J0D01*
G01Y-305311D02*
G03X2595177Y-301374I0J3937D01*
G01X2581586Y368130D02*
G03X2582767Y366948I1181J-1D01*
G01X2584342D02*
G03X2585523Y368130I0J1181D01*
G01Y405492D02*
Y368130D01*
G01X2581586Y405492D02*
Y368130D01*
G01X2587098Y461032D02*
X2587885D01*
G01X2590248D02*
X2591035D01*
G01X2583948D02*
X2584736D01*
G01X2580799D02*
X2581586D01*
G01X2580011D02*
X2579224D01*
G01X2583161D02*
X2582374D01*
G01X2586311D02*
X2585523D01*
G01X2589460D02*
X2588673D01*
G01X2591035Y469309D02*
Y461032D01*
G01X2590248Y469309D02*
Y461032D01*
G01X2589460Y469309D02*
Y461032D01*
G01X2588673Y469309D02*
Y461032D01*
G01X2587885Y469309D02*
Y461032D01*
G01X2587098Y469309D02*
Y461032D01*
G01X2586311Y469309D02*
Y461032D01*
G01X2585523Y469309D02*
Y461032D01*
G01X2584736Y469309D02*
Y461032D01*
G01X2583948Y469309D02*
Y461032D01*
G01X2583161Y469309D02*
Y461032D01*
G01X2582374Y469309D02*
Y461032D01*
G01X2581586Y469309D02*
Y461032D01*
G01X2580799Y469309D02*
Y461032D01*
G01X2580011Y469309D02*
Y461032D01*
G01X2579224Y469309D02*
Y461032D01*
G01X2587098Y464796D02*
X2587885D01*
G01X2590248D02*
X2591035D01*
G01X2583948D02*
X2584736D01*
G01X2580799D02*
X2581586D01*
G01X2580011D02*
X2579224D01*
G01X2583161D02*
X2582374D01*
G01X2586311D02*
X2585523D01*
G01X2589460D02*
X2588673D01*
G01X2593397Y461032D02*
X2594185D01*
G01X2592610D02*
X2591822D01*
G01X2595759D02*
X2594972D01*
G01Y469309D02*
Y461032D01*
G01X2594185Y469309D02*
Y461032D01*
G01X2593397Y469309D02*
Y461032D01*
G01X2592610Y469309D02*
Y461032D01*
G01X2591822Y469309D02*
Y461032D01*
G01X2593397Y464796D02*
X2594185D01*
G01X2592610D02*
X2591822D01*
G01X2595759D02*
X2594972D01*
G01X2588673Y469309D02*
X2589460D01*
G01X2582374D02*
X2583161D01*
G01X2585523D02*
X2586311D01*
G01X2579224D02*
X2580011D01*
G01X2581586D02*
X2580799D01*
G01X2584736D02*
X2583948D01*
G01X2587885D02*
X2587098D01*
G01X2591035D02*
X2590248D01*
G01X2588673Y468342D02*
X2589460D01*
G01X2582374D02*
X2583161D01*
G01X2585523D02*
X2586311D01*
G01X2579224D02*
X2580011D01*
G01X2581586D02*
X2580799D01*
G01X2584736D02*
X2583948D01*
G01X2587885D02*
X2587098D01*
G01X2591035D02*
X2590248D01*
G01X2587098Y467438D02*
X2587885D01*
G01X2590248D02*
X2591035D01*
G01X2583948D02*
X2584736D01*
G01X2580799D02*
X2581586D01*
G01X2580011D02*
X2579224D01*
G01X2583161D02*
X2582374D01*
G01X2586311D02*
X2585523D01*
G01X2589460D02*
X2588673D01*
G01X2591822Y469309D02*
X2592610D01*
G01X2594972D02*
X2595759D01*
G01X2594185D02*
X2593397D01*
G01X2591822Y468342D02*
X2592610D01*
G01X2594972D02*
X2595759D01*
G01X2594185D02*
X2593397D01*
G01Y467438D02*
X2594185D01*
G01X2592610D02*
X2591822D01*
G01X2595759D02*
X2594972D01*
G01X2580011Y493890D02*
X2579224D01*
G01X2586311D02*
X2585523D01*
G01X2583161D02*
X2582374D01*
G01X2589460D02*
X2588673D01*
G01X2587098Y488701D02*
X2587885D01*
G01X2590248D02*
X2591035D01*
G01X2583948D02*
X2584736D01*
G01X2580799D02*
X2581586D01*
G01X2587098Y488690D02*
X2587885D01*
G01X2590248D02*
X2591035D01*
G01X2583948D02*
X2584736D01*
G01X2580799D02*
X2581586D01*
G01Y488468D02*
X2580799D01*
G01X2584736D02*
X2583948D01*
G01X2587885D02*
X2587098D01*
G01X2591035D02*
X2590248D01*
G01X2587098Y488190D02*
X2587885D01*
G01X2590248D02*
X2591035D01*
G01X2583948D02*
X2584736D01*
G01X2580799D02*
X2581586D01*
G01Y488118D02*
X2580799D01*
G01X2584736D02*
X2583948D01*
G01X2587885D02*
X2587098D01*
G01X2591035D02*
X2590248D01*
G01X2606980Y488074D02*
X2590104D01*
G01X2581586Y487830D02*
X2580799D01*
G01X2584736D02*
X2583948D01*
G01X2587885D02*
X2587098D01*
G01X2591035D02*
X2590248D01*
G01X2587098Y487552D02*
X2587885D01*
G01X2590248D02*
X2591035D01*
G01X2583948D02*
X2584736D01*
G01X2580799D02*
X2581586D01*
G01Y487535D02*
X2580799D01*
G01X2584736D02*
X2583948D01*
G01X2587885D02*
X2587098D01*
G01X2591035D02*
X2590248D01*
G01X2606980Y487287D02*
X2589317D01*
G01X2581586Y486076D02*
X2580799D01*
G01X2584736D02*
X2583948D01*
G01X2587885D02*
X2587098D01*
G01X2591035D02*
X2590248D01*
G01X2587098Y485041D02*
X2587885D01*
G01X2590248D02*
X2591035D01*
G01X2583948D02*
X2584736D01*
G01X2580799D02*
X2581586D01*
G01Y484441D02*
X2580799D01*
G01X2584736D02*
X2583948D01*
G01X2587885D02*
X2587098D01*
G01X2591035D02*
X2590248D01*
G01X2588029Y488074D02*
X2588817Y487287D01*
G01X2590104Y488074D02*
X2589317Y487287D01*
G01X2591035Y488701D02*
Y484441D01*
G01X2590248Y488701D02*
Y484441D01*
G01X2590104Y491724D02*
Y488074D01*
G01X2589460Y498071D02*
Y493890D01*
G01X2589317Y487287D02*
Y491724D01*
G01X2588817D02*
Y487287D01*
G01X2588673Y498071D02*
Y493890D01*
G01X2588029Y491724D02*
Y488074D01*
G01X2587885Y488701D02*
Y484441D01*
G01X2587098Y488701D02*
Y484441D01*
G01X2586311Y498071D02*
Y493890D01*
G01X2585523Y498071D02*
Y493890D01*
G01X2584736Y488701D02*
Y484441D01*
G01X2583948Y488701D02*
Y484441D01*
G01X2583161Y498071D02*
Y493890D01*
G01X2582374Y498071D02*
Y493890D01*
G01X2581586Y488701D02*
Y484441D01*
G01X2580799Y488701D02*
Y484441D01*
G01X2580011Y498071D02*
Y493890D01*
G01X2579224Y498071D02*
Y493890D01*
G01X2580011Y498071D02*
X2579224D01*
G01X2586311D02*
X2585523D01*
G01X2583161D02*
X2582374D01*
G01X2589460D02*
X2588673D01*
G01X2580011Y497471D02*
X2579224D01*
G01X2586311D02*
X2585523D01*
G01X2583161D02*
X2582374D01*
G01X2589460D02*
X2588673D01*
G01X2580011Y496065D02*
X2579224D01*
G01X2586311D02*
X2585523D01*
G01X2583161D02*
X2582374D01*
G01X2589460D02*
X2588673D01*
G01Y495501D02*
X2589460D01*
G01X2585523D02*
X2586311D01*
G01X2582374D02*
X2583161D01*
G01X2579224D02*
X2580011D01*
G01X2588673Y494490D02*
X2589460D01*
G01X2585523D02*
X2586311D01*
G01X2582374D02*
X2583161D01*
G01X2579224D02*
X2580011D01*
G01X2595759Y493890D02*
X2594972D01*
G01X2592610D02*
X2591822D01*
G01X2593397Y488701D02*
X2594185D01*
G01X2593397Y488690D02*
X2594185D01*
G01Y488468D02*
X2593397D01*
G01Y488190D02*
X2594185D01*
G01Y488118D02*
X2593397D01*
G01X2594185Y487830D02*
X2593397D01*
G01Y487552D02*
X2594185D01*
G01Y487535D02*
X2593397D01*
G01X2594185Y486076D02*
X2593397D01*
G01Y485041D02*
X2594185D01*
G01Y484441D02*
X2593397D01*
G01X2594972Y498071D02*
Y493890D01*
G01X2594185Y488701D02*
Y484441D01*
G01X2593397Y488701D02*
Y484441D01*
G01X2592610Y498071D02*
Y493890D01*
G01X2591822Y498071D02*
Y493890D01*
G01X2595759Y498071D02*
X2594972D01*
G01X2592610D02*
X2591822D01*
G01X2595759Y497471D02*
X2594972D01*
G01X2592610D02*
X2591822D01*
G01X2595759Y496065D02*
X2594972D01*
G01X2592610D02*
X2591822D01*
G01X2594972Y495501D02*
X2595759D01*
G01X2591822D02*
X2592610D01*
G01X2594972Y494490D02*
X2595759D01*
G01X2591822D02*
X2592610D01*
G01X2584539Y508130D02*
X2590445D01*
G01Y519586D02*
Y508130D01*
G01X2584539Y519586D02*
Y508130D01*
G01X2580996Y519586D02*
Y508130D01*
G01X2590445Y511279D02*
X2593988D01*
G01X2580996D02*
X2584539D01*
G01X2593988Y508130D02*
X2599893D01*
G01X2593988Y519586D02*
Y508130D01*
G01X2595767Y-1057240D02*
G03X2603641Y-1065114I7874J0D01*
G01D02*
X2727460D01*
G01X2595767Y-994248D02*
Y-1057240D01*
G01X2611238Y-945695D02*
X2614387D01*
G01X2610734Y-931977D02*
X2613883D01*
G01X2595177Y-275389D02*
Y-301374D01*
G01X2600295Y-291925D02*
X2603051D01*
G01X2596358D02*
X2599114D01*
G01X2603051D02*
Y-275389D01*
G01X2600295D02*
Y-291925D01*
G01X2599114D02*
Y-275389D01*
G01X2596358D02*
Y-291925D01*
G01X2604232D02*
X2606988D01*
G01X2608169D02*
X2610925D01*
G01D02*
Y-275389D01*
G01X2608169D02*
Y-291925D01*
G01X2606988D02*
Y-275389D01*
G01X2604232D02*
Y-291925D01*
G01X2599114Y-275389D02*
X2596358D01*
G01X2623523D02*
X2595177D01*
G01X2603051D02*
X2600295D01*
G01X2595177Y-271846D02*
Y-275389D01*
G01X2606988D02*
X2604232D01*
G01X2610925D02*
X2608169D01*
G01X2621555Y-269878D02*
X2597145D01*
G01D02*
X2595177Y-271846D01*
G01X2603633Y378759D02*
X2597728D01*
G01Y370885D02*
X2603633D01*
G01Y378759D02*
Y370885D01*
G01X2597728Y378759D02*
Y370885D01*
G01X2602846Y461032D02*
X2603633D01*
G01X2596547D02*
X2597334D01*
G01X2599696D02*
X2600484D01*
G01X2598909D02*
X2598122D01*
G01X2602059D02*
X2601271D01*
G01X2604671Y459455D02*
X2609933D01*
G01X2608387Y459077D02*
X2605336D01*
G01X2608387Y458585D02*
X2604450D01*
G01X2608781Y458191D02*
X2604056D01*
G01X2609933Y458077D02*
X2604671D01*
G01X2608387Y460258D02*
X2605336Y459077D01*
G01X2607600Y460504D02*
X2604450Y459274D01*
G01Y461734D02*
X2607600Y460504D01*
G01X2605336Y461931D02*
X2608387Y460750D01*
G01X2606783Y457797D02*
X2609383Y454297D01*
G01X2606783Y478419D02*
Y457797D01*
G01X2604671Y469592D02*
Y454297D01*
G01X2604450Y459274D02*
Y458585D01*
G01X2604056Y470150D02*
Y458191D01*
G01X2603633Y469309D02*
Y461032D01*
G01X2602846Y469309D02*
Y461032D01*
G01X2602059Y469309D02*
Y461032D01*
G01X2601271Y469309D02*
Y461032D01*
G01X2600484Y469309D02*
Y461032D01*
G01X2599696Y469309D02*
Y461032D01*
G01X2598909Y469309D02*
Y461032D01*
G01X2598122Y469309D02*
Y461032D01*
G01X2597334Y469309D02*
Y461032D01*
G01X2596547Y469309D02*
Y461032D01*
G01X2595759Y469309D02*
Y461032D01*
G01X2605315Y464623D02*
G03Y466833I1862J1105D01*
G01X2609826Y466486D02*
G03X2605315Y467759I-2649J-758D01*
G01Y463696D02*
G03X2609826Y464970I1862J2032D01*
G01X2602846Y464796D02*
X2603633D01*
G01X2596547D02*
X2597334D01*
G01X2599696D02*
X2600484D01*
G01X2598909D02*
X2598122D01*
G01X2602059D02*
X2601271D01*
G01X2608387Y462423D02*
X2604450D01*
G01X2608387Y461931D02*
X2605336D01*
G01X2605926Y464884D02*
X2604450Y463900D01*
G01X2608387Y465917D02*
X2606861Y464884D01*
G01X2608387Y466557D02*
X2606369Y465179D01*
G01Y464589D02*
X2604450Y463260D01*
G01Y466508D02*
X2606369Y465179D01*
G01Y464589D02*
X2608387Y463211D01*
G01X2606861Y464884D02*
X2608387Y463850D01*
G01X2604450Y465868D02*
X2605926Y464884D01*
G01X2605315Y463696D02*
Y467759D01*
G01X2604450Y463900D02*
Y463260D01*
G01Y466508D02*
Y465868D01*
G01Y462423D02*
Y461734D01*
G01X2603240Y485682D02*
Y465997D01*
G01X2609933Y499591D02*
Y454297D01*
G01X2608781Y470150D02*
Y458191D01*
G01X2608387Y459077D02*
Y458585D01*
G01Y460750D02*
Y460258D01*
G01X2609826Y466486D02*
Y464970D01*
G01X2608387Y463850D02*
Y463211D01*
G01Y466557D02*
Y465917D01*
G01Y462423D02*
Y461931D01*
G01X2608781Y470150D02*
X2604056D01*
G01X2608387Y469756D02*
X2604450D01*
G01X2609933Y469592D02*
X2604671D01*
G01X2609933Y469413D02*
X2604671D01*
G01X2601271Y469309D02*
X2602059D01*
G01X2598122D02*
X2598909D01*
G01X2597334D02*
X2596547D01*
G01X2600484D02*
X2599696D01*
G01X2603633D02*
X2602846D01*
G01X2608387Y469264D02*
X2605533D01*
G01X2601271Y468342D02*
X2602059D01*
G01X2598122D02*
X2598909D01*
G01X2597334D02*
X2596547D01*
G01X2600484D02*
X2599696D01*
G01X2603633D02*
X2602846D01*
G01X2605533Y468329D02*
X2605139D01*
G01X2602846Y467438D02*
X2603633D01*
G01X2596547D02*
X2597334D01*
G01X2599696D02*
X2600484D01*
G01X2598909D02*
X2598122D01*
G01X2602059D02*
X2601271D01*
G01X2604450Y469362D02*
X2604598Y469313D01*
G01D02*
X2604795Y469165D01*
G01D02*
X2604942Y469018D01*
G01X2605041Y468821D02*
X2605090Y468673D01*
G01X2604942Y469018D02*
X2605041Y468821D01*
G01X2605090Y468673D02*
X2605139Y468427D01*
G01X2605533Y469264D02*
Y468329D01*
G01X2605139Y468427D02*
Y468329D01*
G01X2604450Y469756D02*
Y469362D01*
G01X2608387Y469756D02*
Y469264D01*
G01X2598909Y493890D02*
X2598122D01*
G01X2602059D02*
X2601271D01*
G01X2606980Y493299D02*
X2609933D01*
G01Y492906D02*
X2606980D01*
G01Y492512D02*
X2609933D01*
G01X2601409Y491122D02*
X2599933D01*
G01X2602846Y488701D02*
X2603633D01*
G01X2596547D02*
X2597334D01*
G01X2599696D02*
X2600484D01*
G01X2602846Y488690D02*
X2603633D01*
G01X2596547D02*
X2597334D01*
G01X2599696D02*
X2600484D01*
G01X2597334Y488468D02*
X2596547D01*
G01X2600484D02*
X2599696D01*
G01X2603633D02*
X2602846D01*
G01Y488190D02*
X2603633D01*
G01X2596547D02*
X2597334D01*
G01X2599696D02*
X2600484D01*
G01X2597334Y488118D02*
X2596547D01*
G01X2600484D02*
X2599696D01*
G01X2603633D02*
X2602846D01*
G01X2597334Y487830D02*
X2596547D01*
G01X2600484D02*
X2599696D01*
G01X2603633D02*
X2602846D01*
G01Y487552D02*
X2603633D01*
G01X2596547D02*
X2597334D01*
G01X2599696D02*
X2600484D01*
G01X2597334Y487535D02*
X2596547D01*
G01X2600484D02*
X2599696D01*
G01X2603633D02*
X2602846D01*
G01X2597334Y486076D02*
X2596547D01*
G01X2600484D02*
X2599696D01*
G01X2603633D02*
X2602846D01*
G01Y485041D02*
X2603633D01*
G01X2596547D02*
X2597334D01*
G01X2599696D02*
X2600484D01*
G01X2597334Y484441D02*
X2596547D01*
G01X2600484D02*
X2599696D01*
G01X2603633D02*
X2602846D01*
G01X2606980Y499591D02*
Y486500D01*
G01X2603633Y488701D02*
Y484441D01*
G01X2602846Y488701D02*
Y484441D01*
G01X2602059Y498071D02*
Y485682D01*
G01X2601409Y496650D02*
Y491122D01*
G01X2601271Y498071D02*
Y493890D01*
G01X2600484Y488701D02*
Y484441D01*
G01X2599933Y491122D02*
Y502933D01*
G01X2599696Y488701D02*
Y484441D01*
G01X2598909Y498071D02*
Y493890D01*
G01X2598122Y498071D02*
Y493890D01*
G01X2597334Y488701D02*
Y484441D01*
G01X2596547Y488701D02*
Y484441D01*
G01X2595759Y498071D02*
Y493890D01*
G01X2606980Y499591D02*
X2609933D01*
G01X2601409Y498158D02*
X2608299D01*
G01X2598909Y498071D02*
X2598122D01*
G01X2602059D02*
X2601271D01*
G01X2598909Y497471D02*
X2598122D01*
G01X2602059D02*
X2601271D01*
G01X2608299Y496650D02*
X2601409D01*
G01X2598909Y496065D02*
X2598122D01*
G01X2602059D02*
X2601271D01*
G01Y495501D02*
X2602059D01*
G01X2598122D02*
X2598909D01*
G01X2601271Y494490D02*
X2602059D01*
G01X2598122D02*
X2598909D01*
G01X2601409Y502933D02*
Y498158D01*
G01X2609775Y491122D02*
X2608299D01*
G01X2609775Y502933D02*
Y491122D01*
G01X2608299D02*
Y496650D01*
G01Y498158D02*
Y502933D01*
G01X2599933D02*
X2601409D01*
G01X2599893Y519586D02*
Y508130D01*
G01Y511279D02*
X2618476D01*
G01X2608299Y502933D02*
X2609775D01*
G01X2627596Y-943530D02*
Y-934869D01*
X2623590Y-941076D01*
X2629004D01*
G01X2633551Y-940643D02*
X2636365D01*
G01X2614387Y-945695D02*
X2729007D01*
G01X2627092Y-929812D02*
Y-921151D01*
X2623086Y-927358D01*
X2628500D01*
G01X2633047Y-926925D02*
X2635861D01*
G01X2613883Y-931977D02*
X2728503D01*
G01X2629628Y-912940D02*
Y-904279D01*
X2625622Y-910486D01*
X2631036D01*
G01X2635583Y-910053D02*
X2638397D01*
G01X2616420Y-915105D02*
X2746629D01*
G01X2613270D02*
X2616420D01*
G01X2617357Y-892939D02*
X2620507D01*
G01D02*
X2742922D01*
G01X2619980Y-291925D02*
X2622736D01*
G01X2616043D02*
X2618799D01*
G01X2612106D02*
X2614862D01*
G01X2619980Y-275389D02*
Y-291925D01*
G01X2618799D02*
Y-275389D01*
G01X2616043D02*
Y-291925D01*
G01X2614862D02*
Y-275389D01*
G01X2612106D02*
Y-291925D01*
G01X2623523Y-299208D02*
G03X2631003I3740J0D01*
G01X2623523D02*
Y-271846D01*
G01X2622736Y-291925D02*
Y-275389D01*
G01X2614862D02*
X2612106D01*
G01X2618799D02*
X2616043D01*
G01X2622736D02*
X2619980D01*
G01X2623523Y-271846D02*
X2621555Y-269878D01*
G01X2621429Y368130D02*
X2620248Y366948D01*
G01X2621429Y394507D02*
Y368130D01*
G01X2618476Y405492D02*
Y366948D01*
G01X2616507Y405492D02*
Y366948D01*
G01X2615326Y372460D02*
G03X2616901Y370885I1575J0D01*
G01X2618476Y372460D02*
X2615326D01*
G01X2618476Y370885D02*
X2616901D01*
G01X2615326Y405492D02*
Y372460D01*
G01X2620346Y398444D02*
Y394507D01*
G01X2628732Y398444D02*
X2620563D01*
G01D02*
X2620346D01*
G01X2624362Y422421D02*
Y398444D01*
G01X2624303Y519586D02*
Y398444D01*
G01X2623122D02*
Y519586D01*
G01X2622334D02*
Y398444D01*
G01X2620838D02*
Y519586D01*
G01X2620563Y401555D02*
Y398444D01*
G01X2632767Y391752D02*
G03X2624893Y399626I-7874J0D01*
G01X2625189Y394507D02*
Y398444D01*
G01X2625504Y401555D02*
X2620563D01*
G01X2624519Y515649D02*
Y401555D01*
G01X2623496Y515649D02*
Y401555D01*
G01X2621527Y515649D02*
Y401555D01*
G01X2618476Y511279D02*
Y416122D01*
G01X2625504Y515649D02*
Y401555D01*
G01X2627256Y430295D02*
G03I-3937J0D01*
G01X2628240D02*
G03I-4921J0D01*
G01X2631193D02*
G03I-7874J0D01*
G01X2628732Y422421D02*
X2624362D01*
G01X2628732Y438169D02*
X2624362D01*
G01Y481476D02*
Y438169D01*
G01X2623279Y465728D02*
G03I-1890J0D01*
G01X2624263D02*
G03I-2874J0D01*
G01X2624441D02*
G03I-3052J0D01*
G01X2631193Y489350D02*
G03I-7874J0D01*
G01X2628732Y481476D02*
X2624362D01*
G01X2627256Y489350D02*
G03I-3937J0D01*
G01X2628240D02*
G03I-4921J0D01*
G01X2624539Y492378D02*
X2631429D01*
G01Y491122D02*
X2622570D01*
G01X2620602D02*
X2619126D01*
G01X2630691Y497907D02*
X2624539Y492378D01*
G01X2622570D02*
X2629460Y498661D01*
G01X2622570Y491122D02*
Y492378D01*
G01X2620602Y502933D02*
Y491122D01*
G01X2619126D02*
Y500922D01*
G01X2611744Y499163D02*
X2615681D01*
G01Y498158D02*
X2611744D01*
G01X2628732Y497224D02*
X2624362D01*
G01X2611744Y496148D02*
X2615681D01*
G01Y495143D02*
X2611744D01*
G01X2619126Y500922D02*
X2617649Y499163D01*
G01X2624362Y497224D02*
Y519586D01*
G01X2617649Y499163D02*
Y501174D01*
G01X2615681Y496148D02*
Y495143D01*
G01Y499163D02*
Y498158D01*
G01X2611744Y495143D02*
Y496148D01*
G01Y498158D02*
Y499163D01*
G01X2627687Y495902D02*
X2641738Y516978D01*
G01X2619126Y502933D02*
X2620602D01*
G01X2624047Y500168D02*
X2622817D01*
G01X2624047Y502179D02*
X2625031Y502681D01*
G01X2625277Y501425D02*
X2624539Y500922D01*
G01X2623063Y501174D02*
X2624047Y502179D01*
G01X2617649Y501174D02*
X2619126Y502933D01*
G01X2624539Y500922D02*
X2624047Y500168D01*
G01X2622817D02*
X2623063Y501174D01*
G01X2625504Y515649D02*
X2617433D01*
G01D02*
Y524941D01*
G01X2625031Y502681D02*
X2626754Y502933D01*
G01X2626507Y501676D02*
X2625277Y501425D01*
G01X2626754Y502933D02*
X2627738D01*
G01X2627492Y501676D02*
X2626507D01*
G01X2627738Y502933D02*
X2629214Y502681D01*
G01X2628722Y501425D02*
X2627492Y501676D01*
G01X2640046Y-943530D02*
Y-937756D01*
G01Y-939200D02*
X2640480Y-938478D01*
X2641129Y-937900D01*
X2641995Y-937756D01*
X2642753Y-937900D01*
X2643403Y-938478D01*
X2643728Y-939488D01*
Y-943530D01*
G01X2639542Y-929812D02*
Y-924038D01*
G01Y-925482D02*
X2639976Y-924760D01*
X2640625Y-924182D01*
X2641491Y-924038D01*
X2642249Y-924182D01*
X2642899Y-924760D01*
X2643224Y-925770D01*
Y-929812D01*
G01X2642079Y-912940D02*
Y-907166D01*
G01Y-908610D02*
X2642513Y-907888D01*
X2643162Y-907310D01*
X2644028Y-907166D01*
X2644786Y-907310D01*
X2645436Y-907888D01*
X2645761Y-908898D01*
Y-912940D01*
G01X2630359Y-883556D02*
X2631009Y-882691D01*
X2631766Y-882257D01*
X2632633Y-882113D01*
X2633715Y-882402D01*
X2634473Y-883123D01*
X2634690Y-883989D01*
X2634581Y-884856D01*
X2634148Y-885577D01*
X2631983Y-887021D01*
X2631009Y-888031D01*
X2630359Y-889475D01*
X2630142Y-890774D01*
X2634690D01*
G01X2639670Y-887887D02*
X2642484D01*
G01X2631702Y-883228D02*
X2632352Y-882363D01*
X2633109Y-881929D01*
X2633976Y-881785D01*
X2635058Y-882074D01*
X2635816Y-882795D01*
X2636033Y-883661D01*
X2635924Y-884528D01*
X2635491Y-885249D01*
X2633326Y-886693D01*
X2632352Y-887703D01*
X2631702Y-889147D01*
X2631485Y-890446D01*
X2636033D01*
G01X2641013Y-887559D02*
X2643827D01*
G01X2648807Y-890446D02*
Y-881785D01*
G01X2653355D02*
Y-890446D01*
G01Y-886116D02*
X2648807D01*
G01X2658335Y-888858D02*
X2661149D01*
G01Y-886260D02*
X2658335D01*
G01X2668403Y-881785D02*
X2667537Y-882074D01*
X2666887Y-882795D01*
X2666454Y-883661D01*
X2666129Y-884816D01*
X2666021Y-886116D01*
X2666129Y-887415D01*
X2666454Y-888570D01*
X2666887Y-889436D01*
X2667537Y-890157D01*
X2668403Y-890446D01*
X2669269Y-890157D01*
X2669919Y-889436D01*
X2670352Y-888570D01*
X2670677Y-887415D01*
X2670785Y-886116D01*
X2670677Y-884816D01*
X2670352Y-883661D01*
X2669919Y-882795D01*
X2669269Y-882074D01*
X2668403Y-881785D01*
G01X2673816Y-890446D02*
Y-884672D01*
G01Y-886260D02*
X2674141Y-885538D01*
X2674682Y-884961D01*
X2675440Y-884672D01*
X2676198Y-884961D01*
X2676739Y-885538D01*
X2677064Y-886260D01*
Y-890446D01*
G01Y-886260D02*
X2677389Y-885538D01*
X2677930Y-884961D01*
X2678688Y-884672D01*
X2679446Y-884961D01*
X2679987Y-885538D01*
X2680312Y-886404D01*
Y-890446D01*
G01X2682477D02*
Y-884672D01*
G01Y-886260D02*
X2682802Y-885538D01*
X2683343Y-884961D01*
X2684101Y-884672D01*
X2684859Y-884961D01*
X2685400Y-885538D01*
X2685725Y-886260D01*
Y-890446D01*
G01Y-886260D02*
X2686050Y-885538D01*
X2686591Y-884961D01*
X2687349Y-884672D01*
X2688107Y-884961D01*
X2688648Y-885538D01*
X2688973Y-886404D01*
Y-890446D01*
G01X2634547Y-291925D02*
X2631791D01*
G01X2638484D02*
X2635728D01*
G01D02*
Y-275389D01*
G01X2634547D02*
Y-291925D01*
G01X2631791D02*
Y-275389D01*
G01X2631003Y-271846D02*
Y-299208D01*
G01X2642421Y-291925D02*
X2639665D01*
G01X2646358D02*
X2643602D01*
G01D02*
Y-275389D01*
G01X2642421D02*
Y-291925D01*
G01X2639665D02*
Y-275389D01*
G01X2638484D02*
Y-291925D01*
G01X2631791Y-275389D02*
X2634547D01*
G01X2635728D02*
X2638484D01*
G01X2675098D02*
X2631003D01*
G01X2643602D02*
X2646358D01*
G01X2639665D02*
X2642421D01*
G01X2673129Y-269878D02*
X2632972D01*
G01D02*
X2631003Y-271846D01*
G01X2632767Y328759D02*
G03X2640641Y320885I7874J0D01*
G01D02*
X2764460D01*
G01X2632767Y391752D02*
Y328759D01*
G01X2643200Y336633D02*
X2669578D01*
G01X2643200Y363405D02*
Y336633D01*
G01Y363405D02*
X2645405D01*
G01X2628732Y394507D02*
Y519586D01*
G01X2634628Y491122D02*
X2633397D01*
G01X2638565D02*
X2637334D01*
G01X2638565Y497153D02*
Y491122D01*
G01X2637334D02*
Y497153D01*
G01X2634628Y497404D02*
Y491122D01*
G01X2633397D02*
Y499163D01*
G01X2631429Y492378D02*
Y491122D01*
G01X2639795Y499163D02*
X2640779D01*
G01X2633397D02*
X2634628D01*
G01X2635858D02*
X2636842D01*
G01X2636350Y498158D02*
X2635858D01*
G01X2640287D02*
X2639549D01*
G01X2639057Y498912D02*
X2639795Y499163D01*
G01X2635858Y498158D02*
X2635120Y497907D01*
G01Y498912D02*
X2635858Y499163D01*
G01X2640779D02*
X2641517Y498912D01*
G01X2636842Y499163D02*
X2637580Y498912D01*
G01X2640779Y497907D02*
X2640287Y498158D01*
G01X2636842Y497907D02*
X2636350Y498158D01*
G01X2639549D02*
X2639057Y497907D01*
G01D02*
X2638811Y497656D01*
G01X2638319Y498158D02*
X2639057Y498912D01*
G01X2635120Y497907D02*
X2634628Y497404D01*
G01Y498409D02*
X2635120Y498912D01*
G01X2641025Y497656D02*
X2640779Y497907D01*
G01X2637580Y498912D02*
X2638319Y498158D01*
G01X2637088Y497656D02*
X2636842Y497907D01*
G01X2641271Y497153D02*
X2641025Y497656D01*
G01X2637334Y497153D02*
X2637088Y497656D01*
G01X2631183Y498661D02*
X2630691Y497907D01*
G01X2638811Y497656D02*
X2638565Y497153D01*
G01X2629460Y498661D02*
X2629952Y499666D01*
G01X2631429D02*
X2631183Y498661D01*
G01X2634628Y499163D02*
Y498409D01*
G01X2631429Y500168D02*
Y499666D01*
G01X2629952D02*
Y500168D01*
G01X2642502Y491122D02*
X2641271D01*
G01X2642502Y497153D02*
Y491122D01*
G01X2641271D02*
Y497153D01*
G01X2641517Y498912D02*
X2642009Y498409D01*
G01D02*
X2642502Y497153D01*
G01X2629214Y502681D02*
X2630198Y502179D01*
G01X2629460Y500922D02*
X2628722Y501425D01*
G01X2630198Y502179D02*
X2631183Y501174D01*
G01X2629952Y500168D02*
X2629460Y500922D01*
G01X2631183Y501174D02*
X2631429Y500168D01*
G01X2641738Y516978D02*
X2644888D01*
G01X2628240Y1080689D02*
G03X2632177Y1084626I0J3937D01*
G01Y1110610D02*
Y1084626D01*
G01X2640051Y1094074D02*
X2637295D01*
G01X2636114D02*
X2633358D01*
G01X2640051Y1106673D02*
Y1094074D01*
G01X2637295D02*
Y1106673D01*
G01X2636114Y1110610D02*
Y1094074D01*
G01X2633358D02*
Y1110610D01*
G01X2637295Y1106673D02*
X2640051D01*
G01X2643988Y1094074D02*
X2641232D01*
G01X2643988Y1110610D02*
Y1094074D01*
G01X2641232D02*
Y1110610D01*
G01X2658555Y1116122D02*
X2634145D01*
G01X2633358Y1110610D02*
X2636114D01*
G01X2660523D02*
X2632177D01*
G01Y1114153D02*
Y1110610D01*
G01X2634145Y1116122D02*
X2632177Y1114153D01*
G01X2641232Y1110610D02*
X2643988D01*
G01X2654735Y-943530D02*
Y-934869D01*
X2650729Y-941076D01*
X2656143D01*
G01X2662097Y-943819D02*
X2661880Y-943674D01*
Y-943386D01*
X2662097Y-943241D01*
X2662314Y-943386D01*
Y-943674D01*
X2662097Y-943819D01*
G01X2670758Y-934869D02*
X2669892Y-935158D01*
X2669242Y-935879D01*
X2668809Y-936745D01*
X2668484Y-937900D01*
X2668376Y-939200D01*
X2668484Y-940499D01*
X2668809Y-941654D01*
X2669242Y-942520D01*
X2669892Y-943241D01*
X2670758Y-943530D01*
X2671624Y-943241D01*
X2672274Y-942520D01*
X2672707Y-941654D01*
X2673032Y-940499D01*
X2673140Y-939200D01*
X2673032Y-937900D01*
X2672707Y-936745D01*
X2672274Y-935879D01*
X2671624Y-935158D01*
X2670758Y-934869D01*
G01X2679419D02*
X2678553Y-935158D01*
X2677903Y-935879D01*
X2677470Y-936745D01*
X2677145Y-937900D01*
X2677037Y-939200D01*
X2677145Y-940499D01*
X2677470Y-941654D01*
X2677903Y-942520D01*
X2678553Y-943241D01*
X2679419Y-943530D01*
X2680285Y-943241D01*
X2680935Y-942520D01*
X2681368Y-941654D01*
X2681693Y-940499D01*
X2681801Y-939200D01*
X2681693Y-937900D01*
X2681368Y-936745D01*
X2680935Y-935879D01*
X2680285Y-935158D01*
X2679419Y-934869D01*
G01X2650875Y-922594D02*
X2651525Y-921729D01*
X2652282Y-921295D01*
X2653149Y-921151D01*
X2654231Y-921440D01*
X2654989Y-922161D01*
X2655206Y-923027D01*
X2655097Y-923894D01*
X2654664Y-924615D01*
X2652499Y-926059D01*
X2651525Y-927069D01*
X2650875Y-928513D01*
X2650658Y-929812D01*
X2655206D01*
G01X2661593Y-930101D02*
X2661376Y-929956D01*
Y-929668D01*
X2661593Y-929523D01*
X2661810Y-929668D01*
Y-929956D01*
X2661593Y-930101D01*
G01X2667872Y-928513D02*
X2668522Y-929235D01*
X2669280Y-929668D01*
X2670254Y-929812D01*
X2671228Y-929523D01*
X2671986Y-928946D01*
X2672528Y-927936D01*
X2672636Y-926781D01*
X2672419Y-925626D01*
X2671878Y-924904D01*
X2671120Y-924327D01*
X2670362Y-924182D01*
X2669604Y-924327D01*
X2668630Y-924904D01*
X2668955Y-921151D01*
X2671878D01*
G01X2678915D02*
X2678049Y-921440D01*
X2677399Y-922161D01*
X2676966Y-923027D01*
X2676641Y-924182D01*
X2676533Y-925482D01*
X2676641Y-926781D01*
X2676966Y-927936D01*
X2677399Y-928802D01*
X2678049Y-929523D01*
X2678915Y-929812D01*
X2679781Y-929523D01*
X2680431Y-928802D01*
X2680864Y-927936D01*
X2681189Y-926781D01*
X2681297Y-925482D01*
X2681189Y-924182D01*
X2680864Y-923027D01*
X2680431Y-922161D01*
X2679781Y-921440D01*
X2678915Y-921151D01*
G01X2653086Y-911641D02*
X2653736Y-912363D01*
X2654494Y-912796D01*
X2655468Y-912940D01*
X2656442Y-912651D01*
X2657200Y-912074D01*
X2657742Y-911064D01*
X2657850Y-909909D01*
X2657633Y-908754D01*
X2657092Y-908032D01*
X2656334Y-907455D01*
X2655576Y-907310D01*
X2654818Y-907455D01*
X2653844Y-908032D01*
X2654169Y-904279D01*
X2657092D01*
G01X2664129Y-913229D02*
X2663912Y-913084D01*
Y-912796D01*
X2664129Y-912651D01*
X2664346Y-912796D01*
Y-913084D01*
X2664129Y-913229D01*
G01X2672790Y-904279D02*
X2671924Y-904568D01*
X2671274Y-905289D01*
X2670841Y-906155D01*
X2670516Y-907310D01*
X2670408Y-908610D01*
X2670516Y-909909D01*
X2670841Y-911064D01*
X2671274Y-911930D01*
X2671924Y-912651D01*
X2672790Y-912940D01*
X2673656Y-912651D01*
X2674306Y-911930D01*
X2674739Y-911064D01*
X2675064Y-909909D01*
X2675172Y-908610D01*
X2675064Y-907310D01*
X2674739Y-906155D01*
X2674306Y-905289D01*
X2673656Y-904568D01*
X2672790Y-904279D01*
G01X2681451D02*
X2680585Y-904568D01*
X2679935Y-905289D01*
X2679502Y-906155D01*
X2679177Y-907310D01*
X2679069Y-908610D01*
X2679177Y-909909D01*
X2679502Y-911064D01*
X2679935Y-911930D01*
X2680585Y-912651D01*
X2681451Y-912940D01*
X2682317Y-912651D01*
X2682967Y-911930D01*
X2683400Y-911064D01*
X2683725Y-909909D01*
X2683833Y-908610D01*
X2683725Y-907310D01*
X2683400Y-906155D01*
X2682967Y-905289D01*
X2682317Y-904568D01*
X2681451Y-904279D01*
G01X2646166Y-890774D02*
Y-885000D01*
G01Y-886444D02*
X2646600Y-885722D01*
X2647249Y-885144D01*
X2648115Y-885000D01*
X2648873Y-885144D01*
X2649523Y-885722D01*
X2649848Y-886732D01*
Y-890774D01*
G01X2659556D02*
Y-882113D01*
X2658257Y-883845D01*
G01Y-890774D02*
X2660855D01*
G01X2668217Y-891063D02*
X2668000Y-890918D01*
Y-890630D01*
X2668217Y-890485D01*
X2668434Y-890630D01*
Y-890918D01*
X2668217Y-891063D01*
G01X2674496Y-889475D02*
X2675146Y-890197D01*
X2675904Y-890630D01*
X2676878Y-890774D01*
X2677852Y-890485D01*
X2678610Y-889908D01*
X2679152Y-888898D01*
X2679260Y-887743D01*
X2679043Y-886588D01*
X2678502Y-885866D01*
X2677744Y-885289D01*
X2676986Y-885144D01*
X2676228Y-885289D01*
X2675254Y-885866D01*
X2675579Y-882113D01*
X2678502D01*
G01X2683157Y-889475D02*
X2683807Y-890197D01*
X2684565Y-890630D01*
X2685539Y-890774D01*
X2686513Y-890485D01*
X2687271Y-889908D01*
X2687813Y-888898D01*
X2687921Y-887743D01*
X2687704Y-886588D01*
X2687163Y-885866D01*
X2686405Y-885289D01*
X2685647Y-885144D01*
X2684889Y-885289D01*
X2683915Y-885866D01*
X2684240Y-882113D01*
X2687163D01*
G01X2650295Y-291925D02*
X2647539D01*
G01X2654232D02*
X2651476D01*
G01D02*
Y-275389D01*
G01X2650295D02*
Y-291925D01*
G01X2647539D02*
Y-275389D01*
G01X2646358D02*
Y-291925D01*
G01X2658169D02*
X2655413D01*
G01X2662106D02*
X2659350D01*
G01D02*
Y-275389D01*
G01X2658169D02*
Y-291925D01*
G01X2655413D02*
Y-275389D01*
G01X2654232D02*
Y-291925D01*
G01X2651476Y-275389D02*
X2654232D01*
G01X2647539D02*
X2650295D01*
G01X2655413D02*
X2658169D01*
G01X2659350D02*
X2662106D01*
G01X2660925Y-267830D02*
X2659940D01*
G01D02*
X2662565Y-259956D01*
G01X2650287Y327775D02*
G03X2662492I6103J0D01*
G01X2650287D02*
X2662492D01*
G01X2656389Y358287D02*
Y327775D01*
G01X2650287Y337224D02*
Y327775D01*
G01X2653673Y342145D02*
G03X2653870Y341948I197J0D01*
G01X2655208D02*
G03X2655405Y342145I0J197D01*
G01X2657374D02*
G03X2657570Y341948I197J0D01*
G01X2655405Y342145D02*
X2657374D01*
G01X2662558Y341948D02*
X2648359D01*
G01X2666822Y340570D02*
X2645956D01*
G01X2648909Y338011D02*
X2662492D01*
G01X2649500Y337224D02*
X2662492D01*
G01X2645405Y344862D02*
X2652098Y341948D01*
G01X2651311Y347229D02*
X2653673Y343917D01*
G01X2657374Y342145D02*
Y363405D01*
G01X2655405Y342145D02*
Y363405D01*
G01X2653673Y343917D02*
Y342145D01*
G01X2649500Y337224D02*
Y338011D01*
G01X2649377Y358287D02*
Y341948D01*
G01X2648909Y338011D02*
Y341948D01*
G01X2648359D02*
Y336633D01*
G01X2645956Y361043D02*
Y340570D01*
G01X2645405Y363405D02*
Y344862D01*
G01X2645208Y361043D02*
Y336633D01*
G01X2647374Y348607D02*
G03X2647964Y348017I590J0D01*
G01X2651311D02*
X2647964D01*
G01X2651311D02*
Y347229D01*
G01X2647374Y348607D02*
Y363405D01*
G01X2658909Y341948D02*
G03X2659106Y342145I0J197D01*
G01X2661312D02*
X2659106D01*
G01Y347657D02*
Y342145D01*
G01X2659696Y348248D02*
G03X2659106Y347657I1J-591D01*
G01X2664815Y348248D02*
X2659696D01*
G01X2647374Y362263D02*
X2645405D01*
G01X2657374D02*
X2655405D01*
G01X2648358Y361043D02*
X2644815D01*
G01X2658673D02*
X2654106D01*
G01X2644815Y359468D02*
X2667964D01*
G01X2662558Y358287D02*
X2649377D01*
G01X2654815Y361437D02*
X2651271Y359468D01*
G01X2647964Y361437D02*
X2649933Y359468D01*
G01X2654815Y363405D02*
Y361437D01*
G01X2647964Y363405D02*
Y361437D01*
G01X2644815Y359468D02*
Y363405D01*
G01X2655405D02*
X2647374D01*
G01X2665405D02*
X2657374D01*
G01X2647374Y363011D02*
X2645405D01*
G01X2657374D02*
X2655405D01*
G01X2661507Y359468D02*
X2657964Y361437D01*
G01Y363405D02*
Y361437D01*
G01X2645700Y491122D02*
X2644470D01*
G01X2649637D02*
X2648407D01*
G01X2653574D02*
X2652344D01*
G01X2653574Y497153D02*
Y491122D01*
G01X2652344D02*
Y497153D01*
G01X2649637D02*
Y491122D01*
G01X2648407D02*
Y497153D01*
G01X2645700Y497404D02*
Y491122D01*
G01X2644470D02*
Y499163D01*
G01X2646931D02*
X2647915D01*
G01X2650868D02*
X2651852D01*
G01X2644470D02*
X2645700D01*
G01X2651360Y498158D02*
X2650622D01*
G01X2647423D02*
X2646931D01*
G01X2650130Y498912D02*
X2650868Y499163D01*
G01X2646931Y498158D02*
X2646193Y497907D01*
G01Y498912D02*
X2646931Y499163D01*
G01X2651852D02*
X2652590Y498912D01*
G01X2647915Y499163D02*
X2648653Y498912D01*
G01X2651852Y497907D02*
X2651360Y498158D01*
G01X2647915Y497907D02*
X2647423Y498158D01*
G01X2650622D02*
X2650130Y497907D01*
G01X2652590Y498912D02*
X2653082Y498409D01*
G01X2652098Y497656D02*
X2651852Y497907D01*
G01X2650130D02*
X2649883Y497656D01*
G01X2649391Y498158D02*
X2650130Y498912D01*
G01X2646193Y497907D02*
X2645700Y497404D01*
G01Y498409D02*
X2646193Y498912D01*
G01X2648653D02*
X2649391Y498158D01*
G01X2648161Y497656D02*
X2647915Y497907D01*
G01X2653082Y498409D02*
X2653574Y497153D01*
G01X2652344D02*
X2652098Y497656D01*
G01X2648407Y497153D02*
X2648161Y497656D01*
G01X2649883D02*
X2649637Y497153D01*
G01X2645700Y499163D02*
Y498409D01*
G01X2658096Y519143D02*
Y527804D01*
X2654090Y521597D01*
X2659504D01*
G01X2664051Y522030D02*
X2666865D01*
G01X2644888Y516978D02*
X2759507D01*
G01X2660523Y1086791D02*
G03X2668004I3740J0D01*
G01X2660523D02*
Y1114153D01*
G01X2647925Y1094074D02*
X2645169D01*
G01X2651862D02*
X2649106D01*
G01X2655799D02*
X2653043D01*
G01X2659736D02*
X2656980D01*
G01D02*
Y1110610D01*
G01X2655799D02*
Y1094074D01*
G01X2653043D02*
Y1110610D01*
G01X2651862D02*
Y1094074D01*
G01X2649106D02*
Y1110610D01*
G01X2647925D02*
Y1094074D01*
G01X2645169D02*
Y1110610D01*
G01X2659736D02*
Y1094074D01*
G01X2656980Y1110610D02*
X2659736D01*
G01X2653043D02*
X2655799D01*
G01X2649106D02*
X2651862D01*
G01X2645169D02*
X2647925D01*
G01X2660523Y1114153D02*
X2658555Y1116122D01*
G01X2660366Y1163799D02*
X2661376Y1164449D01*
X2661954Y1165315D01*
X2662098Y1166289D01*
X2661954Y1167155D01*
X2661232Y1168022D01*
X2660366Y1168563D01*
X2659500Y1168671D01*
X2658489Y1168455D01*
X2657768Y1167697D01*
X2657479Y1166939D01*
Y1165964D01*
G01Y1166939D02*
X2657046Y1167588D01*
X2656324Y1168130D01*
X2655458Y1168346D01*
X2654592Y1168130D01*
X2653870Y1167588D01*
X2653437Y1166614D01*
X2653581Y1165640D01*
X2654159Y1164665D01*
G01X2660799Y1172460D02*
X2661521Y1173110D01*
X2661954Y1173868D01*
X2662098Y1174842D01*
X2661809Y1175816D01*
X2661232Y1176574D01*
X2660222Y1177116D01*
X2659067Y1177224D01*
X2657912Y1177007D01*
X2657190Y1176466D01*
X2656613Y1175708D01*
X2656468Y1174950D01*
X2656613Y1174192D01*
X2657190Y1173218D01*
X2653437Y1173543D01*
Y1176466D01*
G01X2662387Y1183503D02*
X2662242Y1183286D01*
X2661954D01*
X2661809Y1183503D01*
X2661954Y1183720D01*
X2662242D01*
X2662387Y1183503D01*
G01X2660799Y1189782D02*
X2661521Y1190432D01*
X2661954Y1191190D01*
X2662098Y1192164D01*
X2661809Y1193138D01*
X2661232Y1193896D01*
X2660222Y1194438D01*
X2659067Y1194546D01*
X2657912Y1194329D01*
X2657190Y1193788D01*
X2656613Y1193030D01*
X2656468Y1192272D01*
X2656613Y1191514D01*
X2657190Y1190540D01*
X2653437Y1190865D01*
Y1193788D01*
G01Y1200825D02*
X2653726Y1199959D01*
X2654447Y1199309D01*
X2655313Y1198876D01*
X2656468Y1198551D01*
X2657768Y1198443D01*
X2659067Y1198551D01*
X2660222Y1198876D01*
X2661088Y1199309D01*
X2661809Y1199959D01*
X2662098Y1200825D01*
X2661809Y1201691D01*
X2661088Y1202341D01*
X2660222Y1202774D01*
X2659067Y1203099D01*
X2657768Y1203207D01*
X2656468Y1203099D01*
X2655313Y1202774D01*
X2654447Y1202341D01*
X2653726Y1201691D01*
X2653437Y1200825D01*
G01X2675098Y-301374D02*
G03X2679035Y-305311I3937J0D01*
G01X2666043Y-291925D02*
X2663287D01*
G01X2669980D02*
X2667224D01*
G01D02*
Y-275389D01*
G01X2666043D02*
Y-291925D01*
G01X2663287D02*
Y-275389D01*
G01X2662106D02*
Y-291925D01*
G01X2675098Y-301374D02*
Y-271846D01*
G01X2671161Y-291925D02*
X2673917D01*
G01D02*
Y-279326D01*
G01X2671161D02*
Y-291925D01*
G01X2669980Y-275389D02*
Y-291925D01*
G01X2667224Y-275389D02*
X2669980D01*
G01X2663287D02*
X2666043D01*
G01X2673917Y-279326D02*
X2671161D01*
G01X2669783Y-267830D02*
X2668799D01*
G01X2666502D02*
X2665518D01*
G01D02*
X2664862Y-265820D01*
G01X2663877Y-259956D02*
X2666502Y-267830D01*
G01X2668799D02*
Y-261297D01*
G01X2661581Y-265820D02*
X2660925Y-267830D01*
G01X2668799Y-259956D02*
X2669783D01*
G01X2662565D02*
X2663877D01*
G01X2664698Y-265150D02*
X2661745D01*
G01X2664862Y-265820D02*
X2661581D01*
G01X2663221Y-260627D02*
X2664698Y-265150D01*
G01X2667814Y-262469D02*
Y-261129D01*
G01X2661745Y-265150D02*
X2663221Y-260627D01*
G01X2668799Y-261297D02*
X2667814Y-262469D01*
G01Y-261129D02*
X2668799Y-259956D01*
G01X2675098Y-271846D02*
X2673129Y-269878D01*
G01X2669783Y-259956D02*
Y-267830D01*
G01X2662492Y341948D02*
Y327775D01*
G01X2680011Y331397D02*
G03I-1574J0D01*
G01X2676074Y320885D02*
X2750878D01*
G01X2676074Y411437D02*
Y320885D01*
G01X2667374Y344783D02*
X2660860Y341948D01*
G01X2669578Y363405D02*
Y336633D01*
G01X2667570Y361043D02*
Y336633D01*
G01X2667374Y344783D02*
Y363405D01*
G01X2666822Y361043D02*
Y340570D01*
G01X2662558Y358287D02*
Y341948D01*
G01X2662531D02*
Y336633D01*
G01X2664815Y348248D02*
G03X2665405Y348838I0J590D01*
G01D02*
Y363405D01*
G01X2680011Y339271D02*
G03I-1574J0D01*
G01X2667374Y362263D02*
X2665405D01*
G01X2667964Y361043D02*
X2664342D01*
G01X2662452Y359468D02*
X2664815Y361437D01*
G01X2667964Y363405D02*
Y359468D01*
G01X2664815Y363405D02*
Y361437D01*
G01X2666281Y368248D02*
X2666803D01*
G01Y364074D02*
X2666281D01*
G01X2669578Y363405D02*
X2667374D01*
G01Y363011D02*
X2665405D01*
G01X2666281Y367537D02*
X2665759Y366916D01*
G01Y367626D02*
X2666281Y368248D01*
G01X2666803D02*
Y364074D01*
G01X2666281D02*
Y367537D01*
G01X2665759Y366916D02*
Y367626D01*
G01X2680011Y353051D02*
G03I-1574J0D01*
G01X2750878Y411437D02*
X2676074D01*
G01X2670547Y519143D02*
Y524917D01*
G01Y523473D02*
X2670981Y524195D01*
X2671630Y524773D01*
X2672496Y524917D01*
X2673254Y524773D01*
X2673904Y524195D01*
X2674229Y523185D01*
Y519143D01*
G01X2668004Y1114153D02*
Y1086791D01*
G01X2664263Y1090728D02*
Y1158602D01*
G01X2671547Y1094074D02*
X2668791D01*
G01X2675484D02*
X2672728D01*
G01D02*
Y1110610D01*
G01X2671547D02*
Y1094074D01*
G01X2668791D02*
Y1110610D01*
G01X2679421Y1094074D02*
X2676665D01*
G01D02*
Y1110610D01*
G01X2675484D02*
Y1094074D01*
G01X2710130Y1116122D02*
X2669972D01*
G01X2672728Y1110610D02*
X2675484D01*
G01X2668791D02*
X2671547D01*
G01X2712098D02*
X2668004D01*
G01X2669972Y1116122D02*
X2668004Y1114153D01*
G01X2676665Y1110610D02*
X2679421D01*
G01X2686807Y-1837784D02*
Y-1856796D01*
G01X2684076Y-946417D02*
X2682993Y-944973D01*
X2682452Y-943530D01*
Y-937756D01*
X2682993Y-936312D01*
X2684076Y-934869D01*
G01X2691113Y-943530D02*
Y-934869D01*
X2693711D01*
X2694577Y-935302D01*
X2695227Y-936312D01*
X2695443Y-937467D01*
X2695227Y-938622D01*
X2694685Y-939488D01*
X2693711Y-939921D01*
X2691113D01*
G01X2699232Y-943530D02*
X2701939Y-934869D01*
X2704646Y-943530D01*
G01X2703671Y-940499D02*
X2700207D01*
G01X2708218Y-943530D02*
Y-934869D01*
X2710383D01*
X2711250Y-935302D01*
X2711899Y-935879D01*
X2712441Y-936745D01*
X2712874Y-937756D01*
X2712982Y-939200D01*
X2712874Y-940643D01*
X2712441Y-941654D01*
X2711899Y-942520D01*
X2711250Y-943097D01*
X2710383Y-943530D01*
X2708218D01*
G01X2719802Y-946417D02*
X2720885Y-944973D01*
X2721426Y-943530D01*
Y-937756D01*
X2720885Y-936312D01*
X2719802Y-934869D01*
G01X2683572Y-932699D02*
X2682489Y-931255D01*
X2681948Y-929812D01*
Y-924038D01*
X2682489Y-922594D01*
X2683572Y-921151D01*
G01X2690609Y-929812D02*
Y-921151D01*
X2693207D01*
X2694073Y-921584D01*
X2694723Y-922594D01*
X2694939Y-923749D01*
X2694723Y-924904D01*
X2694181Y-925770D01*
X2693207Y-926203D01*
X2690609D01*
G01X2701435Y-921151D02*
Y-929812D01*
G01X2698945Y-921151D02*
X2703925D01*
G01X2707822Y-929812D02*
Y-921151D01*
G01X2712370D02*
Y-929812D01*
G01Y-925482D02*
X2707822D01*
G01X2719298Y-932699D02*
X2720381Y-931255D01*
X2720922Y-929812D01*
Y-924038D01*
X2720381Y-922594D01*
X2719298Y-921151D01*
G01X2686108Y-915827D02*
X2685025Y-914383D01*
X2684484Y-912940D01*
Y-907166D01*
X2685025Y-905722D01*
X2686108Y-904279D01*
G01X2693036Y-912940D02*
Y-904279D01*
G01X2697584D02*
Y-912940D01*
G01Y-908610D02*
X2693036D01*
G01X2702564Y-911352D02*
X2705378D01*
G01Y-908754D02*
X2702564D01*
G01X2712632Y-904279D02*
X2711766Y-904568D01*
X2711116Y-905289D01*
X2710683Y-906155D01*
X2710358Y-907310D01*
X2710250Y-908610D01*
X2710358Y-909909D01*
X2710683Y-911064D01*
X2711116Y-911930D01*
X2711766Y-912651D01*
X2712632Y-912940D01*
X2713498Y-912651D01*
X2714148Y-911930D01*
X2714581Y-911064D01*
X2714906Y-909909D01*
X2715014Y-908610D01*
X2714906Y-907310D01*
X2714581Y-906155D01*
X2714148Y-905289D01*
X2713498Y-904568D01*
X2712632Y-904279D01*
G01X2718045Y-912940D02*
Y-907166D01*
G01Y-908754D02*
X2718370Y-908032D01*
X2718911Y-907455D01*
X2719669Y-907166D01*
X2720427Y-907455D01*
X2720968Y-908032D01*
X2721293Y-908754D01*
Y-912940D01*
G01Y-908754D02*
X2721618Y-908032D01*
X2722159Y-907455D01*
X2722917Y-907166D01*
X2723675Y-907455D01*
X2724216Y-908032D01*
X2724541Y-908898D01*
Y-912940D01*
G01X2726706D02*
Y-907166D01*
G01Y-908754D02*
X2727031Y-908032D01*
X2727572Y-907455D01*
X2728330Y-907166D01*
X2729088Y-907455D01*
X2729629Y-908032D01*
X2729954Y-908754D01*
Y-912940D01*
G01Y-908754D02*
X2730279Y-908032D01*
X2730820Y-907455D01*
X2731578Y-907166D01*
X2732336Y-907455D01*
X2732877Y-908032D01*
X2733202Y-908898D01*
Y-912940D01*
G01X2739156Y-915827D02*
X2740239Y-914383D01*
X2740780Y-912940D01*
Y-907166D01*
X2740239Y-905722D01*
X2739156Y-904279D01*
G01X2690196Y-893661D02*
X2689113Y-892217D01*
X2688572Y-890774D01*
Y-885000D01*
X2689113Y-883556D01*
X2690196Y-882113D01*
G01X2696908Y-890774D02*
Y-882113D01*
X2701888Y-890774D01*
Y-882113D01*
G01X2705894Y-890774D02*
Y-882113D01*
X2708492D01*
X2709358Y-882546D01*
X2710008Y-883556D01*
X2710224Y-884711D01*
X2710008Y-885866D01*
X2709466Y-886732D01*
X2708492Y-887165D01*
X2705894D01*
G01X2716720Y-882113D02*
Y-890774D01*
G01X2714230Y-882113D02*
X2719210D01*
G01X2723107Y-890774D02*
Y-882113D01*
G01X2727655D02*
Y-890774D01*
G01Y-886444D02*
X2723107D01*
G01X2734583Y-893661D02*
X2735666Y-892217D01*
X2736207Y-890774D01*
Y-885000D01*
X2735666Y-883556D01*
X2734583Y-882113D01*
G01X2748720Y-305311D02*
X2679035D01*
G01X2677945Y329429D02*
X2678929D01*
G01Y328661D02*
X2677945D01*
G01X2678929Y327086D02*
X2677945D01*
G01X2678929Y326496D02*
X2677945D01*
G01Y323622D02*
X2749007D01*
G01X2677945Y321653D02*
X2678929D01*
G01X2677945Y320866D02*
X2678929D01*
G01X2680405Y360236D02*
Y323622D01*
G01X2678929Y360313D02*
Y320866D01*
G01X2677945D02*
Y360236D01*
G01X2680398Y335330D02*
G03X2680250Y336533I-844J507D01*
G01X2681242Y334823D02*
G03X2680946Y337229I-1688J1014D01*
G01X2678929Y333956D02*
X2677945D01*
G01X2678929Y332775D02*
X2677945D01*
G01Y332670D02*
X2678929D01*
G01Y332374D02*
X2677945D01*
G01X2678929Y331023D02*
X2677945D01*
G01Y331011D02*
X2678929D01*
G01Y330715D02*
X2677945D01*
G01X2678929Y330610D02*
X2677945D01*
G01X2681242Y334823D02*
X2679668Y332204D01*
G01X2680398Y335330D02*
X2678824Y332711D01*
G01X2679838Y334399D02*
X2680682Y333892D01*
G01X2678824Y332711D02*
X2679668Y332204D01*
G01X2695759Y339435D02*
G03Y333793I0J-2821D01*
G01Y340287D02*
G03Y332941I1J-3673D01*
G01X2679460Y339072D02*
G03X2679747Y338428I983J52D01*
G01X2678477Y339021D02*
G03X2679051Y337732I1966J103D01*
G01X2678929Y341830D02*
X2677945D01*
G01X2678929Y340649D02*
X2677945D01*
G01Y340544D02*
X2678929D01*
G01Y340248D02*
X2677945D01*
G01Y338885D02*
X2678929D01*
G01Y338589D02*
X2677945D01*
G01X2678929Y338484D02*
X2677945D01*
G01Y337303D02*
X2678929D01*
G01X2679747Y338428D02*
X2680946Y337229D01*
G01X2679051Y337732D02*
X2680250Y336533D01*
G01X2678929Y349212D02*
X2679460Y339072D01*
G01X2677945Y349187D02*
X2678477Y339021D01*
G01X2677945Y351082D02*
X2678929D01*
G01Y350196D02*
X2677945D01*
G01X2678929Y349212D02*
X2677945D01*
G01X2678045Y360774D02*
G03X2677946Y360236I1868J-622D01*
G01X2692610D02*
X2677945D01*
G01X2678929Y355610D02*
X2677945D01*
G01X2678929Y354429D02*
X2677945D01*
G01Y354323D02*
X2678929D01*
G01Y354028D02*
X2677945D01*
G01Y352664D02*
X2678929D01*
G01Y352369D02*
X2677945D01*
G01X2678929Y352263D02*
X2677945D01*
G01X2680158Y364020D02*
X2678929Y360313D01*
G01X2679124Y364029D02*
X2678045Y360774D01*
G01X2680158Y364020D02*
G03X2680208Y364330I-934J310D01*
G01X2682767Y364842D02*
G03X2683948Y366023I0J1181D01*
G01X2679124Y364029D02*
G03X2679224Y364648I-1868J619D01*
G01X2689618Y368346D02*
X2691665D01*
G01X2686468D02*
X2688515D01*
G01X2688279Y366909D02*
X2686704D01*
G01X2691429D02*
X2689854D01*
G01X2682374Y366850D02*
X2744578D01*
G01X2679224Y365137D02*
X2684480D01*
G01X2682767Y364842D02*
X2679224D01*
G01X2747728Y364153D02*
X2679224D01*
G01X2690149Y368878D02*
X2689618Y368346D01*
G01X2687000Y368878D02*
X2686468Y368346D01*
G01X2680208Y364153D02*
X2681193Y365137D01*
G01X2682374Y366850D02*
X2679677Y364153D01*
G01X2687984Y368878D02*
X2688515Y368346D01*
G01X2689854Y366909D02*
Y364153D01*
G01X2689696Y397756D02*
Y364153D01*
G01X2689618Y397441D02*
Y368346D01*
G01X2688515D02*
Y397441D01*
G01X2688437Y397756D02*
Y364153D01*
G01X2688279Y366909D02*
Y364153D01*
G01X2686704Y366909D02*
Y364153D01*
G01X2686547Y397756D02*
Y364153D01*
G01X2686468Y397441D02*
Y368346D01*
G01X2685287Y397756D02*
Y364153D01*
G01X2684480D02*
Y379901D01*
G01X2683948Y372322D02*
Y366023D01*
G01X2682374Y388248D02*
Y366850D01*
G01X2681193Y364842D02*
Y365137D01*
G01D02*
Y373602D01*
G01X2680208Y364153D02*
Y388130D01*
G01X2679224Y364153D02*
Y409429D01*
G01X2692610Y355315D02*
G03X2694578I984J0D01*
G01X2692610Y360236D02*
Y355315D01*
G01X2692767Y368346D02*
X2694815D01*
G01X2694578Y366909D02*
X2693004D01*
G01X2693299Y368878D02*
X2692767Y368346D01*
G01X2691133Y368878D02*
X2691665Y368346D01*
G01X2693004Y366909D02*
Y364153D01*
G01X2692846Y397756D02*
Y364153D01*
G01X2692767Y397441D02*
Y368346D01*
G01X2691665D02*
Y397441D01*
G01X2691586Y397756D02*
Y364153D01*
G01X2691429Y366909D02*
Y364153D01*
G01X2683948Y372322D02*
G03X2682767Y373504I-1181J1D01*
G01X2683693Y376541D02*
G03Y374600I-1713J-971D01*
G01X2684480Y376730D02*
G03Y374411I-2500J-1160D01*
G01X2685051Y375571D02*
G03I-3071J0D01*
G01X2689266Y369964D02*
X2688867D01*
G01X2686116D02*
X2685718D01*
G01X2684480Y379114D02*
X2679224D01*
G01X2688515Y378523D02*
X2687984D01*
G01X2687000D02*
X2686468D01*
G01X2690149D02*
X2689618D01*
G01X2687204Y376504D02*
X2687780D01*
G01X2686196Y376263D02*
X2685638D01*
G01X2689346D02*
X2688788D01*
G01X2687885Y376160D02*
X2687098D01*
G01X2691035D02*
X2690248D01*
G01X2688818Y376064D02*
X2689315D01*
G01X2685668D02*
X2686166D01*
G01X2686161Y376039D02*
X2685673D01*
G01X2689310D02*
X2688823D01*
G01X2685523Y376006D02*
X2686311D01*
G01X2688673D02*
X2689460D01*
G01X2686311Y375823D02*
X2685523D01*
G01X2689460D02*
X2688673D01*
G01X2685523Y375682D02*
X2686311D01*
G01X2688673D02*
X2689460D01*
G01X2686311Y375465D02*
X2685523D01*
G01X2689460D02*
X2688673D01*
G01X2688834Y375165D02*
X2689299D01*
G01X2685684D02*
X2686150D01*
G01X2690248Y375135D02*
X2691035D01*
G01X2687098D02*
X2687885D01*
G01X2687771Y374710D02*
X2687213D01*
G01X2684480Y373602D02*
X2679224D01*
G01Y373504D02*
X2682767D01*
G01X2689618Y372618D02*
X2690149D01*
G01X2687984D02*
X2688515D01*
G01X2686468D02*
X2687000D01*
G01X2690248Y371785D02*
X2691035D01*
G01X2687098D02*
X2687885D01*
G01X2686311Y371314D02*
X2685523D01*
G01X2689460D02*
X2688673D01*
G01X2684480Y371240D02*
X2679224D01*
G01X2687885Y370502D02*
X2687098D01*
G01X2691035D02*
X2690248D01*
G01X2685581Y370476D02*
X2686254D01*
G01X2688730D02*
X2689403D01*
G01X2679224Y370452D02*
X2684480D01*
G01X2690248Y370252D02*
X2691035D01*
G01X2687098D02*
X2687885D01*
G01X2688801Y370212D02*
X2689332D01*
G01X2685651D02*
X2686183D01*
G01X2686182Y370207D02*
X2685653D01*
G01X2689331D02*
X2688802D01*
G01X2687885Y370198D02*
X2687098D01*
G01X2691035D02*
X2690248D01*
G01X2687885Y370171D02*
X2687098D01*
G01X2691035D02*
X2690248D01*
G01X2688869Y369955D02*
X2689263D01*
G01X2685719D02*
X2686114D01*
G01X2690149Y368878D02*
X2691133D01*
G01X2687000D02*
X2687984D01*
G01X2687885Y370324D02*
X2687098Y370323D01*
G01X2691035Y370324D02*
X2690248Y370323D01*
G01X2689263Y369955D02*
X2689460Y370689D01*
G01X2686114Y369955D02*
X2686311Y370689D01*
G01X2689315Y376064D02*
X2689310Y376039D01*
G01X2686166Y376064D02*
X2686161Y376039D01*
G01X2687780Y376504D02*
X2687885Y377021D01*
G01X2690362Y374710D02*
X2690248Y374117D01*
G01X2687213Y374710D02*
X2687098Y374117D01*
G01X2688673Y374267D02*
X2688834Y375165D01*
G01X2685523Y374267D02*
X2685684Y375165D01*
G01X2689460Y377419D02*
X2689346Y376263D01*
G01X2686311Y377419D02*
X2686196Y376263D01*
G01X2690248Y370171D02*
Y398326D01*
G01X2690149Y372618D02*
Y368878D01*
G01Y396909D02*
Y378523D01*
G01X2689460Y370689D02*
Y407972D01*
G01X2688673Y370689D02*
Y407972D01*
G01X2687984Y378523D02*
Y396909D01*
G01Y368878D02*
Y372618D01*
G01X2687885Y398326D02*
Y370171D01*
G01X2687098D02*
Y398326D01*
G01X2687000Y372618D02*
Y368878D01*
G01Y396909D02*
Y378523D01*
G01X2686311Y370689D02*
Y407972D01*
G01X2685523Y370689D02*
Y407972D01*
G01X2683693Y374600D02*
Y376541D01*
G01X2688788Y376263D02*
X2688673Y377419D01*
G01X2689299Y375165D02*
X2689460Y374267D01*
G01X2686150Y375165D02*
X2686311Y374267D01*
G01X2687885Y374117D02*
X2687771Y374710D01*
G01X2690353Y376504D02*
X2690248Y377021D01*
G01X2687204Y376504D02*
X2687098Y377021D01*
G01X2688823Y376039D02*
X2688818Y376064D01*
G01X2685673Y376039D02*
X2685668Y376064D01*
G01X2688870Y369955D02*
X2688673Y370689D01*
G01X2685720Y369955D02*
X2685523Y370689D01*
G01X2685638Y376263D02*
X2685523Y377419D01*
G01X2681153Y381653D02*
X2680187Y381466D01*
G01X2680208Y381043D02*
X2681193D01*
G01X2680208Y380551D02*
X2679224D01*
G01X2684480Y379901D02*
X2679224D01*
G01X2681193Y381043D02*
Y398011D01*
G01X2681153Y381653D02*
X2680208Y386535D01*
G01X2679224Y386441D02*
X2680187Y381466D01*
G01X2692415Y369964D02*
X2692017D01*
G01X2693299Y378523D02*
X2692767D01*
G01X2691665D02*
X2691133D01*
G01X2693503Y376504D02*
X2694079D01*
G01X2690353D02*
X2690930D01*
G01X2692495Y376263D02*
X2691937D01*
G01X2694185Y376160D02*
X2693397D01*
G01X2691967Y376064D02*
X2692465D01*
G01X2692460Y376039D02*
X2691972D01*
G01X2691822Y376006D02*
X2692610D01*
G01Y375823D02*
X2691822D01*
G01Y375682D02*
X2692610D01*
G01Y375465D02*
X2691822D01*
G01X2691983Y375165D02*
X2692449D01*
G01X2693397Y375135D02*
X2694185D01*
G01X2690920Y374710D02*
X2690362D01*
G01X2694070D02*
X2693512D01*
G01X2692767Y372618D02*
X2693299D01*
G01X2691133D02*
X2691665D01*
G01X2693397Y371785D02*
X2694185D01*
G01X2692610Y371314D02*
X2691822D01*
G01X2694185Y370502D02*
X2693397D01*
G01X2691880Y370476D02*
X2692553D01*
G01X2693397Y370252D02*
X2694185D01*
G01X2691950Y370212D02*
X2692482D01*
G01X2692481Y370207D02*
X2691952D01*
G01X2694185Y370198D02*
X2693397D01*
G01X2694185Y370171D02*
X2693397D01*
G01X2692019Y369955D02*
X2692413D01*
G01X2693299Y368878D02*
X2694283D01*
G01X2694185Y370324D02*
X2693397Y370323D01*
G01X2692413Y369955D02*
X2692610Y370689D01*
G01X2692465Y376064D02*
X2692460Y376039D01*
G01X2690930Y376504D02*
X2691035Y377021D01*
G01X2693512Y374710D02*
X2693397Y374117D01*
G01X2691822Y374267D02*
X2691983Y375165D01*
G01X2692610Y377419D02*
X2692495Y376263D01*
G01X2693397Y370171D02*
Y398326D01*
G01X2693299Y372618D02*
Y368878D01*
G01Y396909D02*
Y378523D01*
G01X2692610Y370689D02*
Y407972D01*
G01X2691822Y370689D02*
Y407972D01*
G01X2691133Y378523D02*
Y396909D01*
G01Y368878D02*
Y372618D01*
G01X2691035Y370171D02*
Y398326D01*
G01X2691937Y376263D02*
X2691822Y377419D01*
G01X2692449Y375165D02*
X2692610Y374267D01*
G01X2691035Y374117D02*
X2690920Y374710D01*
G01X2693503Y376504D02*
X2693397Y377021D01*
G01X2691972Y376039D02*
X2691967Y376064D01*
G01X2692019Y369955D02*
X2691822Y370689D01*
G01X2689618Y394074D02*
X2690149Y394294D01*
G01X2687000D02*
X2686468Y394074D01*
G01X2687885Y394901D02*
X2687098D01*
G01X2691035D02*
X2690248D01*
G01X2687885Y394665D02*
X2687098D01*
G01X2691035D02*
X2690248D01*
G01X2685523Y394626D02*
X2686311D01*
G01X2688673D02*
X2689460D01*
G01X2685523Y394586D02*
X2686311D01*
G01X2688673D02*
X2689460D01*
G01X2687885Y394488D02*
X2687098D01*
G01X2691035D02*
X2690248D01*
G01X2686311Y394347D02*
X2685523D01*
G01X2689460D02*
X2688673D01*
G01X2690248Y394311D02*
X2691035D01*
G01X2687098D02*
X2687885D01*
G01X2686468Y394074D02*
X2679224D01*
G01X2687885D02*
X2687098D01*
G01X2689618D02*
X2688515D01*
G01X2691035D02*
X2690248D01*
G01X2690149Y394055D02*
X2691133D01*
G01X2687000D02*
X2687984D01*
G01X2690248Y393996D02*
X2691035D01*
G01X2687098D02*
X2687885D01*
G01X2687984Y393740D02*
X2687000D01*
G01X2691133D02*
X2690149D01*
G01X2690248Y393702D02*
X2691035D01*
G01X2687098D02*
X2687885D01*
G01Y393681D02*
X2687098D01*
G01X2691035D02*
X2690248D01*
G01X2687876Y393641D02*
X2687107D01*
G01X2691026D02*
X2690257D01*
G01X2687885Y393629D02*
X2687098D01*
G01X2691035D02*
X2690248D01*
G01Y393594D02*
X2691035D01*
G01X2687098D02*
X2687885D01*
G01X2687210Y393539D02*
X2687774D01*
G01X2685523Y393526D02*
X2686311D01*
G01X2688673D02*
X2689460D01*
G01X2690248Y393514D02*
X2691035D01*
G01X2687098D02*
X2687885D01*
G01X2686311Y393408D02*
X2685523D01*
G01X2689460D02*
X2688673D01*
G01X2686468Y393287D02*
X2679224D01*
G01X2689618D02*
X2688515D01*
G01X2687689Y393283D02*
X2687295D01*
G01X2687984Y392500D02*
X2690149D01*
G01X2679224D02*
X2687000D01*
G01X2685523Y392254D02*
X2686311D01*
G01X2688673D02*
X2689460D01*
G01X2685523Y392231D02*
X2686311D01*
G01X2688673D02*
X2689460D01*
G01X2686311Y391977D02*
X2685523D01*
G01X2689460D02*
X2688673D01*
G01X2686311Y391318D02*
X2685523D01*
G01X2689460D02*
X2688673D01*
G01X2687295Y391126D02*
X2687689D01*
G01X2687774Y390870D02*
X2687210D01*
G01X2690257Y390768D02*
X2691026D01*
G01X2687107D02*
X2687876D01*
G01X2686311Y390728D02*
X2685523D01*
G01X2689460D02*
X2688673D01*
G01X2687984D02*
X2687000D01*
G01X2691133D02*
X2690149D01*
G01X2687885Y390515D02*
X2687098D01*
G01X2691035D02*
X2690248D01*
G01X2690149Y390413D02*
X2691133D01*
G01X2687000D02*
X2687984D01*
G01X2686311Y390137D02*
X2685523D01*
G01X2689460D02*
X2688673D01*
G01X2690149Y390098D02*
X2691133D01*
G01X2687000D02*
X2687984D01*
G01X2690248Y390082D02*
X2691035D01*
G01X2687098D02*
X2687885D01*
G01X2690248Y389858D02*
X2691035D01*
G01X2687098D02*
X2687885D01*
G01X2685523Y389547D02*
X2686311D01*
G01X2688673D02*
X2689460D01*
G01X2687885Y389425D02*
X2687098D01*
G01X2691035D02*
X2690248D01*
G01X2686311Y388956D02*
X2685523D01*
G01X2689460D02*
X2688673D01*
G01X2744578Y388248D02*
X2682374D01*
G01X2679224Y388228D02*
X2680208D01*
G01Y388130D02*
X2679224D01*
G01Y387047D02*
X2680208D01*
G01Y386653D02*
X2679224D01*
G01X2680338Y385866D02*
X2679224D01*
G01X2690257Y390768D02*
X2690359Y390870D01*
G01X2687107Y390768D02*
X2687210Y390870D01*
G01X2689618Y393287D02*
X2690149Y393818D01*
G01D02*
X2689618Y393287D01*
G01X2687774Y393539D02*
X2687876Y393641D01*
G01X2686468Y393287D02*
X2687000Y393818D01*
G01D02*
X2686468Y393287D01*
G01X2687984Y394294D02*
X2688515Y394074D01*
G01X2690359Y393539D02*
X2690257Y393641D01*
G01X2687984Y393818D02*
X2688515Y393287D01*
G01D02*
X2687984Y393818D01*
G01X2687210Y393539D02*
X2687107Y393641D01*
G01X2687774Y390870D02*
X2687876Y390768D01*
G01X2689559Y397618D02*
Y388248D01*
G01X2688574Y397618D02*
Y388248D01*
G01X2687689Y393283D02*
Y391126D01*
G01X2687295D02*
Y393283D01*
G01X2686409Y397618D02*
Y388248D01*
G01X2685425Y397618D02*
Y388248D01*
G01X2680208Y388130D02*
Y388228D01*
G01X2744578Y399586D02*
X2682374D01*
G01X2686311Y398602D02*
X2685523D01*
G01X2689460D02*
X2688673D01*
G01X2687885Y398326D02*
X2687098D01*
G01X2691035D02*
X2690248D01*
G01X2747728Y398011D02*
X2679224D01*
G01X2687885Y397736D02*
X2687098D01*
G01X2691035D02*
X2690248D01*
G01X2685425Y397618D02*
X2686409D01*
G01X2689559D02*
X2688574D01*
G01X2688515Y397441D02*
X2686468D01*
G01X2691665D02*
X2689618D01*
G01X2686311Y397421D02*
X2685523D01*
G01X2689460D02*
X2688673D01*
G01X2687984Y396909D02*
X2687000D01*
G01X2691133D02*
X2690149D01*
G01X2687885Y396830D02*
X2687098D01*
G01X2691035D02*
X2690248D01*
G01X2685523Y396633D02*
X2686311D01*
G01X2688673D02*
X2689460D01*
G01X2690248Y396594D02*
X2691035D01*
G01X2687098D02*
X2687885D01*
G01X2686311Y396515D02*
X2685523D01*
G01X2689460D02*
X2688673D01*
G01X2687885Y396417D02*
X2687098D01*
G01X2691035D02*
X2690248D01*
G01X2689854Y396043D02*
X2688279D01*
G01X2686704D02*
X2685130D01*
G01X2687885D02*
X2687098D01*
G01X2691035D02*
X2690248D01*
G01X2687885Y396004D02*
X2687098D01*
G01X2691035D02*
X2690248D01*
G01X2689952Y398011D02*
X2689559Y397618D01*
G01X2687984Y396909D02*
X2688515Y397441D01*
G01X2686803Y398011D02*
X2686409Y397618D01*
G01X2689618Y397441D02*
X2690149Y396909D01*
G01X2688181Y398011D02*
X2688574Y397618D01*
G01X2686468Y397441D02*
X2687000Y396909D01*
G01X2685031Y398011D02*
X2685425Y397618D01*
G01X2689854Y398011D02*
Y396043D01*
G01X2688279Y398011D02*
Y396043D01*
G01X2686704Y398011D02*
Y396043D01*
G01X2685130Y398011D02*
Y396043D01*
G01X2682374Y399586D02*
Y404704D01*
G01X2692767Y394074D02*
X2693299Y394294D01*
G01X2694185Y394901D02*
X2693397D01*
G01X2694185Y394665D02*
X2693397D01*
G01X2691822Y394626D02*
X2692610D01*
G01X2691822Y394586D02*
X2692610D01*
G01X2694185Y394488D02*
X2693397D01*
G01X2692610Y394347D02*
X2691822D01*
G01X2693397Y394311D02*
X2694185D01*
G01Y394074D02*
X2693397D01*
G01X2692767D02*
X2691665D01*
G01X2693299Y394055D02*
X2694283D01*
G01X2693397Y393996D02*
X2694185D01*
G01X2694283Y393740D02*
X2693299D01*
G01X2693397Y393702D02*
X2694185D01*
G01Y393681D02*
X2693397D01*
G01X2694176Y393641D02*
X2693406D01*
G01X2694185Y393629D02*
X2693397D01*
G01Y393594D02*
X2694185D01*
G01X2693509Y393539D02*
X2694073D01*
G01X2690359D02*
X2690924D01*
G01X2691822Y393526D02*
X2692610D01*
G01X2693397Y393514D02*
X2694185D01*
G01X2692610Y393408D02*
X2691822D01*
G01X2692767Y393287D02*
X2691665D01*
G01X2690838Y393283D02*
X2690445D01*
G01X2693988D02*
X2693594D01*
G01X2691133Y392500D02*
X2693299D01*
G01X2691822Y392254D02*
X2692610D01*
G01X2691822Y392231D02*
X2692610D01*
G01Y391977D02*
X2691822D01*
G01X2692610Y391318D02*
X2691822D01*
G01X2693594Y391126D02*
X2693988D01*
G01X2690445D02*
X2690838D01*
G01X2690924Y390870D02*
X2690359D01*
G01X2694073D02*
X2693509D01*
G01X2693406Y390768D02*
X2694176D01*
G01X2692610Y390728D02*
X2691822D01*
G01X2694283D02*
X2693299D01*
G01X2694185Y390515D02*
X2693397D01*
G01X2693299Y390413D02*
X2694283D01*
G01X2692610Y390137D02*
X2691822D01*
G01X2693299Y390098D02*
X2694283D01*
G01X2693397Y390082D02*
X2694185D01*
G01X2693397Y389858D02*
X2694185D01*
G01X2691822Y389547D02*
X2692610D01*
G01X2694185Y389425D02*
X2693397D01*
G01X2692610Y388956D02*
X2691822D01*
G01X2693406Y390768D02*
X2693509Y390870D01*
G01X2692767Y393287D02*
X2693299Y393818D01*
G01D02*
X2692767Y393287D01*
G01X2690924Y393539D02*
X2691026Y393641D01*
G01X2691133Y394294D02*
X2691665Y394074D01*
G01X2693509Y393539D02*
X2693406Y393641D01*
G01X2691133Y393818D02*
X2691665Y393287D01*
G01D02*
X2691133Y393818D01*
G01X2690924Y390870D02*
X2691026Y390768D01*
G01X2693594Y391126D02*
Y393283D01*
G01X2692708Y397618D02*
Y388248D01*
G01X2691724Y397618D02*
Y388248D01*
G01X2690838Y393283D02*
Y391126D01*
G01X2690445D02*
Y393283D01*
G01X2692610Y398602D02*
X2691822D01*
G01X2694185Y398326D02*
X2693397D01*
G01X2694185Y397736D02*
X2693397D01*
G01X2692708Y397618D02*
X2691724D01*
G01X2694815Y397441D02*
X2692767D01*
G01X2692610Y397421D02*
X2691822D01*
G01X2694283Y396909D02*
X2693299D01*
G01X2694185Y396830D02*
X2693397D01*
G01X2691822Y396633D02*
X2692610D01*
G01X2693397Y396594D02*
X2694185D01*
G01X2692610Y396515D02*
X2691822D01*
G01X2694185Y396417D02*
X2693397D01*
G01X2693004Y396043D02*
X2691429D01*
G01X2694185D02*
X2693397D01*
G01X2694185Y396004D02*
X2693397D01*
G01X2693102Y398011D02*
X2692708Y397618D01*
G01X2691133Y396909D02*
X2691665Y397441D01*
G01X2692767D02*
X2693299Y396909D01*
G01X2691330Y398011D02*
X2691724Y397618D01*
G01X2693004Y398011D02*
Y396043D01*
G01X2691429Y398011D02*
Y396043D01*
G01X2685961Y408308D02*
X2685858Y408287D01*
G01X2679224Y409429D02*
X2682374D01*
G01X2686412Y409271D02*
X2686535D01*
G01X2685366D02*
X2685858D01*
G01X2685878Y409146D02*
X2685489D01*
G01Y408852D02*
X2685878D01*
G01X2685489Y408727D02*
X2685878D01*
G01X2679224Y408641D02*
X2682374D01*
G01X2685878Y408413D02*
X2685489D01*
G01X2686535Y408287D02*
X2686412D01*
G01X2685858D02*
X2685366D01*
G01X2686311Y407972D02*
X2685523D01*
G01X2689460D02*
X2688673D01*
G01X2686311Y407381D02*
X2685523D01*
G01X2689460D02*
X2688673D01*
G01X2685523Y406476D02*
X2686311D01*
G01X2688673D02*
X2689460D01*
G01X2690169Y405885D02*
X2691114D01*
G01X2687019D02*
X2687964D01*
G01X2679224D02*
X2684815D01*
G01X2686311D02*
X2685523D01*
G01X2689460D02*
X2688673D01*
G01X2686311Y405177D02*
X2685523D01*
G01X2689460D02*
X2688673D01*
G01X2679224Y405098D02*
X2682374D01*
G01X2679224Y404704D02*
X2682374D01*
G01X2686311Y404232D02*
X2685523D01*
G01X2689460D02*
X2688673D01*
G01X2682374Y403917D02*
X2679224D01*
G01X2688555Y403641D02*
X2689578D01*
G01X2685405D02*
X2686429D01*
G01X2679224Y403130D02*
X2682374D01*
G01X2685523Y403051D02*
X2686311D01*
G01X2688673D02*
X2689460D01*
G01X2685940Y408433D02*
X2685878Y408413D01*
G01Y408852D02*
X2685940Y408874D01*
G01X2686043Y408811D02*
X2686002Y408790D01*
G01X2685858Y409271D02*
X2685961Y409250D01*
G01X2685940Y409125D02*
X2685878Y409146D01*
G01Y408727D02*
X2685940Y408706D01*
G01X2686043Y408371D02*
X2685961Y408308D01*
G01X2690169Y405885D02*
X2689578Y405295D01*
G01X2686002Y408790D02*
X2686043Y408769D01*
G01X2687019Y405885D02*
X2686429Y405295D01*
G01X2685981Y408476D02*
X2685940Y408433D01*
G01Y408874D02*
X2685981Y408915D01*
G01X2686412Y409104D02*
X2686289Y408957D01*
G01Y409125D02*
X2686412Y409271D01*
G01X2685961Y409250D02*
X2686043Y409187D01*
G01X2686104Y408455D02*
X2686043Y408371D01*
G01X2686104Y408894D02*
X2686043Y408811D01*
G01X2685981Y409083D02*
X2685940Y409125D01*
G01Y408706D02*
X2685981Y408664D01*
G01X2687964Y405885D02*
X2688555Y405295D01*
G01X2684815Y405885D02*
X2685405Y405295D01*
G01X2686124Y408517D02*
X2686104Y408455D01*
G01X2686002Y408538D02*
X2685981Y408476D01*
G01X2686124Y408957D02*
X2686104Y408894D01*
G01X2685981Y408915D02*
X2686002Y408978D01*
G01X2686104Y409104D02*
X2686124Y409041D01*
G01X2686002Y409020D02*
X2685981Y409083D01*
G01X2686104Y408685D02*
X2686124Y408622D01*
G01X2685981Y408664D02*
X2686002Y408601D01*
G01X2686043Y409187D02*
X2686104Y409104D01*
G01X2686043Y408769D02*
X2686104Y408685D01*
G01X2689578Y403641D02*
Y405295D01*
G01X2688555D02*
Y403641D01*
G01X2686535Y409271D02*
Y408287D01*
G01X2686429Y403641D02*
Y405295D01*
G01X2686412Y408287D02*
Y409104D01*
G01X2686289Y408957D02*
Y409125D01*
G01X2686124Y408622D02*
Y408517D01*
G01Y409041D02*
Y408957D01*
G01X2686002Y408978D02*
Y409020D01*
G01Y408601D02*
Y408538D01*
G01X2685489Y408413D02*
Y408727D01*
G01Y409146D02*
Y408852D01*
G01X2685405Y405295D02*
Y403641D01*
G01X2685366Y408287D02*
Y409271D01*
G01X2682374Y409429D02*
Y405098D01*
G01X2692610Y407972D02*
X2691822D01*
G01X2692610Y407381D02*
X2691822D01*
G01Y406476D02*
X2692610D01*
G01X2693319Y405885D02*
X2694263D01*
G01X2692610D02*
X2691822D01*
G01X2692610Y405177D02*
X2691822D01*
G01X2692610Y404232D02*
X2691822D01*
G01X2691704Y403641D02*
X2692728D01*
G01X2691822Y403051D02*
X2692610D01*
G01X2693319Y405885D02*
X2692728Y405295D01*
G01X2691114Y405885D02*
X2691704Y405295D01*
G01X2692728Y403641D02*
Y405295D01*
G01X2691704D02*
Y403641D01*
G01X2685235Y519143D02*
Y527804D01*
X2681229Y521597D01*
X2686643D01*
G01X2692597Y518854D02*
X2692380Y518999D01*
Y519287D01*
X2692597Y519432D01*
X2692814Y519287D01*
Y518999D01*
X2692597Y518854D01*
G01X2701258Y527804D02*
X2700392Y527515D01*
X2699742Y526794D01*
X2699309Y525928D01*
X2698984Y524773D01*
X2698876Y523473D01*
X2698984Y522174D01*
X2699309Y521019D01*
X2699742Y520153D01*
X2700392Y519432D01*
X2701258Y519143D01*
X2702124Y519432D01*
X2702774Y520153D01*
X2703207Y521019D01*
X2703532Y522174D01*
X2703640Y523473D01*
X2703532Y524773D01*
X2703207Y525928D01*
X2702774Y526794D01*
X2702124Y527515D01*
X2701258Y527804D01*
G01X2709919D02*
X2709053Y527515D01*
X2708403Y526794D01*
X2707970Y525928D01*
X2707645Y524773D01*
X2707537Y523473D01*
X2707645Y522174D01*
X2707970Y521019D01*
X2708403Y520153D01*
X2709053Y519432D01*
X2709919Y519143D01*
X2710785Y519432D01*
X2711435Y520153D01*
X2711868Y521019D01*
X2712193Y522174D01*
X2712301Y523473D01*
X2712193Y524773D01*
X2711868Y525928D01*
X2711435Y526794D01*
X2710785Y527515D01*
X2709919Y527804D01*
G01X2741518Y809409D02*
X2684618D01*
G01Y844409D02*
Y809409D01*
G01X2701122Y811409D02*
X2690622D01*
G01D02*
Y838409D01*
G01X2689618Y814409D02*
X2809618D01*
G01X2741518Y813622D02*
X2688830D01*
G01X2689618Y839409D02*
Y814409D01*
G01X2688830Y840196D02*
Y813622D01*
G01D02*
X2689618Y814409D01*
G01X2696622Y815409D02*
X2690622D01*
G01X2814618Y844409D02*
X2684618D01*
G01X2810405Y840196D02*
X2688830D01*
G01X2809618Y839409D02*
X2689618D01*
G01X2688830Y840196D02*
X2689618Y839409D01*
G01X2690622Y838409D02*
X2808614D01*
G01X2683358Y1094074D02*
X2680602D01*
G01X2687295D02*
X2684539D01*
G01X2691232D02*
X2688476D01*
G01D02*
Y1110610D01*
G01X2687295D02*
Y1094074D01*
G01X2684539D02*
Y1110610D01*
G01X2683358D02*
Y1094074D01*
G01X2680602D02*
Y1110610D01*
G01X2679421D02*
Y1094074D01*
G01X2695169D02*
X2692413D01*
G01D02*
Y1110610D01*
G01X2691232D02*
Y1094074D01*
G01X2684539Y1110610D02*
X2687295D01*
G01X2688476D02*
X2691232D01*
G01X2680602D02*
X2683358D01*
G01X2692413D02*
X2695169D01*
G01X2686807Y1453929D02*
Y1434916D01*
G01X2698496Y327559D02*
G03X2699283Y326771I787J-1D01*
G01Y329724D02*
G03X2698496Y328937I0J-787D01*
G01X2706882D02*
G03X2706094Y329724I-788J-1D01*
G01Y326771D02*
G03X2706882Y327559I0J788D01*
G01X2706094Y329724D02*
X2699283D01*
G01X2706094Y326771D02*
X2699283D01*
G01X2698496Y328937D02*
Y327559D01*
G01X2695759Y338582D02*
G03Y334645I1J-1968D01*
G01X2731193D02*
X2695759D01*
G01X2731193Y333793D02*
X2695759D01*
G01X2731193Y332941D02*
X2695759D01*
G01Y334645D02*
Y332941D01*
G01X2706882Y328937D02*
Y327559D01*
G01X2731193Y340287D02*
X2695759D01*
G01Y339435D02*
X2731193D01*
G01Y338582D02*
X2695759D01*
G01Y340287D02*
Y338582D01*
G01X2732374Y362637D02*
X2694578D01*
G01Y362365D02*
X2732374D01*
G01X2694578Y364153D02*
Y355315D01*
G01X2705366Y368346D02*
X2707413D01*
G01X2699067D02*
X2701114D01*
G01X2702216D02*
X2704263D01*
G01X2695917D02*
X2697964D01*
G01X2697728Y366909D02*
X2696153D01*
G01X2704027D02*
X2702452D01*
G01X2700878D02*
X2699303D01*
G01X2707177D02*
X2705602D01*
G01X2705897Y368878D02*
X2705366Y368346D01*
G01X2702748Y368878D02*
X2702216Y368346D01*
G01X2699598Y368878D02*
X2699067Y368346D01*
G01X2696448Y368878D02*
X2695917Y368346D01*
G01X2703732Y368878D02*
X2704263Y368346D01*
G01X2700582Y368878D02*
X2701114Y368346D01*
G01X2697433Y368878D02*
X2697964Y368346D01*
G01X2694283Y368878D02*
X2694815Y368346D01*
G01X2705602Y366909D02*
Y364153D01*
G01X2705445Y397756D02*
Y364153D01*
G01X2705366Y397441D02*
Y368346D01*
G01X2704263D02*
Y397441D01*
G01X2704185Y397756D02*
Y364153D01*
G01X2704027Y366909D02*
Y364153D01*
G01X2702452Y366909D02*
Y364153D01*
G01X2702295Y397756D02*
Y364153D01*
G01X2702216Y397441D02*
Y368346D01*
G01X2701114D02*
Y397441D01*
G01X2701035Y397756D02*
Y364153D01*
G01X2700878Y366909D02*
Y364153D01*
G01X2699303Y366909D02*
Y364153D01*
G01X2699145Y397756D02*
Y364153D01*
G01X2699067Y397441D02*
Y368346D01*
G01X2697964D02*
Y397441D01*
G01X2697885Y397756D02*
Y364153D01*
G01X2697728Y366909D02*
Y364153D01*
G01X2696153Y366909D02*
Y364153D01*
G01X2695996Y397756D02*
Y364153D01*
G01X2695917Y397441D02*
Y368346D01*
G01X2694815D02*
Y397441D01*
G01X2694736Y397756D02*
Y364153D01*
G01X2694578Y366909D02*
Y381346D01*
G01Y366909D02*
Y364153D01*
G01X2708515Y368346D02*
X2710563D01*
G01X2710326Y366909D02*
X2708752D01*
G01X2709047Y368878D02*
X2708515Y368346D01*
G01X2706882Y368878D02*
X2707413Y368346D01*
G01X2708752Y366909D02*
Y364153D01*
G01X2708594Y397756D02*
Y364153D01*
G01X2708515Y397441D02*
Y368346D01*
G01X2707413D02*
Y397441D01*
G01X2707334Y397756D02*
Y364153D01*
G01X2707177Y366909D02*
Y364153D01*
G01X2701864Y369964D02*
X2701466D01*
G01X2698715D02*
X2698316D01*
G01X2705014D02*
X2704615D01*
G01X2695565D02*
X2695167D01*
G01X2697964Y378523D02*
X2697433D01*
G01X2696448D02*
X2695917D01*
G01X2694815D02*
X2694283D01*
G01X2702748D02*
X2702216D01*
G01X2701114D02*
X2700582D01*
G01X2699598D02*
X2699067D01*
G01X2705897D02*
X2705366D01*
G01X2704263D02*
X2703732D01*
G01X2732374Y377696D02*
X2694578D01*
G01Y377302D02*
X2732374D01*
G01X2702952Y376504D02*
X2703528D01*
G01X2706101D02*
X2706678D01*
G01X2699802D02*
X2700378D01*
G01X2696652D02*
X2697229D01*
G01X2695645Y376263D02*
X2695087D01*
G01X2698795D02*
X2698237D01*
G01X2701944D02*
X2701386D01*
G01X2705094D02*
X2704536D01*
G01X2697334Y376160D02*
X2696547D01*
G01X2700484D02*
X2699696D01*
G01X2703633D02*
X2702846D01*
G01X2706783D02*
X2705996D01*
G01X2704566Y376064D02*
X2705063D01*
G01X2698267D02*
X2698764D01*
G01X2701416D02*
X2701914D01*
G01X2695117D02*
X2695615D01*
G01X2695609Y376039D02*
X2695122D01*
G01X2698759D02*
X2698272D01*
G01X2701909D02*
X2701421D01*
G01X2705058D02*
X2704571D01*
G01X2704421Y376006D02*
X2705208D01*
G01X2701271D02*
X2702059D01*
G01X2694972D02*
X2695759D01*
G01X2698122D02*
X2698909D01*
G01X2695759Y375823D02*
X2694972D01*
G01X2698909D02*
X2698122D01*
G01X2702059D02*
X2701271D01*
G01X2705208D02*
X2704421D01*
G01Y375682D02*
X2705208D01*
G01X2701271D02*
X2702059D01*
G01X2694972D02*
X2695759D01*
G01X2698122D02*
X2698909D01*
G01X2695759Y375465D02*
X2694972D01*
G01X2698909D02*
X2698122D01*
G01X2702059D02*
X2701271D01*
G01X2705208D02*
X2704421D01*
G01X2704582Y375165D02*
X2705047D01*
G01X2698283D02*
X2698748D01*
G01X2701432D02*
X2701898D01*
G01X2695133D02*
X2695598D01*
G01X2702846Y375135D02*
X2703633D01*
G01X2705996D02*
X2706783D01*
G01X2699696D02*
X2700484D01*
G01X2696547D02*
X2697334D01*
G01X2732374Y374744D02*
X2694578D01*
G01X2697220Y374710D02*
X2696661D01*
G01X2700369D02*
X2699811D01*
G01X2703519D02*
X2702961D01*
G01X2706669D02*
X2706110D01*
G01X2694578Y374351D02*
X2732374D01*
G01X2705366Y372618D02*
X2705897D01*
G01X2703732D02*
X2704263D01*
G01X2702216D02*
X2702748D01*
G01X2700582D02*
X2701114D01*
G01X2699067D02*
X2699598D01*
G01X2697433D02*
X2697964D01*
G01X2695917D02*
X2696448D01*
G01X2694283D02*
X2694815D01*
G01X2694578Y372497D02*
X2732374D01*
G01Y372051D02*
X2694578D01*
G01X2702846Y371785D02*
X2703633D01*
G01X2705996D02*
X2706783D01*
G01X2699696D02*
X2700484D01*
G01X2696547D02*
X2697334D01*
G01X2732374Y371612D02*
X2694578D01*
G01Y371559D02*
X2732374D01*
G01X2695759Y371314D02*
X2694972D01*
G01X2698909D02*
X2698122D01*
G01X2702059D02*
X2701271D01*
G01X2705208D02*
X2704421D01*
G01X2732374Y371243D02*
X2694578D01*
G01Y370970D02*
X2732374D01*
G01X2697334Y370502D02*
X2696547D01*
G01X2700484D02*
X2699696D01*
G01X2703633D02*
X2702846D01*
G01X2706783D02*
X2705996D01*
G01X2704478Y370476D02*
X2705151D01*
G01X2698179D02*
X2698852D01*
G01X2701329D02*
X2702002D01*
G01X2695030D02*
X2695702D01*
G01X2702846Y370252D02*
X2703633D01*
G01X2705996D02*
X2706783D01*
G01X2699696D02*
X2700484D01*
G01X2696547D02*
X2697334D01*
G01X2704549Y370212D02*
X2705080D01*
G01X2698250D02*
X2698781D01*
G01X2701399D02*
X2701931D01*
G01X2695100D02*
X2695632D01*
G01X2695630Y370207D02*
X2695102D01*
G01X2698780D02*
X2698251D01*
G01X2701930D02*
X2701401D01*
G01X2705079D02*
X2704550D01*
G01X2697334Y370198D02*
X2696547D01*
G01X2700484D02*
X2699696D01*
G01X2703633D02*
X2702846D01*
G01X2706783D02*
X2705996D01*
G01X2697334Y370171D02*
X2696547D01*
G01X2700484D02*
X2699696D01*
G01X2703633D02*
X2702846D01*
G01X2706783D02*
X2705996D01*
G01X2704618Y369955D02*
X2705011D01*
G01X2698317D02*
X2698712D01*
G01X2701467D02*
X2701862D01*
G01X2695169D02*
X2695563D01*
G01X2705897Y368878D02*
X2706882D01*
G01X2702748D02*
X2703732D01*
G01X2699598D02*
X2700582D01*
G01X2696448D02*
X2697433D01*
G01X2697334Y370324D02*
X2696547Y370323D01*
G01X2700484Y370324D02*
X2699696Y370323D01*
G01X2703633Y370324D02*
X2702846Y370323D01*
G01X2706783Y370324D02*
X2705996Y370323D01*
G01X2705011Y369955D02*
X2705208Y370689D01*
G01X2701862Y369955D02*
X2702059Y370689D01*
G01X2698712Y369955D02*
X2698909Y370689D01*
G01X2695563Y369955D02*
X2695759Y370689D01*
G01X2705063Y376064D02*
X2705058Y376039D01*
G01X2701914Y376064D02*
X2701909Y376039D01*
G01X2706678Y376504D02*
X2706783Y377021D01*
G01X2703528Y376504D02*
X2703633Y377021D01*
G01X2700378Y376504D02*
X2700484Y377021D01*
G01X2706110Y374710D02*
X2705996Y374117D01*
G01X2702961Y374710D02*
X2702846Y374117D01*
G01X2705047Y375165D02*
X2705208Y374267D01*
G01X2701898Y375165D02*
X2702059Y374267D01*
G01X2698748Y375165D02*
X2698909Y374267D01*
G01X2695598Y375165D02*
X2695759Y374267D01*
G01X2706783Y374117D02*
X2706669Y374710D01*
G01X2703633Y374117D02*
X2703519Y374710D01*
G01X2700484Y374117D02*
X2700369Y374710D01*
G01X2697334Y374117D02*
X2697220Y374710D01*
G01X2706101Y376504D02*
X2705996Y377021D01*
G01X2702952Y376504D02*
X2702846Y377021D01*
G01X2699802Y376504D02*
X2699696Y377021D01*
G01X2696652Y376504D02*
X2696547Y377021D01*
G01X2704571Y376039D02*
X2704566Y376064D01*
G01X2701421Y376039D02*
X2701416Y376064D01*
G01X2698272Y376039D02*
X2698267Y376064D01*
G01X2695122Y376039D02*
X2695117Y376064D01*
G01X2704618Y369955D02*
X2704421Y370689D01*
G01X2701468Y369955D02*
X2701271Y370689D01*
G01X2698319Y369955D02*
X2698122Y370689D01*
G01X2698764Y376064D02*
X2698759Y376039D01*
G01X2695615Y376064D02*
X2695609Y376039D01*
G01X2697229Y376504D02*
X2697334Y377021D01*
G01X2694079Y376504D02*
X2694185Y377021D01*
G01X2699811Y374710D02*
X2699696Y374117D01*
G01X2696661Y374710D02*
X2696547Y374117D01*
G01X2704421Y374267D02*
X2704582Y375165D01*
G01X2701271Y374267D02*
X2701432Y375165D01*
G01X2698122Y374267D02*
X2698283Y375165D01*
G01X2694972Y374267D02*
X2695133Y375165D01*
G01X2705208Y377419D02*
X2705094Y376263D01*
G01X2702059Y377419D02*
X2701944Y376263D01*
G01X2698909Y377419D02*
X2698795Y376263D01*
G01X2695759Y377419D02*
X2695645Y376263D01*
G01X2705996Y370171D02*
Y398326D01*
G01X2705897Y372618D02*
Y368878D01*
G01Y396909D02*
Y378523D01*
G01X2705208Y370689D02*
Y407972D01*
G01X2704421Y370689D02*
Y407972D01*
G01X2703732Y378523D02*
Y396909D01*
G01Y368878D02*
Y372618D01*
G01X2703633Y398326D02*
Y370171D01*
G01X2702846D02*
Y398326D01*
G01X2702748Y372618D02*
Y368878D01*
G01Y396909D02*
Y378523D01*
G01X2702059Y370689D02*
Y407972D01*
G01X2701271Y370689D02*
Y407972D01*
G01X2700582Y378523D02*
Y396909D01*
G01Y368878D02*
Y372618D01*
G01X2700484Y370171D02*
Y398326D01*
G01X2699696Y370171D02*
Y398326D01*
G01X2699598Y372618D02*
Y368878D01*
G01Y396909D02*
Y378523D01*
G01X2698909Y370689D02*
Y407972D01*
G01X2698122Y370689D02*
Y407972D01*
G01X2697433Y378523D02*
Y396909D01*
G01Y368878D02*
Y372618D01*
G01X2697334Y398326D02*
Y370171D01*
G01X2696547D02*
Y398326D01*
G01X2696448Y372618D02*
Y368878D01*
G01Y396909D02*
Y378523D01*
G01X2695759Y370689D02*
Y407972D01*
G01X2694972Y370689D02*
Y407972D01*
G01X2694283Y378523D02*
Y396909D01*
G01Y368878D02*
Y372618D01*
G01X2694185Y398326D02*
Y370171D01*
G01X2704536Y376263D02*
X2704421Y377419D01*
G01X2701386Y376263D02*
X2701271Y377419D01*
G01X2698237Y376263D02*
X2698122Y377419D01*
G01X2695087Y376263D02*
X2694972Y377419D01*
G01X2694185Y374117D02*
X2694070Y374710D01*
G01X2695169Y369955D02*
X2694972Y370689D01*
G01X2732374Y381346D02*
X2694578D01*
G01X2732374Y380574D02*
X2694578D01*
G01Y380521D02*
X2732374D01*
G01X2694578Y380082D02*
X2732374D01*
G01Y379635D02*
X2694578D01*
G01X2708163Y369964D02*
X2707765D01*
G01X2707413Y378523D02*
X2706882D01*
G01X2709047D02*
X2708515D01*
G01X2709251Y376504D02*
X2709827D01*
G01X2708243Y376263D02*
X2707685D01*
G01X2709933Y376160D02*
X2709145D01*
G01X2707715Y376064D02*
X2708213D01*
G01X2708208Y376039D02*
X2707720D01*
G01X2707570Y376006D02*
X2708358D01*
G01Y375823D02*
X2707570D01*
G01Y375682D02*
X2708358D01*
G01Y375465D02*
X2707570D01*
G01X2707732Y375165D02*
X2708197D01*
G01X2709145Y375135D02*
X2709933D01*
G01X2709818Y374710D02*
X2709260D01*
G01X2708515Y372618D02*
X2709047D01*
G01X2706882D02*
X2707413D01*
G01X2709145Y371785D02*
X2709933D01*
G01X2708358Y371314D02*
X2707570D01*
G01X2709933Y370502D02*
X2709145D01*
G01X2707628Y370476D02*
X2708301D01*
G01X2709145Y370252D02*
X2709933D01*
G01X2707698Y370212D02*
X2708230D01*
G01X2708229Y370207D02*
X2707700D01*
G01X2709933Y370198D02*
X2709145D01*
G01X2709933Y370171D02*
X2709145D01*
G01X2707767Y369955D02*
X2708161D01*
G01X2709047Y368878D02*
X2710031D01*
G01X2709933Y370324D02*
X2709145Y370323D01*
G01X2708161Y369955D02*
X2708358Y370689D01*
G01X2708213Y376064D02*
X2708208Y376039D01*
G01X2709827Y376504D02*
X2709933Y377021D01*
G01X2709260Y374710D02*
X2709145Y374117D01*
G01X2707570Y374267D02*
X2707732Y375165D01*
G01X2708197D02*
X2708358Y374267D01*
G01X2709933Y374117D02*
X2709818Y374710D01*
G01X2709251Y376504D02*
X2709145Y377021D01*
G01X2707720Y376039D02*
X2707715Y376064D01*
G01X2707767Y369955D02*
X2707570Y370689D01*
G01X2708358Y377419D02*
X2708243Y376263D01*
G01X2709933Y370171D02*
Y398326D01*
G01X2709145Y370171D02*
Y398326D01*
G01X2709047Y372618D02*
Y368878D01*
G01Y396909D02*
Y378523D01*
G01X2708358Y370689D02*
Y407972D01*
G01X2707570Y370689D02*
Y407972D01*
G01X2706882Y378523D02*
Y396909D01*
G01Y368878D02*
Y372618D01*
G01X2706783Y398326D02*
Y370171D01*
G01X2707685Y376263D02*
X2707570Y377419D01*
G01X2705366Y394074D02*
X2705897Y394294D01*
G01X2702216Y394074D02*
X2702748Y394294D01*
G01X2699067Y394074D02*
X2699598Y394294D01*
G01X2695917Y394074D02*
X2696448Y394294D01*
G01X2697334Y394901D02*
X2696547D01*
G01X2700484D02*
X2699696D01*
G01X2703633D02*
X2702846D01*
G01X2706783D02*
X2705996D01*
G01X2697334Y394665D02*
X2696547D01*
G01X2700484D02*
X2699696D01*
G01X2703633D02*
X2702846D01*
G01X2706783D02*
X2705996D01*
G01X2704421Y394626D02*
X2705208D01*
G01X2701271D02*
X2702059D01*
G01X2694972D02*
X2695759D01*
G01X2698122D02*
X2698909D01*
G01X2704421Y394586D02*
X2705208D01*
G01X2701271D02*
X2702059D01*
G01X2694972D02*
X2695759D01*
G01X2698122D02*
X2698909D01*
G01X2697334Y394488D02*
X2696547D01*
G01X2700484D02*
X2699696D01*
G01X2703633D02*
X2702846D01*
G01X2706783D02*
X2705996D01*
G01X2695759Y394347D02*
X2694972D01*
G01X2698909D02*
X2698122D01*
G01X2702059D02*
X2701271D01*
G01X2705208D02*
X2704421D01*
G01X2702846Y394311D02*
X2703633D01*
G01X2705996D02*
X2706783D01*
G01X2699696D02*
X2700484D01*
G01X2696547D02*
X2697334D01*
G01Y394074D02*
X2696547D01*
G01X2695917D02*
X2694815D01*
G01X2699067D02*
X2697964D01*
G01X2700484D02*
X2699696D01*
G01X2702216D02*
X2701114D01*
G01X2703633D02*
X2702846D01*
G01X2706783D02*
X2705996D01*
G01X2705366D02*
X2704263D01*
G01X2702748Y394055D02*
X2703732D01*
G01X2705897D02*
X2706882D01*
G01X2699598D02*
X2700582D01*
G01X2696448D02*
X2697433D01*
G01X2702846Y393996D02*
X2703633D01*
G01X2705996D02*
X2706783D01*
G01X2699696D02*
X2700484D01*
G01X2696547D02*
X2697334D01*
G01X2697433Y393740D02*
X2696448D01*
G01X2700582D02*
X2699598D01*
G01X2703732D02*
X2702748D01*
G01X2706882D02*
X2705897D01*
G01X2702846Y393702D02*
X2703633D01*
G01X2705996D02*
X2706783D01*
G01X2699696D02*
X2700484D01*
G01X2696547D02*
X2697334D01*
G01Y393681D02*
X2696547D01*
G01X2700484D02*
X2699696D01*
G01X2703633D02*
X2702846D01*
G01X2706783D02*
X2705996D01*
G01X2697325Y393641D02*
X2696556D01*
G01X2700475D02*
X2699706D01*
G01X2703624D02*
X2702855D01*
G01X2706774D02*
X2706005D01*
G01X2697334Y393629D02*
X2696547D01*
G01X2700484D02*
X2699696D01*
G01X2703633D02*
X2702846D01*
G01X2706783D02*
X2705996D01*
G01X2702846Y393594D02*
X2703633D01*
G01X2705996D02*
X2706783D01*
G01X2699696D02*
X2700484D01*
G01X2696547D02*
X2697334D01*
G01X2702958Y393539D02*
X2703522D01*
G01X2706107D02*
X2706672D01*
G01X2699808D02*
X2700372D01*
G01X2696659D02*
X2697223D01*
G01X2704421Y393526D02*
X2705208D01*
G01X2701271D02*
X2702059D01*
G01X2694972D02*
X2695759D01*
G01X2698122D02*
X2698909D01*
G01X2702846Y393514D02*
X2703633D01*
G01X2705996D02*
X2706783D01*
G01X2699696D02*
X2700484D01*
G01X2696547D02*
X2697334D01*
G01X2695759Y393408D02*
X2694972D01*
G01X2698909D02*
X2698122D01*
G01X2702059D02*
X2701271D01*
G01X2705208D02*
X2704421D01*
G01X2695917Y393287D02*
X2694815D01*
G01X2699067D02*
X2697964D01*
G01X2702216D02*
X2701114D01*
G01X2705366D02*
X2704263D01*
G01X2697137Y393283D02*
X2696744D01*
G01X2700287D02*
X2699893D01*
G01X2703437D02*
X2703043D01*
G01X2706586D02*
X2706193D01*
G01X2703732Y392500D02*
X2705897D01*
G01X2700582D02*
X2702748D01*
G01X2697433D02*
X2699598D01*
G01X2694283D02*
X2696448D01*
G01X2704421Y392254D02*
X2705208D01*
G01X2701271D02*
X2702059D01*
G01X2694972D02*
X2695759D01*
G01X2698122D02*
X2698909D01*
G01X2704421Y392231D02*
X2705208D01*
G01X2701271D02*
X2702059D01*
G01X2694972D02*
X2695759D01*
G01X2698122D02*
X2698909D01*
G01X2695759Y391977D02*
X2694972D01*
G01X2698909D02*
X2698122D01*
G01X2702059D02*
X2701271D01*
G01X2705208D02*
X2704421D01*
G01X2695759Y391318D02*
X2694972D01*
G01X2698909D02*
X2698122D01*
G01X2702059D02*
X2701271D01*
G01X2705208D02*
X2704421D01*
G01X2703043Y391126D02*
X2703437D01*
G01X2706193D02*
X2706586D01*
G01X2699893D02*
X2700287D01*
G01X2696744D02*
X2697137D01*
G01X2697223Y390870D02*
X2696659D01*
G01X2700372D02*
X2699808D01*
G01X2703522D02*
X2702958D01*
G01X2706672D02*
X2706107D01*
G01X2702855Y390768D02*
X2703624D01*
G01X2706005D02*
X2706774D01*
G01X2699706D02*
X2700475D01*
G01X2696556D02*
X2697325D01*
G01X2695759Y390728D02*
X2694972D01*
G01X2698909D02*
X2698122D01*
G01X2697433D02*
X2696448D01*
G01X2702059D02*
X2701271D01*
G01X2700582D02*
X2699598D01*
G01X2703732D02*
X2702748D01*
G01X2705208D02*
X2704421D01*
G01X2706882D02*
X2705897D01*
G01X2697334Y390515D02*
X2696547D01*
G01X2700484D02*
X2699696D01*
G01X2703633D02*
X2702846D01*
G01X2706783D02*
X2705996D01*
G01X2702748Y390413D02*
X2703732D01*
G01X2705897D02*
X2706882D01*
G01X2699598D02*
X2700582D01*
G01X2696448D02*
X2697433D01*
G01X2695759Y390137D02*
X2694972D01*
G01X2698909D02*
X2698122D01*
G01X2702059D02*
X2701271D01*
G01X2705208D02*
X2704421D01*
G01X2702748Y390098D02*
X2703732D01*
G01X2705897D02*
X2706882D01*
G01X2699598D02*
X2700582D01*
G01X2696448D02*
X2697433D01*
G01X2702846Y390082D02*
X2703633D01*
G01X2705996D02*
X2706783D01*
G01X2699696D02*
X2700484D01*
G01X2696547D02*
X2697334D01*
G01X2702846Y389858D02*
X2703633D01*
G01X2705996D02*
X2706783D01*
G01X2699696D02*
X2700484D01*
G01X2696547D02*
X2697334D01*
G01X2704421Y389547D02*
X2705208D01*
G01X2701271D02*
X2702059D01*
G01X2694972D02*
X2695759D01*
G01X2698122D02*
X2698909D01*
G01X2697334Y389425D02*
X2696547D01*
G01X2700484D02*
X2699696D01*
G01X2703633D02*
X2702846D01*
G01X2706783D02*
X2705996D01*
G01X2695759Y388956D02*
X2694972D01*
G01X2698909D02*
X2698122D01*
G01X2702059D02*
X2701271D01*
G01X2705208D02*
X2704421D01*
G01X2706005Y390768D02*
X2706107Y390870D01*
G01X2706672Y393539D02*
X2706774Y393641D01*
G01X2702855Y390768D02*
X2702958Y390870D01*
G01X2705366Y393287D02*
X2705897Y393818D01*
G01D02*
X2705366Y393287D01*
G01X2703522Y393539D02*
X2703624Y393641D01*
G01X2699706Y390768D02*
X2699808Y390870D01*
G01X2702216Y393287D02*
X2702748Y393818D01*
G01D02*
X2702216Y393287D01*
G01X2700372Y393539D02*
X2700475Y393641D01*
G01X2696556Y390768D02*
X2696659Y390870D01*
G01X2699067Y393287D02*
X2699598Y393818D01*
G01D02*
X2699067Y393287D01*
G01X2697223Y393539D02*
X2697325Y393641D01*
G01X2695917Y393287D02*
X2696448Y393818D01*
G01D02*
X2695917Y393287D01*
G01X2694073Y393539D02*
X2694176Y393641D01*
G01X2703732Y394294D02*
X2704263Y394074D01*
G01X2700582Y394294D02*
X2701114Y394074D01*
G01X2697433Y394294D02*
X2697964Y394074D01*
G01X2694283Y394294D02*
X2694815Y394074D01*
G01X2706107Y393539D02*
X2706005Y393641D01*
G01X2703732Y393818D02*
X2704263Y393287D01*
G01D02*
X2703732Y393818D01*
G01X2706672Y390870D02*
X2706774Y390768D01*
G01X2702958Y393539D02*
X2702855Y393641D01*
G01X2700582Y393818D02*
X2701114Y393287D01*
G01D02*
X2700582Y393818D01*
G01X2703522Y390870D02*
X2703624Y390768D01*
G01X2699808Y393539D02*
X2699706Y393641D01*
G01X2697433Y393818D02*
X2697964Y393287D01*
G01D02*
X2697433Y393818D01*
G01X2700372Y390870D02*
X2700475Y390768D01*
G01X2696659Y393539D02*
X2696556Y393641D01*
G01X2694283Y393818D02*
X2694815Y393287D01*
G01D02*
X2694283Y393818D01*
G01X2697223Y390870D02*
X2697325Y390768D01*
G01X2694073Y390870D02*
X2694176Y390768D01*
G01X2706586Y393283D02*
Y391126D01*
G01X2706193D02*
Y393283D01*
G01X2705307Y397618D02*
Y388248D01*
G01X2704322Y397618D02*
Y388248D01*
G01X2703437Y393283D02*
Y391126D01*
G01X2703043D02*
Y393283D01*
G01X2702157Y397618D02*
Y388248D01*
G01X2701173Y397618D02*
Y388248D01*
G01X2700287Y393283D02*
Y391126D01*
G01X2699893D02*
Y393283D01*
G01X2699007Y397618D02*
Y388248D01*
G01X2698023Y397618D02*
Y388248D01*
G01X2697137Y393283D02*
Y391126D01*
G01X2696744D02*
Y393283D01*
G01X2695858Y397618D02*
Y388248D01*
G01X2694874Y397618D02*
Y388248D01*
G01X2693988Y393283D02*
Y391126D01*
G01X2695759Y398602D02*
X2694972D01*
G01X2698909D02*
X2698122D01*
G01X2702059D02*
X2701271D01*
G01X2705208D02*
X2704421D01*
G01X2697334Y398326D02*
X2696547D01*
G01X2700484D02*
X2699696D01*
G01X2703633D02*
X2702846D01*
G01X2706783D02*
X2705996D01*
G01X2697334Y397736D02*
X2696547D01*
G01X2700484D02*
X2699696D01*
G01X2703633D02*
X2702846D01*
G01X2706783D02*
X2705996D01*
G01X2695858Y397618D02*
X2694874D01*
G01X2699007D02*
X2698023D01*
G01X2702157D02*
X2701173D01*
G01X2705307D02*
X2704322D01*
G01X2697964Y397441D02*
X2695917D01*
G01X2701114D02*
X2699067D01*
G01X2704263D02*
X2702216D01*
G01X2707413D02*
X2705366D01*
G01X2695759Y397421D02*
X2694972D01*
G01X2698909D02*
X2698122D01*
G01X2702059D02*
X2701271D01*
G01X2705208D02*
X2704421D01*
G01X2697433Y396909D02*
X2696448D01*
G01X2700582D02*
X2699598D01*
G01X2703732D02*
X2702748D01*
G01X2706882D02*
X2705897D01*
G01X2697334Y396830D02*
X2696547D01*
G01X2700484D02*
X2699696D01*
G01X2703633D02*
X2702846D01*
G01X2706783D02*
X2705996D01*
G01X2704421Y396633D02*
X2705208D01*
G01X2701271D02*
X2702059D01*
G01X2694972D02*
X2695759D01*
G01X2698122D02*
X2698909D01*
G01X2702846Y396594D02*
X2703633D01*
G01X2705996D02*
X2706783D01*
G01X2699696D02*
X2700484D01*
G01X2696547D02*
X2697334D01*
G01X2695759Y396515D02*
X2694972D01*
G01X2698909D02*
X2698122D01*
G01X2702059D02*
X2701271D01*
G01X2705208D02*
X2704421D01*
G01X2697334Y396417D02*
X2696547D01*
G01X2700484D02*
X2699696D01*
G01X2703633D02*
X2702846D01*
G01X2706783D02*
X2705996D01*
G01X2699303Y396043D02*
X2697728D01*
G01X2696153D02*
X2694578D01*
G01X2697334D02*
X2696547D01*
G01X2702452D02*
X2700878D01*
G01X2700484D02*
X2699696D01*
G01X2705602D02*
X2704027D01*
G01X2703633D02*
X2702846D01*
G01X2706783D02*
X2705996D01*
G01X2697334Y396004D02*
X2696547D01*
G01X2700484D02*
X2699696D01*
G01X2703633D02*
X2702846D01*
G01X2706783D02*
X2705996D01*
G01X2705700Y398011D02*
X2705307Y397618D01*
G01X2703732Y396909D02*
X2704263Y397441D01*
G01X2702551Y398011D02*
X2702157Y397618D01*
G01X2700582Y396909D02*
X2701114Y397441D01*
G01X2699401Y398011D02*
X2699007Y397618D01*
G01X2697433Y396909D02*
X2697964Y397441D01*
G01X2696252Y398011D02*
X2695858Y397618D01*
G01X2694283Y396909D02*
X2694815Y397441D01*
G01X2705366D02*
X2705897Y396909D01*
G01X2703929Y398011D02*
X2704322Y397618D01*
G01X2702216Y397441D02*
X2702748Y396909D01*
G01X2700779Y398011D02*
X2701173Y397618D01*
G01X2699067Y397441D02*
X2699598Y396909D01*
G01X2697630Y398011D02*
X2698023Y397618D01*
G01X2695917Y397441D02*
X2696448Y396909D01*
G01X2694480Y398011D02*
X2694874Y397618D01*
G01X2705602Y398011D02*
Y396043D01*
G01X2704027Y398011D02*
Y396043D01*
G01X2702452Y398011D02*
Y396043D01*
G01X2700878Y398011D02*
Y396043D01*
G01X2699303Y398011D02*
Y396043D01*
G01X2697728Y398011D02*
Y396043D01*
G01X2696153Y398011D02*
Y396043D01*
G01X2694578Y398011D02*
Y396043D01*
G01X2708515Y394074D02*
X2709047Y394294D01*
G01X2709933Y394901D02*
X2709145D01*
G01X2709933Y394665D02*
X2709145D01*
G01X2707570Y394626D02*
X2708358D01*
G01X2707570Y394586D02*
X2708358D01*
G01X2709933Y394488D02*
X2709145D01*
G01X2708358Y394347D02*
X2707570D01*
G01X2709145Y394311D02*
X2709933D01*
G01X2708515Y394074D02*
X2707413D01*
G01X2709933D02*
X2709145D01*
G01X2709047Y394055D02*
X2710031D01*
G01X2709145Y393996D02*
X2709933D01*
G01X2710031Y393740D02*
X2709047D01*
G01X2709145Y393702D02*
X2709933D01*
G01Y393681D02*
X2709145D01*
G01X2709924Y393641D02*
X2709154D01*
G01X2709933Y393629D02*
X2709145D01*
G01Y393594D02*
X2709933D01*
G01X2709257Y393539D02*
X2709821D01*
G01X2707570Y393526D02*
X2708358D01*
G01X2709145Y393514D02*
X2709933D01*
G01X2708358Y393408D02*
X2707570D01*
G01X2708515Y393287D02*
X2707413D01*
G01X2709736Y393283D02*
X2709342D01*
G01X2706882Y392500D02*
X2709047D01*
G01X2707570Y392254D02*
X2708358D01*
G01X2707570Y392231D02*
X2708358D01*
G01Y391977D02*
X2707570D01*
G01X2708358Y391318D02*
X2707570D01*
G01X2709342Y391126D02*
X2709736D01*
G01X2709821Y390870D02*
X2709257D01*
G01X2709154Y390768D02*
X2709924D01*
G01X2708358Y390728D02*
X2707570D01*
G01X2710031D02*
X2709047D01*
G01X2709933Y390515D02*
X2709145D01*
G01X2709047Y390413D02*
X2710031D01*
G01X2708358Y390137D02*
X2707570D01*
G01X2709047Y390098D02*
X2710031D01*
G01X2709145Y390082D02*
X2709933D01*
G01X2709145Y389858D02*
X2709933D01*
G01X2707570Y389547D02*
X2708358D01*
G01X2709933Y389425D02*
X2709145D01*
G01X2708358Y388956D02*
X2707570D01*
G01X2709154Y390768D02*
X2709257Y390870D01*
G01X2709821Y393539D02*
X2709924Y393641D01*
G01X2708515Y393287D02*
X2709047Y393818D01*
G01D02*
X2708515Y393287D01*
G01X2706882Y394294D02*
X2707413Y394074D01*
G01X2709257Y393539D02*
X2709154Y393641D01*
G01X2706882Y393818D02*
X2707413Y393287D01*
G01D02*
X2706882Y393818D01*
G01X2709821Y390870D02*
X2709924Y390768D01*
G01X2709736Y393283D02*
Y391126D01*
G01X2709342D02*
Y393283D01*
G01X2708456Y397618D02*
Y388248D01*
G01X2707472Y397618D02*
Y388248D01*
G01X2708358Y398602D02*
X2707570D01*
G01X2709933Y398326D02*
X2709145D01*
G01X2709933Y397736D02*
X2709145D01*
G01X2708456Y397618D02*
X2707472D01*
G01X2710563Y397441D02*
X2708515D01*
G01X2708358Y397421D02*
X2707570D01*
G01X2710031Y396909D02*
X2709047D01*
G01X2709933Y396830D02*
X2709145D01*
G01X2707570Y396633D02*
X2708358D01*
G01X2709145Y396594D02*
X2709933D01*
G01X2708358Y396515D02*
X2707570D01*
G01X2709933Y396417D02*
X2709145D01*
G01X2708752Y396043D02*
X2707177D01*
G01X2709933D02*
X2709145D01*
G01X2709933Y396004D02*
X2709145D01*
G01X2708850Y398011D02*
X2708456Y397618D01*
G01X2706882Y396909D02*
X2707413Y397441D01*
G01X2708515D02*
X2709047Y396909D01*
G01X2707078Y398011D02*
X2707472Y397618D01*
G01X2708752Y398011D02*
Y396043D01*
G01X2707177Y398011D02*
Y396043D01*
G01X2695759Y407972D02*
X2694972D01*
G01X2698909D02*
X2698122D01*
G01X2702059D02*
X2701271D01*
G01X2705208D02*
X2704421D01*
G01X2695759Y407381D02*
X2694972D01*
G01X2698909D02*
X2698122D01*
G01X2702059D02*
X2701271D01*
G01X2705208D02*
X2704421D01*
G01Y406476D02*
X2705208D01*
G01X2701271D02*
X2702059D01*
G01X2694972D02*
X2695759D01*
G01X2698122D02*
X2698909D01*
G01X2705917Y405885D02*
X2706862D01*
G01X2702767D02*
X2703712D01*
G01X2699618D02*
X2700563D01*
G01X2696468D02*
X2697413D01*
G01X2695759D02*
X2694972D01*
G01X2698909D02*
X2698122D01*
G01X2702059D02*
X2701271D01*
G01X2705208D02*
X2704421D01*
G01X2695759Y405177D02*
X2694972D01*
G01X2698909D02*
X2698122D01*
G01X2702059D02*
X2701271D01*
G01X2705208D02*
X2704421D01*
G01X2695759Y404232D02*
X2694972D01*
G01X2698909D02*
X2698122D01*
G01X2702059D02*
X2701271D01*
G01X2705208D02*
X2704421D01*
G01X2704303Y403641D02*
X2705326D01*
G01X2701153D02*
X2702177D01*
G01X2698004D02*
X2699027D01*
G01X2694854D02*
X2695878D01*
G01X2704421Y403051D02*
X2705208D01*
G01X2701271D02*
X2702059D01*
G01X2694972D02*
X2695759D01*
G01X2698122D02*
X2698909D01*
G01X2705917Y405885D02*
X2705326Y405295D01*
G01X2702767Y405885D02*
X2702177Y405295D01*
G01X2699618Y405885D02*
X2699027Y405295D01*
G01X2696468Y405885D02*
X2695878Y405295D01*
G01X2703712Y405885D02*
X2704303Y405295D01*
G01X2700563Y405885D02*
X2701153Y405295D01*
G01X2697413Y405885D02*
X2698004Y405295D01*
G01X2694263Y405885D02*
X2694854Y405295D01*
G01X2705326Y403641D02*
Y405295D01*
G01X2704303D02*
Y403641D01*
G01X2702177D02*
Y405295D01*
G01X2701153D02*
Y403641D01*
G01X2699027D02*
Y405295D01*
G01X2698004D02*
Y403641D01*
G01X2695878D02*
Y405295D01*
G01X2694854D02*
Y403641D01*
G01X2708358Y407972D02*
X2707570D01*
G01X2708358Y407381D02*
X2707570D01*
G01Y406476D02*
X2708358D01*
G01X2709067Y405885D02*
X2710011D01*
G01X2708358D02*
X2707570D01*
G01X2708358Y405177D02*
X2707570D01*
G01X2708358Y404232D02*
X2707570D01*
G01X2707452Y403641D02*
X2708476D01*
G01X2707570Y403051D02*
X2708358D01*
G01X2709067Y405885D02*
X2708476Y405295D01*
G01X2710011Y405885D02*
X2710602Y405295D01*
G01X2706862Y405885D02*
X2707452Y405295D01*
G01X2708476Y403641D02*
Y405295D01*
G01X2707452D02*
Y403641D01*
G01X2701122Y838409D02*
Y811409D01*
G01X2706862Y821909D02*
G03I-2244J0D01*
G01X2704374Y817353D02*
X2704169Y817311D01*
G01X2705368Y822659D02*
X2703868D01*
G01Y821159D02*
X2705368D01*
G01X2703368Y820659D02*
X2705868D01*
G01X2705276Y818400D02*
X2705522D01*
G01X2703185D02*
X2704169D01*
G01X2704210Y818191D02*
X2703431D01*
G01Y817563D02*
X2704210D01*
G01X2704169Y817311D02*
X2703431D01*
G01X2705522Y816432D02*
X2705276D01*
G01X2703431D02*
X2703185D01*
G01X2701122Y815409D02*
X2798114D01*
G01X2704169Y818400D02*
X2704374Y818358D01*
G01X2704333Y818149D02*
X2704210Y818191D01*
G01X2704374Y818358D02*
X2704538Y818233D01*
G01X2704415Y818065D02*
X2704333Y818149D01*
G01X2703868Y822659D02*
X2703368Y823159D01*
G01X2705368Y821159D02*
X2705868Y820659D01*
G01X2704538Y818233D02*
X2704661Y818065D01*
G01D02*
X2704702Y817940D01*
G01X2704456D02*
X2704415Y818065D01*
G01X2704210Y817563D02*
X2704333Y817605D01*
G01X2705868Y820659D02*
Y823159D01*
G01X2705522Y818400D02*
Y816432D01*
G01X2705368Y821159D02*
Y822659D01*
G01X2705276Y816432D02*
Y818065D01*
G01X2705030Y817772D02*
Y818107D01*
G01X2704702Y817940D02*
Y817772D01*
G01X2704456Y817814D02*
Y817940D01*
G01X2703868Y822659D02*
Y821159D01*
G01X2703431Y817311D02*
Y816432D01*
G01Y818191D02*
Y817563D01*
G01X2703368Y823159D02*
Y820659D01*
G01X2703185Y816432D02*
Y818400D01*
G01X2696622Y838409D02*
Y815409D01*
G01X2704538Y817479D02*
X2704374Y817353D01*
G01X2705368Y822659D02*
X2705868Y823159D01*
G01X2703868Y821159D02*
X2703368Y820659D01*
G01X2704333Y817605D02*
X2704415Y817688D01*
G01X2705276Y818065D02*
X2705030Y817772D01*
G01Y818107D02*
X2705276Y818400D01*
G01X2704661Y817646D02*
X2704538Y817479D01*
G01X2704702Y817772D02*
X2704661Y817646D01*
G01X2704415Y817688D02*
X2704456Y817814D01*
G01X2798114Y825409D02*
X2701122D01*
G01X2705868Y823159D02*
X2703368D01*
G01X2708118Y815409D02*
Y838409D01*
G01X2706862Y831909D02*
G03I-2244J0D01*
G01X2705868Y833159D02*
X2703368D01*
G01X2705368Y832659D02*
X2703868D01*
G01Y831159D02*
X2705368D01*
G01X2703368Y830659D02*
X2705868D01*
G01X2798114Y828409D02*
X2701122D01*
G01X2703868Y832659D02*
X2703368Y833159D01*
G01X2705368Y831159D02*
X2705868Y830659D01*
G01D02*
Y833159D01*
G01X2705368Y831159D02*
Y832659D01*
G01X2703868D02*
Y831159D01*
G01X2703368Y833159D02*
Y830659D01*
G01X2705368Y832659D02*
X2705868Y833159D01*
G01X2703868Y831159D02*
X2703368Y830659D01*
G01X2699106Y1094074D02*
X2696350D01*
G01X2703043D02*
X2700287D01*
G01X2706980D02*
X2704224D01*
G01D02*
Y1110610D01*
G01X2703043D02*
Y1094074D01*
G01X2700287D02*
Y1110610D01*
G01X2699106D02*
Y1094074D01*
G01X2696350D02*
Y1110610D01*
G01X2695169D02*
Y1094074D01*
G01X2710917D02*
X2708161D01*
G01D02*
Y1110610D01*
G01X2706980D02*
Y1094074D01*
G01X2704224Y1110610D02*
X2706980D01*
G01X2700287D02*
X2703043D01*
G01X2696350D02*
X2699106D01*
G01X2708161D02*
X2710917D01*
G01X2710354Y1118862D02*
X2709854Y1118759D01*
G01X2709954Y1122950D02*
X2708053D01*
G01Y1121519D02*
X2709954D01*
G01X2708053Y1120906D02*
X2709954D01*
G01Y1119373D02*
X2708053D01*
G01X2709854Y1118759D02*
X2707452D01*
G01X2710254Y1122847D02*
X2709954Y1122950D01*
G01Y1120906D02*
X2710254Y1120804D01*
G01X2708053Y1119373D02*
Y1120906D01*
G01Y1122950D02*
Y1121519D01*
G01X2707452Y1118759D02*
Y1123563D01*
G01X2710254Y1119475D02*
X2709954Y1119373D01*
G01Y1121519D02*
X2710254Y1121621D01*
G01X2707452Y1123563D02*
X2709854D01*
G01D02*
X2710354Y1123461D01*
G01X2720070Y327559D02*
G03X2720858Y326771I788J0D01*
G01Y329724D02*
G03X2720070Y328937I0J-788D01*
G01X2727669Y329724D02*
X2720858D01*
G01X2727669Y326771D02*
X2720858D01*
G01X2720070Y328937D02*
Y327559D01*
G01X2717964Y368346D02*
X2720011D01*
G01X2721114D02*
X2723161D01*
G01X2714815D02*
X2716862D01*
G01X2711665D02*
X2713712D01*
G01X2713476Y366909D02*
X2711901D01*
G01X2716626D02*
X2715051D01*
G01X2722925D02*
X2721350D01*
G01X2719775D02*
X2718200D01*
G01X2721645Y368878D02*
X2721114Y368346D01*
G01X2718496Y368878D02*
X2717964Y368346D01*
G01X2715346Y368878D02*
X2714815Y368346D01*
G01X2712196Y368878D02*
X2711665Y368346D01*
G01X2722630Y368878D02*
X2723161Y368346D01*
G01X2719480Y368878D02*
X2720011Y368346D01*
G01X2716330Y368878D02*
X2716862Y368346D01*
G01X2713181Y368878D02*
X2713712Y368346D01*
G01X2710031Y368878D02*
X2710563Y368346D01*
G01X2723082Y397756D02*
Y364153D01*
G01X2722925Y366909D02*
Y364153D01*
G01X2721350Y366909D02*
Y364153D01*
G01X2721193Y397756D02*
Y364153D01*
G01X2721114Y397441D02*
Y368346D01*
G01X2720011D02*
Y397441D01*
G01X2719933Y397756D02*
Y364153D01*
G01X2719775Y366909D02*
Y364153D01*
G01X2718200Y366909D02*
Y364153D01*
G01X2718043Y397756D02*
Y364153D01*
G01X2717964Y397441D02*
Y368346D01*
G01X2716862D02*
Y397441D01*
G01X2716783Y397756D02*
Y364153D01*
G01X2716626Y366909D02*
Y364153D01*
G01X2715051Y366909D02*
Y364153D01*
G01X2714893Y397756D02*
Y364153D01*
G01X2714815Y397441D02*
Y368346D01*
G01X2713712D02*
Y397441D01*
G01X2713633Y397756D02*
Y364153D01*
G01X2713476Y366909D02*
Y364153D01*
G01X2711901Y366909D02*
Y364153D01*
G01X2711744Y397756D02*
Y364153D01*
G01X2711665Y397441D02*
Y368346D01*
G01X2710563D02*
Y397441D01*
G01X2710484Y397756D02*
Y364153D01*
G01X2710326Y366909D02*
Y364153D01*
G01X2724263Y368346D02*
X2726311D01*
G01X2726074Y366909D02*
X2724500D01*
G01X2724795Y368878D02*
X2724263Y368346D01*
G01X2725779Y368878D02*
X2726311Y368346D01*
G01D02*
Y397441D01*
G01X2726232Y397756D02*
Y364153D01*
G01X2726074Y366909D02*
Y364153D01*
G01X2724500Y366909D02*
Y364153D01*
G01X2724342Y397756D02*
Y364153D01*
G01X2724263Y397441D02*
Y368346D01*
G01X2723161D02*
Y397441D01*
G01X2720762Y369964D02*
X2720363D01*
G01X2717612D02*
X2717214D01*
G01X2714463D02*
X2714064D01*
G01X2711313D02*
X2710915D01*
G01X2712196Y378523D02*
X2711665D01*
G01X2710563D02*
X2710031D01*
G01X2716862D02*
X2716330D01*
G01X2715346D02*
X2714815D01*
G01X2713712D02*
X2713181D01*
G01X2721645D02*
X2721114D01*
G01X2720011D02*
X2719480D01*
G01X2718496D02*
X2717964D01*
G01X2723161D02*
X2722630D01*
G01X2721849Y376504D02*
X2722426D01*
G01X2718700D02*
X2719276D01*
G01X2712400D02*
X2712977D01*
G01X2715550D02*
X2716126D01*
G01X2711393Y376263D02*
X2710835D01*
G01X2714543D02*
X2713985D01*
G01X2717692D02*
X2717134D01*
G01X2720842D02*
X2720284D01*
G01X2713082Y376160D02*
X2712295D01*
G01X2716232D02*
X2715445D01*
G01X2719382D02*
X2718594D01*
G01X2722531D02*
X2721744D01*
G01X2717164Y376064D02*
X2717662D01*
G01X2720314D02*
X2720811D01*
G01X2714015D02*
X2714512D01*
G01X2710865D02*
X2711363D01*
G01X2711357Y376039D02*
X2710870D01*
G01X2714507D02*
X2714020D01*
G01X2717657D02*
X2717169D01*
G01X2720806D02*
X2720319D01*
G01X2717019Y376006D02*
X2717807D01*
G01X2720169D02*
X2720956D01*
G01X2713870D02*
X2714657D01*
G01X2710720D02*
X2711507D01*
G01Y375823D02*
X2710720D01*
G01X2714657D02*
X2713870D01*
G01X2717807D02*
X2717019D01*
G01X2720956D02*
X2720169D01*
G01X2717019Y375682D02*
X2717807D01*
G01X2720169D02*
X2720956D01*
G01X2713870D02*
X2714657D01*
G01X2710720D02*
X2711507D01*
G01Y375465D02*
X2710720D01*
G01X2714657D02*
X2713870D01*
G01X2717807D02*
X2717019D01*
G01X2720956D02*
X2720169D01*
G01X2717180Y375165D02*
X2717646D01*
G01X2720330D02*
X2720795D01*
G01X2714031D02*
X2714496D01*
G01X2710881D02*
X2711346D01*
G01X2721744Y375135D02*
X2722531D01*
G01X2718594D02*
X2719382D01*
G01X2712295D02*
X2713082D01*
G01X2715445D02*
X2716232D01*
G01X2712968Y374710D02*
X2712409D01*
G01X2716117D02*
X2715559D01*
G01X2719267D02*
X2718709D01*
G01X2722417D02*
X2721858D01*
G01X2722630Y372618D02*
X2723161D01*
G01X2721114D02*
X2721645D01*
G01X2719480D02*
X2720011D01*
G01X2717964D02*
X2718496D01*
G01X2716330D02*
X2716862D01*
G01X2714815D02*
X2715346D01*
G01X2713181D02*
X2713712D01*
G01X2711665D02*
X2712196D01*
G01X2710031D02*
X2710563D01*
G01X2721744Y371785D02*
X2722531D01*
G01X2718594D02*
X2719382D01*
G01X2712295D02*
X2713082D01*
G01X2715445D02*
X2716232D01*
G01X2711507Y371314D02*
X2710720D01*
G01X2714657D02*
X2713870D01*
G01X2717807D02*
X2717019D01*
G01X2720956D02*
X2720169D01*
G01X2713082Y370502D02*
X2712295D01*
G01X2716232D02*
X2715445D01*
G01X2719382D02*
X2718594D01*
G01X2722531D02*
X2721744D01*
G01X2717077Y370476D02*
X2717750D01*
G01X2720226D02*
X2720899D01*
G01X2713927D02*
X2714600D01*
G01X2710778D02*
X2711450D01*
G01X2721744Y370252D02*
X2722531D01*
G01X2718594D02*
X2719382D01*
G01X2712295D02*
X2713082D01*
G01X2715445D02*
X2716232D01*
G01X2717147Y370212D02*
X2717679D01*
G01X2720297D02*
X2720828D01*
G01X2713998D02*
X2714529D01*
G01X2710848D02*
X2711380D01*
G01X2711378Y370207D02*
X2710850D01*
G01X2714528D02*
X2713999D01*
G01X2717678D02*
X2717149D01*
G01X2720827D02*
X2720298D01*
G01X2713082Y370198D02*
X2712295D01*
G01X2716232D02*
X2715445D01*
G01X2719382D02*
X2718594D01*
G01X2722531D02*
X2721744D01*
G01X2713082Y370171D02*
X2712295D01*
G01X2716232D02*
X2715445D01*
G01X2719382D02*
X2718594D01*
G01X2722531D02*
X2721744D01*
G01X2717216Y369955D02*
X2717610D01*
G01X2720366D02*
X2720759D01*
G01X2714067D02*
X2714460D01*
G01X2710917D02*
X2711311D01*
G01X2721645Y368878D02*
X2722630D01*
G01X2718496D02*
X2719480D01*
G01X2715346D02*
X2716330D01*
G01X2712196D02*
X2713181D01*
G01X2713082Y370324D02*
X2712295Y370323D01*
G01X2716232Y370324D02*
X2715445Y370323D01*
G01X2719382Y370324D02*
X2718594Y370323D01*
G01X2722531Y370324D02*
X2721744Y370323D01*
G01X2720759Y369955D02*
X2720956Y370689D01*
G01X2717610Y369955D02*
X2717807Y370689D01*
G01X2714460Y369955D02*
X2714657Y370689D01*
G01X2711311Y369955D02*
X2711507Y370689D01*
G01X2720811Y376064D02*
X2720806Y376039D01*
G01X2717662Y376064D02*
X2717657Y376039D01*
G01X2714512Y376064D02*
X2714507Y376039D01*
G01X2711363Y376064D02*
X2711357Y376039D01*
G01X2722426Y376504D02*
X2722531Y377021D01*
G01X2719276Y376504D02*
X2719382Y377021D01*
G01X2716126Y376504D02*
X2716232Y377021D01*
G01X2712977Y376504D02*
X2713082Y377021D01*
G01X2721858Y374710D02*
X2721744Y374117D01*
G01X2718709Y374710D02*
X2718594Y374117D01*
G01X2715559Y374710D02*
X2715445Y374117D01*
G01X2712409Y374710D02*
X2712295Y374117D01*
G01X2720169Y374267D02*
X2720330Y375165D01*
G01X2717019Y374267D02*
X2717180Y375165D01*
G01X2713870Y374267D02*
X2714031Y375165D01*
G01X2710720Y374267D02*
X2710881Y375165D01*
G01X2720795D02*
X2720956Y374267D01*
G01X2717646Y375165D02*
X2717807Y374267D01*
G01X2714496Y375165D02*
X2714657Y374267D01*
G01X2711346Y375165D02*
X2711507Y374267D01*
G01X2722531Y374117D02*
X2722417Y374710D01*
G01X2719382Y374117D02*
X2719267Y374710D01*
G01X2716232Y374117D02*
X2716117Y374710D01*
G01X2713082Y374117D02*
X2712968Y374710D01*
G01X2721849Y376504D02*
X2721744Y377021D01*
G01X2718700Y376504D02*
X2718594Y377021D01*
G01X2715550Y376504D02*
X2715445Y377021D01*
G01X2712400Y376504D02*
X2712295Y377021D01*
G01X2720319Y376039D02*
X2720314Y376064D01*
G01X2717169Y376039D02*
X2717164Y376064D01*
G01X2714020Y376039D02*
X2714015Y376064D01*
G01X2710870Y376039D02*
X2710865Y376064D01*
G01X2720366Y369955D02*
X2720169Y370689D01*
G01X2717216Y369955D02*
X2717019Y370689D01*
G01X2714067Y369955D02*
X2713870Y370689D01*
G01X2710917Y369955D02*
X2710720Y370689D01*
G01X2720956Y377419D02*
X2720842Y376263D01*
G01X2717807Y377419D02*
X2717692Y376263D01*
G01X2714657Y377419D02*
X2714543Y376263D01*
G01X2711507Y377419D02*
X2711393Y376263D01*
G01X2722630Y378523D02*
Y396909D01*
G01Y368878D02*
Y372618D01*
G01X2722531Y398326D02*
Y370171D01*
G01X2721744D02*
Y398326D01*
G01X2721645Y372618D02*
Y368878D01*
G01Y396909D02*
Y378523D01*
G01X2720956Y370689D02*
Y407972D01*
G01X2720169Y370689D02*
Y407972D01*
G01X2719480Y378523D02*
Y396909D01*
G01Y368878D02*
Y372618D01*
G01X2719382Y398326D02*
Y370171D01*
G01X2718594D02*
Y398326D01*
G01X2718496Y372618D02*
Y368878D01*
G01Y396909D02*
Y378523D01*
G01X2717807Y370689D02*
Y407972D01*
G01X2717019Y370689D02*
Y407972D01*
G01X2716330Y378523D02*
Y396909D01*
G01Y368878D02*
Y372618D01*
G01X2716232Y398326D02*
Y370171D01*
G01X2715445D02*
Y398326D01*
G01X2715346Y372618D02*
Y368878D01*
G01Y396909D02*
Y378523D01*
G01X2714657Y370689D02*
Y407972D01*
G01X2713870Y370689D02*
Y407972D01*
G01X2713181Y378523D02*
Y396909D01*
G01Y368878D02*
Y372618D01*
G01X2713082Y398326D02*
Y370171D01*
G01X2712295D02*
Y398326D01*
G01X2712196Y372618D02*
Y368878D01*
G01Y396909D02*
Y378523D01*
G01X2711507Y370689D02*
Y407972D01*
G01X2710720Y370689D02*
Y407972D01*
G01X2710031Y378523D02*
Y396909D01*
G01Y368878D02*
Y372618D01*
G01X2720284Y376263D02*
X2720169Y377419D01*
G01X2717134Y376263D02*
X2717019Y377419D01*
G01X2713985Y376263D02*
X2713870Y377419D01*
G01X2710835Y376263D02*
X2710720Y377419D01*
G01X2723911Y369964D02*
X2723513D01*
G01X2726311Y378523D02*
X2725779D01*
G01X2724795D02*
X2724263D01*
G01X2724999Y376504D02*
X2725575D01*
G01X2723991Y376263D02*
X2723433D01*
G01X2725681Y376160D02*
X2724893D01*
G01X2723463Y376064D02*
X2723961D01*
G01X2723956Y376039D02*
X2723469D01*
G01X2723319Y376006D02*
X2724106D01*
G01Y375823D02*
X2723319D01*
G01Y375682D02*
X2724106D01*
G01Y375465D02*
X2723319D01*
G01X2723480Y375165D02*
X2723945D01*
G01X2724893Y375135D02*
X2725681D01*
G01X2725566Y374710D02*
X2725008D01*
G01X2725779Y372618D02*
X2726311D01*
G01X2724263D02*
X2724795D01*
G01X2724893Y371785D02*
X2725681D01*
G01X2724106Y371314D02*
X2723319D01*
G01X2725681Y370502D02*
X2724893D01*
G01X2723376Y370476D02*
X2724049D01*
G01X2724893Y370252D02*
X2725681D01*
G01X2723446Y370212D02*
X2723978D01*
G01X2723977Y370207D02*
X2723448D01*
G01X2725681Y370198D02*
X2724893D01*
G01X2725681Y370171D02*
X2724893D01*
G01X2723515Y369955D02*
X2723909D01*
G01X2724795Y368878D02*
X2725779D01*
G01X2725681Y370324D02*
X2724893Y370323D01*
G01X2723909Y369955D02*
X2724106Y370689D01*
G01X2723961Y376064D02*
X2723956Y376039D01*
G01X2725575Y376504D02*
X2725681Y377021D01*
G01X2725008Y374710D02*
X2724893Y374117D01*
G01X2723319Y374267D02*
X2723480Y375165D01*
G01X2724106Y377419D02*
X2723991Y376263D01*
G01X2723945Y375165D02*
X2724106Y374267D01*
G01X2725681Y374117D02*
X2725566Y374710D01*
G01X2724999Y376504D02*
X2724893Y377021D01*
G01X2723469Y376039D02*
X2723463Y376064D01*
G01X2723515Y369955D02*
X2723319Y370689D01*
G01X2725779Y378523D02*
Y396909D01*
G01Y368878D02*
Y372618D01*
G01X2725681Y398326D02*
Y370171D01*
G01X2724893D02*
Y398326D01*
G01X2724795Y372618D02*
Y368878D01*
G01Y396909D02*
Y378523D01*
G01X2724106Y370689D02*
Y407972D01*
G01X2723319Y370689D02*
Y407972D01*
G01X2723433Y376263D02*
X2723319Y377419D01*
G01X2721114Y394074D02*
X2721645Y394294D01*
G01X2717964Y394074D02*
X2718496Y394294D01*
G01X2714815Y394074D02*
X2715346Y394294D01*
G01X2711665Y394074D02*
X2712196Y394294D01*
G01X2713082Y394901D02*
X2712295D01*
G01X2716232D02*
X2715445D01*
G01X2719382D02*
X2718594D01*
G01X2722531D02*
X2721744D01*
G01X2713082Y394665D02*
X2712295D01*
G01X2716232D02*
X2715445D01*
G01X2719382D02*
X2718594D01*
G01X2722531D02*
X2721744D01*
G01X2717019Y394626D02*
X2717807D01*
G01X2720169D02*
X2720956D01*
G01X2713870D02*
X2714657D01*
G01X2710720D02*
X2711507D01*
G01X2717019Y394586D02*
X2717807D01*
G01X2720169D02*
X2720956D01*
G01X2713870D02*
X2714657D01*
G01X2710720D02*
X2711507D01*
G01X2713082Y394488D02*
X2712295D01*
G01X2716232D02*
X2715445D01*
G01X2719382D02*
X2718594D01*
G01X2722531D02*
X2721744D01*
G01X2711507Y394347D02*
X2710720D01*
G01X2714657D02*
X2713870D01*
G01X2717807D02*
X2717019D01*
G01X2720956D02*
X2720169D01*
G01X2721744Y394311D02*
X2722531D01*
G01X2718594D02*
X2719382D01*
G01X2712295D02*
X2713082D01*
G01X2715445D02*
X2716232D01*
G01X2711665Y394074D02*
X2710563D01*
G01X2713082D02*
X2712295D01*
G01X2716232D02*
X2715445D01*
G01X2714815D02*
X2713712D01*
G01X2717964D02*
X2716862D01*
G01X2719382D02*
X2718594D01*
G01X2721114D02*
X2720011D01*
G01X2722531D02*
X2721744D01*
G01X2721645Y394055D02*
X2722630D01*
G01X2718496D02*
X2719480D01*
G01X2712196D02*
X2713181D01*
G01X2715346D02*
X2716330D01*
G01X2721744Y393996D02*
X2722531D01*
G01X2718594D02*
X2719382D01*
G01X2712295D02*
X2713082D01*
G01X2715445D02*
X2716232D01*
G01X2713181Y393740D02*
X2712196D01*
G01X2716330D02*
X2715346D01*
G01X2719480D02*
X2718496D01*
G01X2722630D02*
X2721645D01*
G01X2721744Y393702D02*
X2722531D01*
G01X2718594D02*
X2719382D01*
G01X2712295D02*
X2713082D01*
G01X2715445D02*
X2716232D01*
G01X2713082Y393681D02*
X2712295D01*
G01X2716232D02*
X2715445D01*
G01X2719382D02*
X2718594D01*
G01X2722531D02*
X2721744D01*
G01X2713073Y393641D02*
X2712304D01*
G01X2716223D02*
X2715454D01*
G01X2719372D02*
X2718603D01*
G01X2722522D02*
X2721753D01*
G01X2713082Y393629D02*
X2712295D01*
G01X2716232D02*
X2715445D01*
G01X2719382D02*
X2718594D01*
G01X2722531D02*
X2721744D01*
G01Y393594D02*
X2722531D01*
G01X2718594D02*
X2719382D01*
G01X2712295D02*
X2713082D01*
G01X2715445D02*
X2716232D01*
G01X2721856Y393539D02*
X2722420D01*
G01X2718706D02*
X2719270D01*
G01X2712407D02*
X2712971D01*
G01X2715556D02*
X2716120D01*
G01X2717019Y393526D02*
X2717807D01*
G01X2720169D02*
X2720956D01*
G01X2713870D02*
X2714657D01*
G01X2710720D02*
X2711507D01*
G01X2721744Y393514D02*
X2722531D01*
G01X2718594D02*
X2719382D01*
G01X2712295D02*
X2713082D01*
G01X2715445D02*
X2716232D01*
G01X2711507Y393408D02*
X2710720D01*
G01X2714657D02*
X2713870D01*
G01X2717807D02*
X2717019D01*
G01X2720956D02*
X2720169D01*
G01X2711665Y393287D02*
X2710563D01*
G01X2714815D02*
X2713712D01*
G01X2717964D02*
X2716862D01*
G01X2721114D02*
X2720011D01*
G01X2712885Y393283D02*
X2712492D01*
G01X2716035D02*
X2715641D01*
G01X2719185D02*
X2718791D01*
G01X2722334D02*
X2721941D01*
G01X2722630Y392500D02*
X2724795D01*
G01X2719480D02*
X2721645D01*
G01X2716330D02*
X2718496D01*
G01X2713181D02*
X2715346D01*
G01X2710031D02*
X2712196D01*
G01X2717019Y392254D02*
X2717807D01*
G01X2720169D02*
X2720956D01*
G01X2713870D02*
X2714657D01*
G01X2710720D02*
X2711507D01*
G01X2717019Y392231D02*
X2717807D01*
G01X2720169D02*
X2720956D01*
G01X2713870D02*
X2714657D01*
G01X2710720D02*
X2711507D01*
G01Y391977D02*
X2710720D01*
G01X2714657D02*
X2713870D01*
G01X2717807D02*
X2717019D01*
G01X2720956D02*
X2720169D01*
G01X2711507Y391318D02*
X2710720D01*
G01X2714657D02*
X2713870D01*
G01X2717807D02*
X2717019D01*
G01X2720956D02*
X2720169D01*
G01X2721941Y391126D02*
X2722334D01*
G01X2718791D02*
X2719185D01*
G01X2712492D02*
X2712885D01*
G01X2715641D02*
X2716035D01*
G01X2712971Y390870D02*
X2712407D01*
G01X2716120D02*
X2715556D01*
G01X2719270D02*
X2718706D01*
G01X2722420D02*
X2721856D01*
G01X2721753Y390768D02*
X2722522D01*
G01X2718603D02*
X2719372D01*
G01X2712304D02*
X2713073D01*
G01X2715454D02*
X2716223D01*
G01X2711507Y390728D02*
X2710720D01*
G01X2714657D02*
X2713870D01*
G01X2713181D02*
X2712196D01*
G01X2716330D02*
X2715346D01*
G01X2717807D02*
X2717019D01*
G01X2720956D02*
X2720169D01*
G01X2719480D02*
X2718496D01*
G01X2722630D02*
X2721645D01*
G01X2713082Y390515D02*
X2712295D01*
G01X2716232D02*
X2715445D01*
G01X2719382D02*
X2718594D01*
G01X2722531D02*
X2721744D01*
G01X2721645Y390413D02*
X2722630D01*
G01X2718496D02*
X2719480D01*
G01X2712196D02*
X2713181D01*
G01X2715346D02*
X2716330D01*
G01X2711507Y390137D02*
X2710720D01*
G01X2714657D02*
X2713870D01*
G01X2717807D02*
X2717019D01*
G01X2720956D02*
X2720169D01*
G01X2721645Y390098D02*
X2722630D01*
G01X2718496D02*
X2719480D01*
G01X2712196D02*
X2713181D01*
G01X2715346D02*
X2716330D01*
G01X2721744Y390082D02*
X2722531D01*
G01X2718594D02*
X2719382D01*
G01X2712295D02*
X2713082D01*
G01X2715445D02*
X2716232D01*
G01X2721744Y389858D02*
X2722531D01*
G01X2718594D02*
X2719382D01*
G01X2712295D02*
X2713082D01*
G01X2715445D02*
X2716232D01*
G01X2717019Y389547D02*
X2717807D01*
G01X2720169D02*
X2720956D01*
G01X2713870D02*
X2714657D01*
G01X2710720D02*
X2711507D01*
G01X2713082Y389425D02*
X2712295D01*
G01X2716232D02*
X2715445D01*
G01X2719382D02*
X2718594D01*
G01X2722531D02*
X2721744D01*
G01X2711507Y388956D02*
X2710720D01*
G01X2714657D02*
X2713870D01*
G01X2717807D02*
X2717019D01*
G01X2720956D02*
X2720169D01*
G01X2721753Y390768D02*
X2721856Y390870D01*
G01X2722420Y393539D02*
X2722522Y393641D01*
G01X2718603Y390768D02*
X2718706Y390870D01*
G01X2721114Y393287D02*
X2721645Y393818D01*
G01D02*
X2721114Y393287D01*
G01X2719270Y393539D02*
X2719372Y393641D01*
G01X2715454Y390768D02*
X2715556Y390870D01*
G01X2717964Y393287D02*
X2718496Y393818D01*
G01D02*
X2717964Y393287D01*
G01X2716120Y393539D02*
X2716223Y393641D01*
G01X2712304Y390768D02*
X2712407Y390870D01*
G01X2714815Y393287D02*
X2715346Y393818D01*
G01D02*
X2714815Y393287D01*
G01X2712971Y393539D02*
X2713073Y393641D01*
G01X2711665Y393287D02*
X2712196Y393818D01*
G01D02*
X2711665Y393287D01*
G01X2722630Y394294D02*
X2723161Y394074D01*
G01X2719480Y394294D02*
X2720011Y394074D01*
G01X2716330Y394294D02*
X2716862Y394074D01*
G01X2713181Y394294D02*
X2713712Y394074D01*
G01X2710031Y394294D02*
X2710563Y394074D01*
G01X2722630Y393818D02*
X2723161Y393287D01*
G01D02*
X2722630Y393818D01*
G01X2721856Y393539D02*
X2721753Y393641D01*
G01X2719480Y393818D02*
X2720011Y393287D01*
G01D02*
X2719480Y393818D01*
G01X2722420Y390870D02*
X2722522Y390768D01*
G01X2718706Y393539D02*
X2718603Y393641D01*
G01X2716330Y393818D02*
X2716862Y393287D01*
G01D02*
X2716330Y393818D01*
G01X2719270Y390870D02*
X2719372Y390768D01*
G01X2715556Y393539D02*
X2715454Y393641D01*
G01X2713181Y393818D02*
X2713712Y393287D01*
G01D02*
X2713181Y393818D01*
G01X2716120Y390870D02*
X2716223Y390768D01*
G01X2712407Y393539D02*
X2712304Y393641D01*
G01X2710031Y393818D02*
X2710563Y393287D01*
G01D02*
X2710031Y393818D01*
G01X2712971Y390870D02*
X2713073Y390768D01*
G01X2722334Y393283D02*
Y391126D01*
G01X2721941D02*
Y393283D01*
G01X2721055Y397618D02*
Y388248D01*
G01X2720070Y397618D02*
Y388248D01*
G01X2719185Y393283D02*
Y391126D01*
G01X2718791D02*
Y393283D01*
G01X2717905Y397618D02*
Y388248D01*
G01X2716921Y397618D02*
Y388248D01*
G01X2716035Y393283D02*
Y391126D01*
G01X2715641D02*
Y393283D01*
G01X2714756Y397618D02*
Y388248D01*
G01X2713771Y397618D02*
Y388248D01*
G01X2712885Y393283D02*
Y391126D01*
G01X2712492D02*
Y393283D01*
G01X2711606Y397618D02*
Y388248D01*
G01X2710622Y397618D02*
Y388248D01*
G01X2711507Y398602D02*
X2710720D01*
G01X2714657D02*
X2713870D01*
G01X2717807D02*
X2717019D01*
G01X2720956D02*
X2720169D01*
G01X2713082Y398326D02*
X2712295D01*
G01X2716232D02*
X2715445D01*
G01X2719382D02*
X2718594D01*
G01X2722531D02*
X2721744D01*
G01X2713082Y397736D02*
X2712295D01*
G01X2716232D02*
X2715445D01*
G01X2719382D02*
X2718594D01*
G01X2722531D02*
X2721744D01*
G01X2711606Y397618D02*
X2710622D01*
G01X2714756D02*
X2713771D01*
G01X2717905D02*
X2716921D01*
G01X2721055D02*
X2720070D01*
G01X2713712Y397441D02*
X2711665D01*
G01X2716862D02*
X2714815D01*
G01X2720011D02*
X2717964D01*
G01X2723161D02*
X2721114D01*
G01X2711507Y397421D02*
X2710720D01*
G01X2714657D02*
X2713870D01*
G01X2717807D02*
X2717019D01*
G01X2720956D02*
X2720169D01*
G01X2713181Y396909D02*
X2712196D01*
G01X2716330D02*
X2715346D01*
G01X2719480D02*
X2718496D01*
G01X2722630D02*
X2721645D01*
G01X2713082Y396830D02*
X2712295D01*
G01X2716232D02*
X2715445D01*
G01X2719382D02*
X2718594D01*
G01X2722531D02*
X2721744D01*
G01X2717019Y396633D02*
X2717807D01*
G01X2720169D02*
X2720956D01*
G01X2713870D02*
X2714657D01*
G01X2710720D02*
X2711507D01*
G01X2721744Y396594D02*
X2722531D01*
G01X2718594D02*
X2719382D01*
G01X2712295D02*
X2713082D01*
G01X2715445D02*
X2716232D01*
G01X2711507Y396515D02*
X2710720D01*
G01X2714657D02*
X2713870D01*
G01X2717807D02*
X2717019D01*
G01X2720956D02*
X2720169D01*
G01X2713082Y396417D02*
X2712295D01*
G01X2716232D02*
X2715445D01*
G01X2719382D02*
X2718594D01*
G01X2722531D02*
X2721744D01*
G01X2711901Y396043D02*
X2710326D01*
G01X2718200D02*
X2716626D01*
G01X2715051D02*
X2713476D01*
G01X2713082D02*
X2712295D01*
G01X2716232D02*
X2715445D01*
G01X2721350D02*
X2719775D01*
G01X2719382D02*
X2718594D01*
G01X2724500D02*
X2722925D01*
G01X2722531D02*
X2721744D01*
G01X2713082Y396004D02*
X2712295D01*
G01X2716232D02*
X2715445D01*
G01X2719382D02*
X2718594D01*
G01X2722531D02*
X2721744D01*
G01X2722630Y396909D02*
X2723161Y397441D01*
G01X2721448Y398011D02*
X2721055Y397618D01*
G01X2719480Y396909D02*
X2720011Y397441D01*
G01X2718299Y398011D02*
X2717905Y397618D01*
G01X2716330Y396909D02*
X2716862Y397441D01*
G01X2715149Y398011D02*
X2714756Y397618D01*
G01X2713181Y396909D02*
X2713712Y397441D01*
G01X2712000Y398011D02*
X2711606Y397618D01*
G01X2710031Y396909D02*
X2710563Y397441D01*
G01X2722826Y398011D02*
X2723220Y397618D01*
G01X2721114Y397441D02*
X2721645Y396909D01*
G01X2719677Y398011D02*
X2720070Y397618D01*
G01X2717964Y397441D02*
X2718496Y396909D01*
G01X2716527Y398011D02*
X2716921Y397618D01*
G01X2714815Y397441D02*
X2715346Y396909D01*
G01X2713378Y398011D02*
X2713771Y397618D01*
G01X2711665Y397441D02*
X2712196Y396909D01*
G01X2710228Y398011D02*
X2710622Y397618D01*
G01X2722925Y398011D02*
Y396043D01*
G01X2721350Y398011D02*
Y396043D01*
G01X2719775Y398011D02*
Y396043D01*
G01X2718200Y398011D02*
Y396043D01*
G01X2716626Y398011D02*
Y396043D01*
G01X2715051Y398011D02*
Y396043D01*
G01X2713476Y398011D02*
Y396043D01*
G01X2711901Y398011D02*
Y396043D01*
G01X2710326Y398011D02*
Y396043D01*
G01X2724263Y394074D02*
X2724795Y394294D01*
G01X2725681Y394901D02*
X2724893D01*
G01X2725681Y394665D02*
X2724893D01*
G01X2723319Y394626D02*
X2724106D01*
G01X2723319Y394586D02*
X2724106D01*
G01X2725681Y394488D02*
X2724893D01*
G01X2724106Y394347D02*
X2723319D01*
G01X2724893Y394311D02*
X2725681D01*
G01Y394074D02*
X2724893D01*
G01X2724263D02*
X2723161D01*
G01X2727413D02*
X2726311D01*
G01X2724795Y394055D02*
X2725779D01*
G01X2724893Y393996D02*
X2725681D01*
G01X2725779Y393740D02*
X2724795D01*
G01X2724893Y393702D02*
X2725681D01*
G01Y393681D02*
X2724893D01*
G01X2725672Y393641D02*
X2724902D01*
G01X2725681Y393629D02*
X2724893D01*
G01Y393594D02*
X2725681D01*
G01X2725005Y393539D02*
X2725569D01*
G01X2723319Y393526D02*
X2724106D01*
G01X2724893Y393514D02*
X2725681D01*
G01X2724106Y393408D02*
X2723319D01*
G01X2724263Y393287D02*
X2723161D01*
G01X2727413D02*
X2726311D01*
G01X2725484Y393283D02*
X2725090D01*
G01X2725779Y392500D02*
X2727945D01*
G01X2723319Y392254D02*
X2724106D01*
G01X2723319Y392231D02*
X2724106D01*
G01Y391977D02*
X2723319D01*
G01X2724106Y391318D02*
X2723319D01*
G01X2725090Y391126D02*
X2725484D01*
G01X2725569Y390870D02*
X2725005D01*
G01X2724902Y390768D02*
X2725672D01*
G01X2724106Y390728D02*
X2723319D01*
G01X2725779D02*
X2724795D01*
G01X2725681Y390515D02*
X2724893D01*
G01X2724795Y390413D02*
X2725779D01*
G01X2724106Y390137D02*
X2723319D01*
G01X2724795Y390098D02*
X2725779D01*
G01X2724893Y390082D02*
X2725681D01*
G01X2724893Y389858D02*
X2725681D01*
G01X2723319Y389547D02*
X2724106D01*
G01X2725681Y389425D02*
X2724893D01*
G01X2724106Y388956D02*
X2723319D01*
G01X2724902Y390768D02*
X2725005Y390870D01*
G01X2725569Y393539D02*
X2725672Y393641D01*
G01X2724263Y393287D02*
X2724795Y393818D01*
G01D02*
X2724263Y393287D01*
G01X2725779Y394294D02*
X2726311Y394074D01*
G01X2725779Y393818D02*
X2726311Y393287D01*
G01D02*
X2725779Y393818D01*
G01X2725005Y393539D02*
X2724902Y393641D01*
G01X2725569Y390870D02*
X2725672Y390768D01*
G01X2726370Y397618D02*
Y388248D01*
G01X2725484Y393283D02*
Y391126D01*
G01X2725090D02*
Y393283D01*
G01X2724204Y397618D02*
Y388248D01*
G01X2723220Y397618D02*
Y388248D01*
G01X2724106Y398602D02*
X2723319D01*
G01X2725681Y398326D02*
X2724893D01*
G01X2725681Y397736D02*
X2724893D01*
G01X2724204Y397618D02*
X2723220D01*
G01X2727354D02*
X2726370D01*
G01X2726311Y397441D02*
X2724263D01*
G01X2724106Y397421D02*
X2723319D01*
G01X2725779Y396909D02*
X2724795D01*
G01X2725681Y396830D02*
X2724893D01*
G01X2723319Y396633D02*
X2724106D01*
G01X2724893Y396594D02*
X2725681D01*
G01X2724106Y396515D02*
X2723319D01*
G01X2725681Y396417D02*
X2724893D01*
G01X2727649Y396043D02*
X2726074D01*
G01X2725681D02*
X2724893D01*
G01X2725681Y396004D02*
X2724893D01*
G01X2725779Y396909D02*
X2726311Y397441D01*
G01X2724598Y398011D02*
X2724204Y397618D01*
G01X2725976Y398011D02*
X2726370Y397618D01*
G01X2724263Y397441D02*
X2724795Y396909D01*
G01X2726074Y398011D02*
Y396043D01*
G01X2724500Y398011D02*
Y396043D01*
G01X2711507Y407972D02*
X2710720D01*
G01X2714657D02*
X2713870D01*
G01X2717807D02*
X2717019D01*
G01X2720956D02*
X2720169D01*
G01X2711507Y407381D02*
X2710720D01*
G01X2714657D02*
X2713870D01*
G01X2717807D02*
X2717019D01*
G01X2720956D02*
X2720169D01*
G01X2717019Y406476D02*
X2717807D01*
G01X2720169D02*
X2720956D01*
G01X2713870D02*
X2714657D01*
G01X2710720D02*
X2711507D01*
G01X2721665Y405885D02*
X2722610D01*
G01X2718515D02*
X2719460D01*
G01X2715366D02*
X2716311D01*
G01X2712216D02*
X2713161D01*
G01X2711507D02*
X2710720D01*
G01X2714657D02*
X2713870D01*
G01X2717807D02*
X2717019D01*
G01X2720956D02*
X2720169D01*
G01X2711507Y405177D02*
X2710720D01*
G01X2714657D02*
X2713870D01*
G01X2717807D02*
X2717019D01*
G01X2720956D02*
X2720169D01*
G01X2711507Y404232D02*
X2710720D01*
G01X2714657D02*
X2713870D01*
G01X2717807D02*
X2717019D01*
G01X2720956D02*
X2720169D01*
G01X2720051Y403641D02*
X2721074D01*
G01X2716901D02*
X2717925D01*
G01X2713752D02*
X2714775D01*
G01X2710602D02*
X2711626D01*
G01X2717019Y403051D02*
X2717807D01*
G01X2720169D02*
X2720956D01*
G01X2713870D02*
X2714657D01*
G01X2710720D02*
X2711507D01*
G01X2721665Y405885D02*
X2721074Y405295D01*
G01X2718515Y405885D02*
X2717925Y405295D01*
G01X2715366Y405885D02*
X2714775Y405295D01*
G01X2712216Y405885D02*
X2711626Y405295D01*
G01X2722610Y405885D02*
X2723200Y405295D01*
G01X2719460Y405885D02*
X2720051Y405295D01*
G01X2716311Y405885D02*
X2716901Y405295D01*
G01X2713161Y405885D02*
X2713752Y405295D01*
G01X2721074Y403641D02*
Y405295D01*
G01X2720051D02*
Y403641D01*
G01X2717925D02*
Y405295D01*
G01X2716901D02*
Y403641D01*
G01X2714775D02*
Y405295D01*
G01X2713752D02*
Y403641D01*
G01X2711626D02*
Y405295D01*
G01X2710602D02*
Y403641D01*
G01X2724106Y407972D02*
X2723319D01*
G01X2724106Y407381D02*
X2723319D01*
G01Y406476D02*
X2724106D01*
G01X2724815Y405885D02*
X2725759D01*
G01X2724106D02*
X2723319D01*
G01X2724106Y405177D02*
X2723319D01*
G01X2724106Y404232D02*
X2723319D01*
G01X2726350Y403641D02*
X2727374D01*
G01X2723200D02*
X2724224D01*
G01X2723319Y403051D02*
X2724106D01*
G01X2724815Y405885D02*
X2724224Y405295D01*
G01X2725759Y405885D02*
X2726350Y405295D01*
G01D02*
Y403641D01*
G01X2724224D02*
Y405295D01*
G01X2723200D02*
Y403641D01*
G01X2714576Y516256D02*
X2713493Y517700D01*
X2712952Y519143D01*
Y524917D01*
X2713493Y526361D01*
X2714576Y527804D01*
G01X2721613Y519143D02*
Y527804D01*
X2724211D01*
X2725077Y527371D01*
X2725727Y526361D01*
X2725943Y525206D01*
X2725727Y524051D01*
X2725185Y523185D01*
X2724211Y522752D01*
X2721613D01*
G01X2729732Y519143D02*
X2732439Y527804D01*
X2735146Y519143D01*
G01X2734171Y522174D02*
X2730707D01*
G01X2738718Y519143D02*
Y527804D01*
X2740883D01*
X2741750Y527371D01*
X2742399Y526794D01*
X2742941Y525928D01*
X2743374Y524917D01*
X2743482Y523473D01*
X2743374Y522030D01*
X2742941Y521019D01*
X2742399Y520153D01*
X2741750Y519576D01*
X2740883Y519143D01*
X2738718D01*
G01X2750302Y516256D02*
X2751385Y517700D01*
X2751926Y519143D01*
Y524917D01*
X2751385Y526361D01*
X2750302Y527804D01*
G01X2726862Y821909D02*
G03I-2244J0D01*
G01X2716862D02*
G03I-2244J0D01*
G01X2715368Y822659D02*
X2713868D01*
G01Y821159D02*
X2715368D01*
G01X2713368Y820659D02*
X2715868D01*
G01X2713868Y822659D02*
X2713368Y823159D01*
G01X2715368Y821159D02*
X2715868Y820659D01*
G01X2721118Y838409D02*
Y815409D01*
G01X2718118D02*
Y838409D01*
G01X2715868Y820659D02*
Y823159D01*
G01X2715368Y821159D02*
Y822659D01*
G01X2713868D02*
Y821159D01*
G01X2713368Y823159D02*
Y820659D01*
G01X2711118Y838409D02*
Y815409D01*
G01X2715368Y822659D02*
X2715868Y823159D01*
G01X2713868Y821159D02*
X2713368Y820659D01*
G01X2715868Y823159D02*
X2713368D01*
G01X2725368Y822659D02*
X2723868D01*
G01Y821159D02*
X2725368D01*
G01X2723368Y820659D02*
X2725868D01*
G01X2723868Y822659D02*
X2723368Y823159D01*
G01X2725368Y821159D02*
X2725868Y820659D01*
G01D02*
Y823159D01*
G01X2725368Y821159D02*
Y822659D01*
G01X2723868D02*
Y821159D01*
G01X2723368Y823159D02*
Y820659D01*
G01X2725368Y822659D02*
X2725868Y823159D01*
G01X2723868Y821159D02*
X2723368Y820659D01*
G01X2725868Y823159D02*
X2723368D01*
G01X2726862Y831909D02*
G03I-2244J0D01*
G01X2716862D02*
G03I-2244J0D01*
G01X2715868Y833159D02*
X2713368D01*
G01X2715368Y832659D02*
X2713868D01*
G01Y831159D02*
X2715368D01*
G01X2713368Y830659D02*
X2715868D01*
G01X2713868Y832659D02*
X2713368Y833159D01*
G01X2715368Y831159D02*
X2715868Y830659D01*
G01D02*
Y833159D01*
G01X2715368Y831159D02*
Y832659D01*
G01X2713868D02*
Y831159D01*
G01X2713368Y833159D02*
Y830659D01*
G01X2715368Y832659D02*
X2715868Y833159D01*
G01X2713868Y831159D02*
X2713368Y830659D01*
G01X2725868Y833159D02*
X2723368D01*
G01X2725368Y832659D02*
X2723868D01*
G01Y831159D02*
X2725368D01*
G01X2723368Y830659D02*
X2725868D01*
G01X2723868Y832659D02*
X2723368Y833159D01*
G01X2725368Y831159D02*
X2725868Y830659D01*
G01D02*
Y833159D01*
G01X2725368Y831159D02*
Y832659D01*
G01X2723868D02*
Y831159D01*
G01X2723368Y833159D02*
Y830659D01*
G01X2725368Y832659D02*
X2725868Y833159D01*
G01X2723868Y831159D02*
X2723368Y830659D01*
G01X2712098Y1084626D02*
G03X2716035Y1080689I3937J0D01*
G01X2785720D02*
X2716035D01*
G01X2712098Y1084626D02*
Y1114153D01*
G01X2710917Y1110610D02*
Y1094074D01*
G01X2712098Y1114153D02*
X2710130Y1116122D01*
G01X2713156Y1118759D02*
X2712556D01*
G01X2710554Y1121212D02*
X2710755Y1121110D01*
G01X2710354Y1123461D02*
X2710755Y1123154D01*
G01X2710454Y1122643D02*
X2710254Y1122847D01*
G01Y1120804D02*
X2710454Y1120599D01*
G01X2710755Y1123154D02*
X2711055Y1122745D01*
G01X2710755Y1121110D02*
X2711055Y1120701D01*
G01Y1122745D02*
X2711155Y1122439D01*
G01X2710554Y1122336D02*
X2710454Y1122643D01*
G01X2711055Y1120701D02*
X2711155Y1120394D01*
G01X2710454Y1120599D02*
X2710554Y1120293D01*
G01X2713156Y1123563D02*
Y1118759D01*
G01X2712556D02*
Y1122745D01*
G01X2711956Y1122030D02*
Y1122847D01*
G01X2711155Y1120394D02*
Y1119883D01*
G01Y1122439D02*
Y1122030D01*
G01X2710554Y1122132D02*
Y1122336D01*
G01Y1120293D02*
Y1119986D01*
G01X2711155Y1119883D02*
X2711055Y1119577D01*
G01X2710554Y1119986D02*
X2710454Y1119679D01*
G01X2711155Y1122030D02*
X2711055Y1121723D01*
G01X2710454Y1121825D02*
X2710554Y1122132D01*
G01X2710755Y1121315D02*
X2710554Y1121212D01*
G01X2710755Y1119168D02*
X2710354Y1118862D01*
G01X2710454Y1119679D02*
X2710254Y1119475D01*
G01Y1121621D02*
X2710454Y1121825D01*
G01X2712556Y1122745D02*
X2711956Y1122030D01*
G01Y1122847D02*
X2712556Y1123563D01*
G01X2711055Y1119577D02*
X2710755Y1119168D01*
G01X2711055Y1121723D02*
X2710755Y1121315D01*
G01X2712556Y1123563D02*
X2713156D01*
G01X2731397Y-1222633D02*
G03X2735334Y-1226570I3937J0D01*
G01D02*
X2776673D01*
G01X2731397Y-1069051D02*
Y-1222633D01*
G01X2773326Y-1201374D02*
G03I-15748J0D01*
G01Y-1138382D02*
G03I-15748J0D01*
G01X2731397Y-1069051D02*
G03X2727460Y-1065114I-3937J0D01*
G01X2728821Y198340D02*
X2729471Y199205D01*
X2730228Y199639D01*
X2731095Y199783D01*
X2732177Y199494D01*
X2732935Y198773D01*
X2733152Y197907D01*
X2733043Y197040D01*
X2732610Y196319D01*
X2730445Y194875D01*
X2729471Y193865D01*
X2728821Y192421D01*
X2728604Y191122D01*
X2733152D01*
G01X2740838D02*
Y199783D01*
X2736832Y193576D01*
X2742246D01*
G01X2748200Y190833D02*
X2747983Y190978D01*
Y191266D01*
X2748200Y191411D01*
X2748417Y191266D01*
Y190978D01*
X2748200Y190833D01*
G01X2754479Y192421D02*
X2755129Y191699D01*
X2755887Y191266D01*
X2756861Y191122D01*
X2757835Y191411D01*
X2758593Y191988D01*
X2759135Y192998D01*
X2759243Y194153D01*
X2759026Y195308D01*
X2758485Y196030D01*
X2757727Y196607D01*
X2756969Y196752D01*
X2756211Y196607D01*
X2755237Y196030D01*
X2755562Y199783D01*
X2758485D01*
G01X2765522D02*
X2764656Y199494D01*
X2764006Y198773D01*
X2763573Y197907D01*
X2763248Y196752D01*
X2763140Y195452D01*
X2763248Y194153D01*
X2763573Y192998D01*
X2764006Y192132D01*
X2764656Y191411D01*
X2765522Y191122D01*
X2766388Y191411D01*
X2767038Y192132D01*
X2767471Y192998D01*
X2767796Y194153D01*
X2767904Y195452D01*
X2767796Y196752D01*
X2767471Y197907D01*
X2767038Y198773D01*
X2766388Y199494D01*
X2765522Y199783D01*
G01X2740715Y239879D02*
X2728904D01*
G01X2760861Y221361D02*
X2740715Y239879D01*
G01X2728456Y328937D02*
G03X2727669Y329724I-787J0D01*
G01Y326771D02*
G03X2728456Y327559I0J787D01*
G01X2742429Y329100D02*
X2739466Y328133D01*
G01X2744185Y330282D02*
X2739027Y328563D01*
G01X2744185Y325984D02*
X2739027Y327703D01*
G01X2742429Y327166D02*
X2739466Y328133D01*
G01X2739027Y327703D02*
Y328563D01*
G01X2728456Y328937D02*
Y327559D01*
G01X2731193Y334645D02*
G03Y338582I0J1969D01*
G01Y333793D02*
G03Y339435I0J2821D01*
G01Y332941D02*
G03Y340287I0J3673D01*
G01Y334645D02*
Y332941D01*
G01X2742429Y329100D02*
Y327166D01*
G01X2741551Y335117D02*
X2741002Y334902D01*
G01X2741551Y332861D02*
X2741332Y332753D01*
G01X2741551Y334580D02*
X2741332Y334472D01*
G01X2741551Y335117D02*
X2744185D01*
G01Y334580D02*
X2741551D01*
G01Y333398D02*
X2744185D01*
G01Y332861D02*
X2741551D01*
G01X2741441Y331679D02*
X2744185D01*
G01X2740673D02*
X2741002D01*
G01X2744185Y331141D02*
X2740673D01*
G01X2741332Y332753D02*
X2741222Y332646D01*
G01X2741112Y333290D02*
X2740783Y332968D01*
G01X2741332Y334472D02*
X2741222Y334365D01*
G01X2741002Y334902D02*
X2740783Y334687D01*
G01X2741222Y332646D02*
X2741112Y332431D01*
G01X2741222Y334365D02*
X2741112Y334150D01*
G01X2741332Y333505D02*
X2741551Y333398D01*
G01X2740783Y332968D02*
X2740673Y332646D01*
G01X2740783Y334687D02*
X2740673Y334365D01*
G01X2741222Y333613D02*
X2741332Y333505D01*
G01X2740783Y333613D02*
X2741112Y333290D01*
G01X2741222Y331894D02*
X2741441Y331679D01*
G01X2740783Y331894D02*
X2741002Y331679D01*
G01X2741112Y332431D02*
Y332216D01*
G01Y334150D02*
Y333828D01*
G01X2740673Y333935D02*
Y334365D01*
G01Y332216D02*
Y332646D01*
G01Y331141D02*
Y331679D01*
G01Y333935D02*
X2740783Y333613D01*
G01X2741112Y332216D02*
X2741222Y331894D01*
G01X2740673Y332216D02*
X2740783Y331894D01*
G01X2741112Y333828D02*
X2741222Y333613D01*
G01X2739027Y340812D02*
X2741222D01*
G01X2744185Y340274D02*
X2739027D01*
G01D02*
Y340812D01*
G01X2731193Y340287D02*
Y338582D01*
G01X2742100Y338878D02*
X2741770Y338770D01*
G01X2742978Y344787D02*
X2742648Y344680D01*
G01X2741551Y339307D02*
X2741332Y339200D01*
G01X2743087Y344250D02*
X2742429Y344143D01*
G01X2741990Y343283D02*
X2741441Y343176D01*
G01X2741990Y342746D02*
X2741551Y342638D01*
G01X2741990Y339415D02*
X2741551Y339307D01*
G01X2741441Y343176D02*
X2741222Y343068D01*
G01X2741770Y338770D02*
X2741441Y338555D01*
G01X2741990Y344787D02*
X2741880D01*
G01X2742429Y344680D02*
X2742648D01*
G01X2741990Y343283D02*
X2744185D01*
G01Y342746D02*
X2741990D01*
G01X2741661Y340812D02*
X2744185D01*
G01X2741990Y339415D02*
X2742868D01*
G01X2742100Y338878D02*
X2742758D01*
G01X2740673Y336514D02*
X2741332D01*
G01X2742978D02*
X2741880D01*
G01X2745941Y335976D02*
X2740673D01*
G01X2741332Y339200D02*
X2741002Y338878D01*
G01X2741551Y342638D02*
X2741332Y342423D01*
G01X2741222Y343068D02*
X2741002Y342853D01*
G01X2742429Y344143D02*
X2741770Y344250D01*
G01X2741002Y338878D02*
X2740783Y338555D01*
G01X2743087Y338770D02*
X2742758Y338878D01*
G01X2741002Y342853D02*
X2740783Y342531D01*
G01X2741441Y338555D02*
X2741222Y338126D01*
G01X2741332Y342423D02*
X2741222Y342209D01*
G01X2741551Y336729D02*
X2741880Y336514D01*
G01X2741661Y344894D02*
X2741880Y344787D01*
G01X2741332Y344465D02*
X2741770Y344250D01*
G01X2741112Y336621D02*
X2741332Y336514D01*
G01X2740783Y342531D02*
X2740673Y342209D01*
G01X2741332Y345217D02*
X2741661Y344894D01*
G01X2741112Y344680D02*
X2741332Y344465D01*
G01X2741441Y341026D02*
X2741661Y340812D01*
G01X2741002Y341026D02*
X2741222Y340812D01*
G01X2740893Y336836D02*
X2741112Y336621D01*
G01X2740783Y338555D02*
X2740673Y338126D01*
G01X2741222Y342209D02*
X2741112Y341779D01*
G01X2741222Y346506D02*
X2741112Y345862D01*
G01X2740783Y346614D02*
X2740673Y345969D01*
G01X2742429Y347581D02*
Y344680D01*
G01X2741990Y347044D02*
Y344787D01*
G01X2741222Y337481D02*
Y338126D01*
G01X2740673Y341779D02*
Y342209D01*
G01Y337481D02*
Y338126D01*
G01Y335976D02*
Y336514D01*
G01Y345969D02*
X2740783Y345324D01*
G01X2741112Y345862D02*
X2741222Y345432D01*
G01X2741112Y341779D02*
X2741222Y341349D01*
G01X2740673Y341779D02*
X2740783Y341349D01*
G01X2741222Y337481D02*
X2741332Y337051D01*
G01X2740673Y337481D02*
X2740783Y337051D01*
G01Y345324D02*
X2740893Y345002D01*
G01X2741222Y345432D02*
X2741332Y345217D01*
G01X2740783Y337051D02*
X2740893Y336836D01*
G01Y345002D02*
X2741112Y344680D01*
G01X2741222Y341349D02*
X2741441Y341026D01*
G01X2740783Y341349D02*
X2741002Y341026D01*
G01X2741332Y337051D02*
X2741551Y336729D01*
G01X2741990Y347581D02*
X2741551Y347473D01*
G01Y351341D02*
X2741222Y351234D01*
G01X2742100Y351449D02*
X2741551Y351341D01*
G01X2742100Y350912D02*
X2741551Y350804D01*
G01X2742100Y351449D02*
X2744185D01*
G01Y350912D02*
X2742100D01*
G01X2741661Y348978D02*
X2744185D01*
G01X2740673D02*
X2741222D01*
G01X2744185Y348441D02*
X2740673D01*
G01X2741990Y347581D02*
X2742429D01*
G01X2741770Y347044D02*
X2741990D01*
G01X2741770D02*
X2741441Y346829D01*
G01X2741551Y347473D02*
X2741112Y347151D01*
G01X2741551Y350804D02*
X2741332Y350589D01*
G01X2741222Y351234D02*
X2741002Y351019D01*
G01X2741441Y346829D02*
X2741222Y346506D01*
G01X2741002Y351019D02*
X2740783Y350697D01*
G01X2741112Y347151D02*
X2740783Y346614D01*
G01X2741332Y350589D02*
X2741222Y350374D01*
G01X2740783Y350697D02*
X2740673Y350374D01*
G01X2741441Y349193D02*
X2741661Y348978D01*
G01X2741002Y349193D02*
X2741222Y348978D01*
G01Y350374D02*
X2741112Y349945D01*
G01X2740673D02*
Y350374D01*
G01Y348441D02*
Y348978D01*
G01X2741112Y349945D02*
X2741222Y349515D01*
G01X2740673Y349945D02*
X2740783Y349515D01*
G01X2741222D02*
X2741441Y349193D01*
G01X2740783Y349515D02*
X2741002Y349193D01*
G01X2732374Y355315D02*
G03X2734342I984J0D01*
G01X2749007Y360236D02*
X2734342D01*
G01X2739027Y357144D02*
X2744185D01*
G01Y356606D02*
X2739027D01*
G01D02*
Y357144D01*
G01X2734342Y360236D02*
Y355315D01*
G01X2732374Y364153D02*
Y355315D01*
G01X2736862Y368346D02*
X2738909D01*
G01X2733712D02*
X2735759D01*
G01X2727413D02*
X2729460D01*
G01X2730563D02*
X2732610D01*
G01X2732374Y366909D02*
X2730799D01*
G01X2729224D02*
X2727649D01*
G01X2735523D02*
X2733948D01*
G01X2738673D02*
X2737098D01*
G01X2737393Y368878D02*
X2736862Y368346D01*
G01X2734244Y368878D02*
X2733712Y368346D01*
G01X2731094Y368878D02*
X2730563Y368346D01*
G01X2727945Y368878D02*
X2727413Y368346D01*
G01X2738378Y368878D02*
X2738909Y368346D01*
G01X2735228Y368878D02*
X2735759Y368346D01*
G01X2732078Y368878D02*
X2732610Y368346D01*
G01X2728929Y368878D02*
X2729460Y368346D01*
G01X2738909D02*
Y397441D01*
G01X2738830Y364153D02*
Y397756D01*
G01X2738673Y366909D02*
Y364153D01*
G01X2737098Y366909D02*
Y364153D01*
G01X2736941D02*
Y397756D01*
G01X2736862Y397441D02*
Y368346D01*
G01X2735759D02*
Y397441D01*
G01X2735681Y397756D02*
Y364153D01*
G01X2735523Y366909D02*
Y364153D01*
G01X2733948Y366909D02*
Y364153D01*
G01X2733791Y397756D02*
Y364153D01*
G01X2733712Y397441D02*
Y368346D01*
G01X2732610D02*
Y397441D01*
G01X2732531Y397756D02*
Y364153D01*
G01X2732374Y366909D02*
Y381346D01*
G01Y366909D02*
Y364153D01*
G01X2730799Y366909D02*
Y364153D01*
G01X2730641Y397756D02*
Y364153D01*
G01X2730563Y397441D02*
Y368346D01*
G01X2729460D02*
Y397441D01*
G01X2729382Y397756D02*
Y364153D01*
G01X2729224Y366909D02*
Y364153D01*
G01X2727649Y366909D02*
Y364153D01*
G01X2727492Y397756D02*
Y364153D01*
G01X2727413Y397441D02*
Y368346D01*
G01X2742209Y355747D02*
X2741770Y355639D01*
G01X2742209Y355209D02*
X2741770Y355102D01*
G01X2743087Y352953D02*
X2742648Y352846D01*
G01X2743417Y352524D02*
X2742648Y352309D01*
G01X2741770Y355639D02*
X2741441Y355532D01*
G01X2742209Y355747D02*
X2742648D01*
G01X2742209Y355209D02*
X2742648D01*
G01Y352846D02*
X2742209D01*
G01X2742648Y352309D02*
X2742209D01*
G01X2741770Y355102D02*
X2741441Y354887D01*
G01Y355532D02*
X2741112Y355317D01*
G01X2741441Y354887D02*
X2741222Y354672D01*
G01X2741112Y355317D02*
X2740893Y355102D01*
G01X2743417Y355532D02*
X2742648Y355747D01*
G01X2743087Y355102D02*
X2742648Y355209D01*
G01X2742209Y352846D02*
X2741770Y352953D01*
G01X2742209Y352309D02*
X2741770Y352416D01*
G01D02*
X2741441Y352524D01*
G01X2740893Y355102D02*
X2740783Y354887D01*
G01X2741441Y353168D02*
X2741770Y352953D01*
G01X2741112Y352738D02*
X2741441Y352524D01*
G01X2741222Y353383D02*
X2741441Y353168D01*
G01X2740893Y352953D02*
X2741112Y352738D01*
G01X2741222Y354672D02*
X2741112Y354243D01*
G01X2740783Y354887D02*
X2740673Y354457D01*
G01X2741112Y353813D02*
Y354243D01*
G01X2740673Y353598D02*
Y354457D01*
G01X2741112Y353813D02*
X2741222Y353383D01*
G01X2740673Y353598D02*
X2740783Y353168D01*
G01D02*
X2740893Y352953D01*
G01X2740011Y368346D02*
X2742059D01*
G01X2741822Y366909D02*
X2740248D01*
G01X2742472Y365137D02*
X2747728D01*
G01X2740543Y368878D02*
X2740011Y368346D01*
G01X2741527Y368878D02*
X2742059Y368346D01*
G01X2742472Y379901D02*
Y364153D01*
G01X2742059Y368346D02*
Y397441D01*
G01X2741822Y366909D02*
Y364153D01*
G01X2740248Y366909D02*
Y364153D01*
G01X2740090D02*
Y397756D01*
G01X2740011Y397441D02*
Y368346D01*
G01X2739659Y369964D02*
X2739261D01*
G01X2736510D02*
X2736111D01*
G01X2733360D02*
X2732962D01*
G01X2730211D02*
X2729812D01*
G01X2727061D02*
X2726663D01*
G01X2731094Y378523D02*
X2730563D01*
G01X2729460D02*
X2728929D01*
G01X2727945D02*
X2727413D01*
G01X2735759D02*
X2735228D01*
G01X2734244D02*
X2733712D01*
G01X2732610D02*
X2732078D01*
G01X2738909D02*
X2738378D01*
G01X2737393D02*
X2736862D01*
G01X2737597Y376504D02*
X2738174D01*
G01X2731298D02*
X2731874D01*
G01X2734448D02*
X2735024D01*
G01X2728148D02*
X2728725D01*
G01X2727141Y376263D02*
X2726583D01*
G01X2730291D02*
X2729733D01*
G01X2733440D02*
X2732882D01*
G01X2736590D02*
X2736032D01*
G01X2739739D02*
X2739182D01*
G01X2728830Y376160D02*
X2728043D01*
G01X2731980D02*
X2731193D01*
G01X2735130D02*
X2734342D01*
G01X2738279D02*
X2737492D01*
G01X2736062Y376064D02*
X2736559D01*
G01X2739211D02*
X2739709D01*
G01X2732912D02*
X2733410D01*
G01X2726613D02*
X2727111D01*
G01X2729763D02*
X2730260D01*
G01X2727106Y376039D02*
X2726618D01*
G01X2730255D02*
X2729768D01*
G01X2733405D02*
X2732917D01*
G01X2736554D02*
X2736067D01*
G01X2739704D02*
X2739217D01*
G01X2735917Y376006D02*
X2736704D01*
G01X2739067D02*
X2739854D01*
G01X2732767D02*
X2733555D01*
G01X2726468D02*
X2727256D01*
G01X2729618D02*
X2730405D01*
G01X2727256Y375823D02*
X2726468D01*
G01X2730405D02*
X2729618D01*
G01X2733555D02*
X2732767D01*
G01X2736704D02*
X2735917D01*
G01X2739854D02*
X2739067D01*
G01X2735917Y375682D02*
X2736704D01*
G01X2739067D02*
X2739854D01*
G01X2732767D02*
X2733555D01*
G01X2726468D02*
X2727256D01*
G01X2729618D02*
X2730405D01*
G01X2727256Y375465D02*
X2726468D01*
G01X2730405D02*
X2729618D01*
G01X2733555D02*
X2732767D01*
G01X2736704D02*
X2735917D01*
G01X2739854D02*
X2739067D01*
G01X2736078Y375165D02*
X2736543D01*
G01X2739228D02*
X2739693D01*
G01X2732928D02*
X2733394D01*
G01X2726629D02*
X2727095D01*
G01X2729779D02*
X2730244D01*
G01X2737492Y375135D02*
X2738279D01*
G01X2731193D02*
X2731980D01*
G01X2734342D02*
X2735130D01*
G01X2728043D02*
X2728830D01*
G01X2728716Y374710D02*
X2728157D01*
G01X2731865D02*
X2731307D01*
G01X2735015D02*
X2734457D01*
G01X2738165D02*
X2737606D01*
G01X2738378Y372618D02*
X2738909D01*
G01X2736862D02*
X2737393D01*
G01X2735228D02*
X2735759D01*
G01X2733712D02*
X2734244D01*
G01X2732078D02*
X2732610D01*
G01X2730563D02*
X2731094D01*
G01X2728929D02*
X2729460D01*
G01X2727413D02*
X2727945D01*
G01X2737492Y371785D02*
X2738279D01*
G01X2731193D02*
X2731980D01*
G01X2734342D02*
X2735130D01*
G01X2728043D02*
X2728830D01*
G01X2727256Y371314D02*
X2726468D01*
G01X2730405D02*
X2729618D01*
G01X2733555D02*
X2732767D01*
G01X2736704D02*
X2735917D01*
G01X2739854D02*
X2739067D01*
G01X2728830Y370502D02*
X2728043D01*
G01X2731980D02*
X2731193D01*
G01X2735130D02*
X2734342D01*
G01X2738279D02*
X2737492D01*
G01X2735974Y370476D02*
X2736647D01*
G01X2739124D02*
X2739797D01*
G01X2732825D02*
X2733498D01*
G01X2726526D02*
X2727198D01*
G01X2729675D02*
X2730348D01*
G01X2737492Y370252D02*
X2738279D01*
G01X2731193D02*
X2731980D01*
G01X2734342D02*
X2735130D01*
G01X2728043D02*
X2728830D01*
G01X2736045Y370212D02*
X2736576D01*
G01X2739195D02*
X2739726D01*
G01X2732895D02*
X2733427D01*
G01X2726596D02*
X2727128D01*
G01X2729746D02*
X2730277D01*
G01X2727126Y370207D02*
X2726598D01*
G01X2730276D02*
X2729747D01*
G01X2733426D02*
X2732897D01*
G01X2736575D02*
X2736046D01*
G01X2739725D02*
X2739196D01*
G01X2728830Y370198D02*
X2728043D01*
G01X2731980D02*
X2731193D01*
G01X2735130D02*
X2734342D01*
G01X2738279D02*
X2737492D01*
G01X2728830Y370171D02*
X2728043D01*
G01X2731980D02*
X2731193D01*
G01X2735130D02*
X2734342D01*
G01X2738279D02*
X2737492D01*
G01X2736114Y369955D02*
X2736507D01*
G01X2739263D02*
X2739657D01*
G01X2732964D02*
X2733358D01*
G01X2726665D02*
X2727059D01*
G01X2729815D02*
X2730208D01*
G01X2737393Y368878D02*
X2738378D01*
G01X2734244D02*
X2735228D01*
G01X2731094D02*
X2732078D01*
G01X2727945D02*
X2728929D01*
G01X2728830Y370324D02*
X2728043Y370323D01*
G01X2731980Y370324D02*
X2731193Y370323D01*
G01X2735130Y370324D02*
X2734342Y370323D01*
G01X2738279Y370324D02*
X2737492Y370323D01*
G01X2736507Y369955D02*
X2736704Y370689D01*
G01X2733358Y369955D02*
X2733555Y370689D01*
G01X2730208Y369955D02*
X2730405Y370689D01*
G01X2727059Y369955D02*
X2727256Y370689D01*
G01X2736559Y376064D02*
X2736554Y376039D01*
G01X2733410Y376064D02*
X2733405Y376039D01*
G01X2730260Y376064D02*
X2730255Y376039D01*
G01X2727111Y376064D02*
X2727106Y376039D01*
G01X2738174Y376504D02*
X2738279Y377021D01*
G01X2735024Y376504D02*
X2735130Y377021D01*
G01X2731874Y376504D02*
X2731980Y377021D01*
G01X2728725Y376504D02*
X2728830Y377021D01*
G01X2737606Y374710D02*
X2737492Y374117D01*
G01X2734457Y374710D02*
X2734342Y374117D01*
G01X2731307Y374710D02*
X2731193Y374117D01*
G01X2728157Y374710D02*
X2728043Y374117D01*
G01X2739067Y374267D02*
X2739228Y375165D01*
G01X2735917Y374267D02*
X2736078Y375165D01*
G01X2732767Y374267D02*
X2732928Y375165D01*
G01X2729618Y374267D02*
X2729779Y375165D01*
G01X2726468Y374267D02*
X2726629Y375165D01*
G01X2736704Y377419D02*
X2736590Y376263D01*
G01X2733555Y377419D02*
X2733440Y376263D01*
G01X2730405Y377419D02*
X2730291Y376263D01*
G01X2727256Y377419D02*
X2727141Y376263D01*
G01X2739067Y370689D02*
Y407972D01*
G01X2736543Y375165D02*
X2736704Y374267D01*
G01X2733394Y375165D02*
X2733555Y374267D01*
G01X2730244Y375165D02*
X2730405Y374267D01*
G01X2727095Y375165D02*
X2727256Y374267D01*
G01X2738279Y374117D02*
X2738165Y374710D01*
G01X2735130Y374117D02*
X2735015Y374710D01*
G01X2731980Y374117D02*
X2731865Y374710D01*
G01X2728830Y374117D02*
X2728716Y374710D01*
G01X2737597Y376504D02*
X2737492Y377021D01*
G01X2734448Y376504D02*
X2734342Y377021D01*
G01X2731298Y376504D02*
X2731193Y377021D01*
G01X2728148Y376504D02*
X2728043Y377021D01*
G01X2739217Y376039D02*
X2739211Y376064D01*
G01X2736067Y376039D02*
X2736062Y376064D01*
G01X2732917Y376039D02*
X2732912Y376064D01*
G01X2729768Y376039D02*
X2729763Y376064D01*
G01X2726618Y376039D02*
X2726613Y376064D01*
G01X2739263Y369955D02*
X2739067Y370689D01*
G01X2736114Y369955D02*
X2735917Y370689D01*
G01X2732964Y369955D02*
X2732767Y370689D01*
G01X2729815Y369955D02*
X2729618Y370689D01*
G01X2726665Y369955D02*
X2726468Y370689D01*
G01X2738378Y378523D02*
Y396909D01*
G01Y368878D02*
Y372618D01*
G01X2738279Y370171D02*
Y398326D01*
G01X2737492Y370171D02*
Y398326D01*
G01X2737393Y372618D02*
Y368878D01*
G01Y396909D02*
Y378523D01*
G01X2736704Y370689D02*
Y407972D01*
G01X2735917Y370689D02*
Y407972D01*
G01X2735228Y378523D02*
Y396909D01*
G01Y368878D02*
Y372618D01*
G01X2735130Y398326D02*
Y370171D01*
G01X2734342D02*
Y398326D01*
G01X2734244Y372618D02*
Y368878D01*
G01Y396909D02*
Y378523D01*
G01X2733555Y370689D02*
Y407972D01*
G01X2732767Y370689D02*
Y407972D01*
G01X2732078Y378523D02*
Y396909D01*
G01Y368878D02*
Y372618D01*
G01X2731980Y398326D02*
Y370171D01*
G01X2731193D02*
Y398326D01*
G01X2731094Y372618D02*
Y368878D01*
G01Y396909D02*
Y378523D01*
G01X2730405Y370689D02*
Y407972D01*
G01X2729618Y370689D02*
Y407972D01*
G01X2728929Y378523D02*
Y396909D01*
G01Y368878D02*
Y372618D01*
G01X2728830Y398326D02*
Y370171D01*
G01X2728043D02*
Y398326D01*
G01X2727945Y372618D02*
Y368878D01*
G01Y396909D02*
Y378523D01*
G01X2727256Y370689D02*
Y407972D01*
G01X2726468Y370689D02*
Y407972D01*
G01X2739182Y376263D02*
X2739067Y377419D01*
G01X2736032Y376263D02*
X2735917Y377419D01*
G01X2732882Y376263D02*
X2732767Y377419D01*
G01X2729733Y376263D02*
X2729618Y377419D01*
G01X2726583Y376263D02*
X2726468Y377419D01*
G01X2742472Y374411D02*
G03Y376730I2500J1159D01*
G01X2748043Y375571D02*
G03I-3071J0D01*
G01X2747728Y379114D02*
X2742472D01*
G01X2740543Y378523D02*
X2740011D01*
G01X2742059D02*
X2741527D01*
G01X2740747Y376504D02*
X2741323D01*
G01X2741429Y376160D02*
X2740641D01*
G01Y375135D02*
X2741429D01*
G01X2741314Y374710D02*
X2740756D01*
G01X2747728Y373602D02*
X2742472D01*
G01X2741527Y372618D02*
X2742059D01*
G01X2740011D02*
X2740543D01*
G01X2740641Y371785D02*
X2741429D01*
G01X2747728Y371240D02*
X2742472D01*
G01X2741429Y370502D02*
X2740641D01*
G01X2742472Y370452D02*
X2747728D01*
G01X2740641Y370252D02*
X2741429D01*
G01Y370198D02*
X2740641D01*
G01X2741429Y370171D02*
X2740641D01*
G01X2740543Y368878D02*
X2741527D01*
G01X2741429Y370324D02*
X2740641Y370323D01*
G01X2739657Y369955D02*
X2739854Y370689D01*
G01X2739709Y376064D02*
X2739704Y376039D01*
G01X2741323Y376504D02*
X2741429Y377021D01*
G01X2740756Y374710D02*
X2740641Y374117D01*
G01X2739854Y377419D02*
X2739739Y376263D01*
G01X2741527Y378523D02*
Y396909D01*
G01Y368878D02*
Y372618D01*
G01X2741429Y398326D02*
Y370171D01*
G01X2740641D02*
Y398326D01*
G01X2740543Y372618D02*
Y368878D01*
G01Y396909D02*
Y378523D01*
G01X2739854Y370689D02*
Y407972D01*
G01X2739693Y375165D02*
X2739854Y374267D01*
G01X2741429Y374117D02*
X2741314Y374710D01*
G01X2740747Y376504D02*
X2740641Y377021D01*
G01X2747728Y379901D02*
X2742472D01*
G01X2736862Y394074D02*
X2737393Y394294D01*
G01X2733712Y394074D02*
X2734244Y394294D01*
G01X2730563Y394074D02*
X2731094Y394294D01*
G01X2727413Y394074D02*
X2727945Y394294D01*
G01X2728830Y394901D02*
X2728043D01*
G01X2731980D02*
X2731193D01*
G01X2735130D02*
X2734342D01*
G01X2738279D02*
X2737492D01*
G01X2728830Y394665D02*
X2728043D01*
G01X2731980D02*
X2731193D01*
G01X2735130D02*
X2734342D01*
G01X2738279D02*
X2737492D01*
G01X2735917Y394626D02*
X2736704D01*
G01X2739067D02*
X2739854D01*
G01X2732767D02*
X2733555D01*
G01X2726468D02*
X2727256D01*
G01X2729618D02*
X2730405D01*
G01X2735917Y394586D02*
X2736704D01*
G01X2739067D02*
X2739854D01*
G01X2732767D02*
X2733555D01*
G01X2726468D02*
X2727256D01*
G01X2729618D02*
X2730405D01*
G01X2728830Y394488D02*
X2728043D01*
G01X2731980D02*
X2731193D01*
G01X2735130D02*
X2734342D01*
G01X2738279D02*
X2737492D01*
G01X2727256Y394347D02*
X2726468D01*
G01X2730405D02*
X2729618D01*
G01X2733555D02*
X2732767D01*
G01X2736704D02*
X2735917D01*
G01X2739854D02*
X2739067D01*
G01X2737492Y394311D02*
X2738279D01*
G01X2731193D02*
X2731980D01*
G01X2734342D02*
X2735130D01*
G01X2728043D02*
X2728830D01*
G01Y394074D02*
X2728043D01*
G01X2730563D02*
X2729460D01*
G01X2731980D02*
X2731193D01*
G01X2735130D02*
X2734342D01*
G01X2733712D02*
X2732610D01*
G01X2738279D02*
X2737492D01*
G01X2736862D02*
X2735759D01*
G01X2740011D02*
X2738909D01*
G01X2737393Y394055D02*
X2738378D01*
G01X2731094D02*
X2732078D01*
G01X2734244D02*
X2735228D01*
G01X2727945D02*
X2728929D01*
G01X2737492Y393996D02*
X2738279D01*
G01X2731193D02*
X2731980D01*
G01X2734342D02*
X2735130D01*
G01X2728043D02*
X2728830D01*
G01X2728929Y393740D02*
X2727945D01*
G01X2732078D02*
X2731094D01*
G01X2735228D02*
X2734244D01*
G01X2738378D02*
X2737393D01*
G01X2737492Y393702D02*
X2738279D01*
G01X2731193D02*
X2731980D01*
G01X2734342D02*
X2735130D01*
G01X2728043D02*
X2728830D01*
G01Y393681D02*
X2728043D01*
G01X2731980D02*
X2731193D01*
G01X2735130D02*
X2734342D01*
G01X2738279D02*
X2737492D01*
G01X2728821Y393641D02*
X2728052D01*
G01X2731971D02*
X2731202D01*
G01X2735120D02*
X2734351D01*
G01X2738270D02*
X2737501D01*
G01X2728830Y393629D02*
X2728043D01*
G01X2731980D02*
X2731193D01*
G01X2735130D02*
X2734342D01*
G01X2738279D02*
X2737492D01*
G01Y393594D02*
X2738279D01*
G01X2731193D02*
X2731980D01*
G01X2734342D02*
X2735130D01*
G01X2728043D02*
X2728830D01*
G01X2737604Y393539D02*
X2738168D01*
G01X2731304D02*
X2731869D01*
G01X2734454D02*
X2735018D01*
G01X2728155D02*
X2728719D01*
G01X2735917Y393526D02*
X2736704D01*
G01X2739067D02*
X2739854D01*
G01X2732767D02*
X2733555D01*
G01X2726468D02*
X2727256D01*
G01X2729618D02*
X2730405D01*
G01X2737492Y393514D02*
X2738279D01*
G01X2731193D02*
X2731980D01*
G01X2734342D02*
X2735130D01*
G01X2728043D02*
X2728830D01*
G01X2727256Y393408D02*
X2726468D01*
G01X2730405D02*
X2729618D01*
G01X2733555D02*
X2732767D01*
G01X2736704D02*
X2735917D01*
G01X2739854D02*
X2739067D01*
G01X2730563Y393287D02*
X2729460D01*
G01X2733712D02*
X2732610D01*
G01X2736862D02*
X2735759D01*
G01X2740011D02*
X2738909D01*
G01X2728633Y393283D02*
X2728240D01*
G01X2731783D02*
X2731389D01*
G01X2734933D02*
X2734539D01*
G01X2738082D02*
X2737689D01*
G01X2735228Y392500D02*
X2737393D01*
G01X2738378D02*
X2740543D01*
G01X2732078D02*
X2734244D01*
G01X2728929D02*
X2731094D01*
G01X2735917Y392254D02*
X2736704D01*
G01X2739067D02*
X2739854D01*
G01X2732767D02*
X2733555D01*
G01X2726468D02*
X2727256D01*
G01X2729618D02*
X2730405D01*
G01X2735917Y392231D02*
X2736704D01*
G01X2739067D02*
X2739854D01*
G01X2732767D02*
X2733555D01*
G01X2726468D02*
X2727256D01*
G01X2729618D02*
X2730405D01*
G01X2727256Y391977D02*
X2726468D01*
G01X2730405D02*
X2729618D01*
G01X2733555D02*
X2732767D01*
G01X2736704D02*
X2735917D01*
G01X2739854D02*
X2739067D01*
G01X2727256Y391318D02*
X2726468D01*
G01X2730405D02*
X2729618D01*
G01X2733555D02*
X2732767D01*
G01X2736704D02*
X2735917D01*
G01X2739854D02*
X2739067D01*
G01X2737689Y391126D02*
X2738082D01*
G01X2731389D02*
X2731783D01*
G01X2734539D02*
X2734933D01*
G01X2728240D02*
X2728633D01*
G01X2728719Y390870D02*
X2728155D01*
G01X2731869D02*
X2731304D01*
G01X2735018D02*
X2734454D01*
G01X2738168D02*
X2737604D01*
G01X2737501Y390768D02*
X2738270D01*
G01X2731202D02*
X2731971D01*
G01X2734351D02*
X2735120D01*
G01X2728052D02*
X2728821D01*
G01X2727256Y390728D02*
X2726468D01*
G01X2730405D02*
X2729618D01*
G01X2728929D02*
X2727945D01*
G01X2733555D02*
X2732767D01*
G01X2732078D02*
X2731094D01*
G01X2735228D02*
X2734244D01*
G01X2736704D02*
X2735917D01*
G01X2739854D02*
X2739067D01*
G01X2738378D02*
X2737393D01*
G01X2728830Y390515D02*
X2728043D01*
G01X2731980D02*
X2731193D01*
G01X2735130D02*
X2734342D01*
G01X2738279D02*
X2737492D01*
G01X2737393Y390413D02*
X2738378D01*
G01X2731094D02*
X2732078D01*
G01X2734244D02*
X2735228D01*
G01X2727945D02*
X2728929D01*
G01X2727256Y390137D02*
X2726468D01*
G01X2730405D02*
X2729618D01*
G01X2733555D02*
X2732767D01*
G01X2736704D02*
X2735917D01*
G01X2739854D02*
X2739067D01*
G01X2737393Y390098D02*
X2738378D01*
G01X2731094D02*
X2732078D01*
G01X2734244D02*
X2735228D01*
G01X2727945D02*
X2728929D01*
G01X2737492Y390082D02*
X2738279D01*
G01X2731193D02*
X2731980D01*
G01X2734342D02*
X2735130D01*
G01X2728043D02*
X2728830D01*
G01X2737492Y389858D02*
X2738279D01*
G01X2731193D02*
X2731980D01*
G01X2734342D02*
X2735130D01*
G01X2728043D02*
X2728830D01*
G01X2735917Y389547D02*
X2736704D01*
G01X2739067D02*
X2739854D01*
G01X2732767D02*
X2733555D01*
G01X2726468D02*
X2727256D01*
G01X2729618D02*
X2730405D01*
G01X2728830Y389425D02*
X2728043D01*
G01X2731980D02*
X2731193D01*
G01X2735130D02*
X2734342D01*
G01X2738279D02*
X2737492D01*
G01X2727256Y388956D02*
X2726468D01*
G01X2730405D02*
X2729618D01*
G01X2733555D02*
X2732767D01*
G01X2736704D02*
X2735917D01*
G01X2739854D02*
X2739067D01*
G01X2738378Y394294D02*
X2738909Y394074D01*
G01X2737501Y390768D02*
X2737604Y390870D01*
G01X2738168Y393539D02*
X2738270Y393641D01*
G01X2734351Y390768D02*
X2734454Y390870D01*
G01X2736862Y393287D02*
X2737393Y393818D01*
G01D02*
X2736862Y393287D01*
G01X2735018Y393539D02*
X2735120Y393641D01*
G01X2731202Y390768D02*
X2731304Y390870D01*
G01X2733712Y393287D02*
X2734244Y393818D01*
G01D02*
X2733712Y393287D01*
G01X2731869Y393539D02*
X2731971Y393641D01*
G01X2728052Y390768D02*
X2728155Y390870D01*
G01X2730563Y393287D02*
X2731094Y393818D01*
G01D02*
X2730563Y393287D01*
G01X2728719Y393539D02*
X2728821Y393641D01*
G01X2727413Y393287D02*
X2727945Y393818D01*
G01D02*
X2727413Y393287D01*
G01X2735228Y394294D02*
X2735759Y394074D01*
G01X2732078Y394294D02*
X2732610Y394074D01*
G01X2728929Y394294D02*
X2729460Y394074D01*
G01X2738378Y393818D02*
X2738909Y393287D01*
G01D02*
X2738378Y393818D01*
G01X2737604Y393539D02*
X2737501Y393641D01*
G01X2735228Y393818D02*
X2735759Y393287D01*
G01D02*
X2735228Y393818D01*
G01X2738168Y390870D02*
X2738270Y390768D01*
G01X2734454Y393539D02*
X2734351Y393641D01*
G01X2732078Y393818D02*
X2732610Y393287D01*
G01D02*
X2732078Y393818D01*
G01X2735018Y390870D02*
X2735120Y390768D01*
G01X2731304Y393539D02*
X2731202Y393641D01*
G01X2728929Y393818D02*
X2729460Y393287D01*
G01D02*
X2728929Y393818D01*
G01X2731869Y390870D02*
X2731971Y390768D01*
G01X2728155Y393539D02*
X2728052Y393641D01*
G01X2728719Y390870D02*
X2728821Y390768D01*
G01X2738968Y397618D02*
Y388248D01*
G01X2738082Y393283D02*
Y391126D01*
G01X2737689D02*
Y393283D01*
G01X2736803Y397618D02*
Y388248D01*
G01X2735819Y397618D02*
Y388248D01*
G01X2734933Y393283D02*
Y391126D01*
G01X2734539D02*
Y393283D01*
G01X2733653Y397618D02*
Y388248D01*
G01X2732669Y397618D02*
Y388248D01*
G01X2731783Y393283D02*
Y391126D01*
G01X2731389D02*
Y393283D01*
G01X2730504Y397618D02*
Y388248D01*
G01X2729519Y397618D02*
Y388248D01*
G01X2728633Y393283D02*
Y391126D01*
G01X2728240D02*
Y393283D01*
G01X2727354Y397618D02*
Y388248D01*
G01X2727256Y398602D02*
X2726468D01*
G01X2730405D02*
X2729618D01*
G01X2733555D02*
X2732767D01*
G01X2736704D02*
X2735917D01*
G01X2739854D02*
X2739067D01*
G01X2728830Y398326D02*
X2728043D01*
G01X2731980D02*
X2731193D01*
G01X2735130D02*
X2734342D01*
G01X2738279D02*
X2737492D01*
G01X2728830Y397736D02*
X2728043D01*
G01X2731980D02*
X2731193D01*
G01X2735130D02*
X2734342D01*
G01X2738279D02*
X2737492D01*
G01X2738968Y397618D02*
X2739952D01*
G01X2730504D02*
X2729519D01*
G01X2733653D02*
X2732669D01*
G01X2736803D02*
X2735819D01*
G01X2729460Y397441D02*
X2727413D01*
G01X2732610D02*
X2730563D01*
G01X2735759D02*
X2733712D01*
G01X2738909D02*
X2736862D01*
G01X2727256Y397421D02*
X2726468D01*
G01X2730405D02*
X2729618D01*
G01X2733555D02*
X2732767D01*
G01X2736704D02*
X2735917D01*
G01X2739854D02*
X2739067D01*
G01X2728929Y396909D02*
X2727945D01*
G01X2732078D02*
X2731094D01*
G01X2735228D02*
X2734244D01*
G01X2738378D02*
X2737393D01*
G01X2728830Y396830D02*
X2728043D01*
G01X2731980D02*
X2731193D01*
G01X2735130D02*
X2734342D01*
G01X2738279D02*
X2737492D01*
G01X2735917Y396633D02*
X2736704D01*
G01X2739067D02*
X2739854D01*
G01X2732767D02*
X2733555D01*
G01X2726468D02*
X2727256D01*
G01X2729618D02*
X2730405D01*
G01X2737492Y396594D02*
X2738279D01*
G01X2731193D02*
X2731980D01*
G01X2734342D02*
X2735130D01*
G01X2728043D02*
X2728830D01*
G01X2727256Y396515D02*
X2726468D01*
G01X2730405D02*
X2729618D01*
G01X2733555D02*
X2732767D01*
G01X2736704D02*
X2735917D01*
G01X2739854D02*
X2739067D01*
G01X2728830Y396417D02*
X2728043D01*
G01X2731980D02*
X2731193D01*
G01X2735130D02*
X2734342D01*
G01X2738279D02*
X2737492D01*
G01X2730799Y396043D02*
X2729224D01*
G01X2728830D02*
X2728043D01*
G01X2737098D02*
X2735523D01*
G01X2733948D02*
X2732374D01*
G01X2731980D02*
X2731193D01*
G01X2735130D02*
X2734342D01*
G01X2740248D02*
X2738673D01*
G01X2738279D02*
X2737492D01*
G01X2728830Y396004D02*
X2728043D01*
G01X2731980D02*
X2731193D01*
G01X2735130D02*
X2734342D01*
G01X2738279D02*
X2737492D01*
G01X2738378Y396909D02*
X2738909Y397441D01*
G01X2737196Y398011D02*
X2736803Y397618D01*
G01X2735228Y396909D02*
X2735759Y397441D01*
G01X2734047Y398011D02*
X2733653Y397618D01*
G01X2732078Y396909D02*
X2732610Y397441D01*
G01X2730897Y398011D02*
X2730504Y397618D01*
G01X2728929Y396909D02*
X2729460Y397441D01*
G01X2727748Y398011D02*
X2727354Y397618D01*
G01X2738574Y398011D02*
X2738968Y397618D01*
G01X2736862Y397441D02*
X2737393Y396909D01*
G01X2735425Y398011D02*
X2735819Y397618D01*
G01X2733712Y397441D02*
X2734244Y396909D01*
G01X2732275Y398011D02*
X2732669Y397618D01*
G01X2730563Y397441D02*
X2731094Y396909D01*
G01X2729126Y398011D02*
X2729519Y397618D01*
G01X2727413Y397441D02*
X2727945Y396909D01*
G01X2738673Y398011D02*
Y396043D01*
G01X2737098Y398011D02*
Y396043D01*
G01X2735523Y398011D02*
Y396043D01*
G01X2733948Y398011D02*
Y396043D01*
G01X2732374Y398011D02*
Y396043D01*
G01X2730799Y398011D02*
Y396043D01*
G01X2729224Y398011D02*
Y396043D01*
G01X2727649Y398011D02*
Y396043D01*
G01X2740011Y394074D02*
X2740543Y394294D01*
G01X2741429Y394901D02*
X2740641D01*
G01X2741429Y394665D02*
X2740641D01*
G01X2741429Y394488D02*
X2740641D01*
G01Y394311D02*
X2741429D01*
G01Y394074D02*
X2740641D01*
G01X2747728D02*
X2742059D01*
G01X2740543Y394055D02*
X2741527D01*
G01X2740641Y393996D02*
X2741429D01*
G01X2741527Y393740D02*
X2740543D01*
G01X2740641Y393702D02*
X2741429D01*
G01Y393681D02*
X2740641D01*
G01X2741420Y393641D02*
X2740650D01*
G01X2741429Y393629D02*
X2740641D01*
G01Y393594D02*
X2741429D01*
G01X2740753Y393539D02*
X2741317D01*
G01X2740641Y393514D02*
X2741429D01*
G01X2747728Y393287D02*
X2742059D01*
G01X2741232Y393283D02*
X2740838D01*
G01X2741527Y392500D02*
X2747728D01*
G01X2740838Y391126D02*
X2741232D01*
G01X2741317Y390870D02*
X2740753D01*
G01X2740650Y390768D02*
X2741420D01*
G01X2741527Y390728D02*
X2740543D01*
G01X2741429Y390515D02*
X2740641D01*
G01X2740543Y390413D02*
X2741527D01*
G01X2740543Y390098D02*
X2741527D01*
G01X2740641Y390082D02*
X2741429D01*
G01X2740641Y389858D02*
X2741429D01*
G01Y389425D02*
X2740641D01*
G01X2741527Y394294D02*
X2742059Y394074D01*
G01X2740650Y390768D02*
X2740753Y390870D01*
G01X2741317Y393539D02*
X2741420Y393641D01*
G01X2740011Y393287D02*
X2740543Y393818D01*
G01D02*
X2740011Y393287D01*
G01X2741527Y393818D02*
X2742059Y393287D01*
G01D02*
X2741527Y393818D01*
G01X2740753Y393539D02*
X2740650Y393641D01*
G01X2741317Y390870D02*
X2741420Y390768D01*
G01X2741232Y393283D02*
Y391126D01*
G01X2740838D02*
Y393283D01*
G01X2739952Y397618D02*
Y388248D01*
G01X2741429Y398326D02*
X2740641D01*
G01X2741429Y397736D02*
X2740641D01*
G01X2742059Y397441D02*
X2740011D01*
G01X2741527Y396909D02*
X2740543D01*
G01X2741429Y396830D02*
X2740641D01*
G01Y396594D02*
X2741429D01*
G01Y396417D02*
X2740641D01*
G01X2741429Y396043D02*
X2740641D01*
G01X2741429Y396004D02*
X2740641D01*
G01X2741527Y396909D02*
X2742059Y397441D01*
G01X2740346Y398011D02*
X2739952Y397618D01*
G01X2740011Y397441D02*
X2740543Y396909D01*
G01X2740248Y398011D02*
Y396043D01*
G01X2727256Y407972D02*
X2726468D01*
G01X2730405D02*
X2729618D01*
G01X2733555D02*
X2732767D01*
G01X2736704D02*
X2735917D01*
G01X2739854D02*
X2739067D01*
G01X2727256Y407381D02*
X2726468D01*
G01X2730405D02*
X2729618D01*
G01X2733555D02*
X2732767D01*
G01X2736704D02*
X2735917D01*
G01X2739854D02*
X2739067D01*
G01X2735917Y406476D02*
X2736704D01*
G01X2739067D02*
X2739854D01*
G01X2732767D02*
X2733555D01*
G01X2726468D02*
X2727256D01*
G01X2729618D02*
X2730405D01*
G01X2737413Y405885D02*
X2738358D01*
G01X2734263D02*
X2735208D01*
G01X2731114D02*
X2732059D01*
G01X2727964D02*
X2728909D01*
G01X2727256D02*
X2726468D01*
G01X2730405D02*
X2729618D01*
G01X2733555D02*
X2732767D01*
G01X2736704D02*
X2735917D01*
G01X2739854D02*
X2739067D01*
G01X2727256Y405177D02*
X2726468D01*
G01X2730405D02*
X2729618D01*
G01X2733555D02*
X2732767D01*
G01X2736704D02*
X2735917D01*
G01X2739854D02*
X2739067D01*
G01X2727256Y404232D02*
X2726468D01*
G01X2730405D02*
X2729618D01*
G01X2733555D02*
X2732767D01*
G01X2736704D02*
X2735917D01*
G01X2739854D02*
X2739067D01*
G01X2738948Y403641D02*
X2739972D01*
G01X2735799D02*
X2736822D01*
G01X2732649D02*
X2733673D01*
G01X2729500D02*
X2730523D01*
G01X2735917Y403051D02*
X2736704D01*
G01X2739067D02*
X2739854D01*
G01X2732767D02*
X2733555D01*
G01X2726468D02*
X2727256D01*
G01X2729618D02*
X2730405D01*
G01X2737413Y405885D02*
X2736822Y405295D01*
G01X2734263Y405885D02*
X2733673Y405295D01*
G01X2731114Y405885D02*
X2730523Y405295D01*
G01X2727964Y405885D02*
X2727374Y405295D01*
G01X2738358Y405885D02*
X2738948Y405295D01*
G01X2735208Y405885D02*
X2735799Y405295D01*
G01X2732059Y405885D02*
X2732649Y405295D01*
G01X2728909Y405885D02*
X2729500Y405295D01*
G01X2738948D02*
Y403641D01*
G01X2736822D02*
Y405295D01*
G01X2735799D02*
Y403641D01*
G01X2733673D02*
Y405295D01*
G01X2732649D02*
Y403641D01*
G01X2730523D02*
Y405295D01*
G01X2729500D02*
Y403641D01*
G01X2727374D02*
Y405295D01*
G01X2740563Y405885D02*
X2747728D01*
G01X2740563D02*
X2739972Y405295D01*
G01Y403641D02*
Y405295D01*
G01X2741518Y809409D02*
Y814409D01*
G01X2736862Y821909D02*
G03I-2244J0D01*
G01X2735368Y822659D02*
X2733868D01*
G01Y821159D02*
X2735368D01*
G01X2733368Y820659D02*
X2735868D01*
G01X2733868Y822659D02*
X2733368Y823159D01*
G01X2735368Y821159D02*
X2735868Y820659D01*
G01X2738118Y815409D02*
Y838409D01*
G01X2735868Y820659D02*
Y823159D01*
G01X2735368Y821159D02*
Y822659D01*
G01X2733868D02*
Y821159D01*
G01X2733368Y823159D02*
Y820659D01*
G01X2731118Y838409D02*
Y815409D01*
G01X2728118D02*
Y838409D01*
G01X2735368Y822659D02*
X2735868Y823159D01*
G01X2733868Y821159D02*
X2733368Y820659D01*
G01X2735868Y823159D02*
X2733368D01*
G01X2746862Y821909D02*
G03I-2244J0D01*
G01X2741118Y838409D02*
Y815409D01*
G01X2736862Y831909D02*
G03I-2244J0D01*
G01X2735868Y833159D02*
X2733368D01*
G01X2735368Y832659D02*
X2733868D01*
G01Y831159D02*
X2735368D01*
G01X2733368Y830659D02*
X2735868D01*
G01X2733868Y832659D02*
X2733368Y833159D01*
G01X2735368Y831159D02*
X2735868Y830659D01*
G01D02*
Y833159D01*
G01X2735368Y831159D02*
Y832659D01*
G01X2733868D02*
Y831159D01*
G01X2733368Y833159D02*
Y830659D01*
G01X2735368Y832659D02*
X2735868Y833159D01*
G01X2733868Y831159D02*
X2733368Y830659D01*
G01X2746862Y831909D02*
G03I-2244J0D01*
G01X2763877Y-1201374D02*
G03I-6299J0D01*
G01Y-1138382D02*
G03I-6299J0D01*
G01X2748720Y-305311D02*
G03X2752657Y-301374I0J3937D01*
G01Y-271846D02*
Y-301374D01*
G01X2753770Y-291925D02*
X2756662D01*
G01X2757707D02*
X2760599D01*
G01X2757707Y-275389D02*
Y-291925D01*
G01X2756662D02*
Y-275389D01*
G01X2753770D02*
Y-291925D01*
G01X3032972Y-275389D02*
X2752657D01*
G01X2756662D02*
X2753770D01*
G01X2760599D02*
X2757707D01*
G01X3031003Y-269878D02*
X2754625D01*
G01D02*
X2752657Y-271846D01*
G01X2750090Y327460D02*
G03I-1575J0D01*
G01X2744185Y329637D02*
X2742868Y329207D01*
G01X2749007Y330019D02*
X2748023D01*
G01X2749007Y328838D02*
X2748023D01*
G01Y328733D02*
X2749007D01*
G01Y328661D02*
X2748023D01*
G01X2749007Y328437D02*
X2748023D01*
G01X2749007Y327086D02*
X2748023D01*
G01Y327074D02*
X2749007D01*
G01Y326778D02*
X2748023D01*
G01X2749007Y326673D02*
X2748023D01*
G01X2749007Y326496D02*
X2748023D01*
G01Y325492D02*
X2749007D01*
G01Y321653D02*
X2748023D01*
G01X2749007Y320866D02*
X2748023D01*
G01X2744185Y326629D02*
X2742868Y327058D01*
G01X2750878Y320885D02*
Y411437D01*
G01X2749007Y360236D02*
Y320866D01*
G01X2748023D02*
Y360313D01*
G01X2746547Y360236D02*
Y323622D01*
G01X2744185Y330282D02*
Y329637D01*
G01Y326629D02*
Y325984D01*
G01X2742868Y329207D02*
Y327058D01*
G01X2746702Y336533D02*
G03X2746554Y335330I696J-696D01*
G01X2746006Y337229D02*
G03X2745711Y334823I1392J-1392D01*
G01X2748128Y332711D02*
X2747284Y332204D01*
G01X2747114Y334399D02*
X2746270Y333892D01*
G01X2749007Y331023D02*
X2748023D01*
G01X2744185Y331679D02*
Y331141D01*
G01Y333398D02*
Y332861D01*
G01Y335117D02*
Y334580D01*
G01X2746554Y335330D02*
X2748128Y332711D01*
G01X2745711Y334823D02*
X2747284Y332204D01*
G01X2756586Y320885D02*
Y521633D01*
G01X2747205Y338428D02*
G03X2747492Y339072I-696J696D01*
G01X2750090Y339271D02*
G03I-1575J0D01*
G01X2747901Y337732D02*
G03X2748475Y339021I-1392J1392D01*
G01X2743746Y336621D02*
X2743526Y336514D01*
G01Y344465D02*
X2743087Y344250D01*
G01X2743197Y344894D02*
X2742978Y344787D01*
G01X2743307Y336729D02*
X2742978Y336514D01*
G01X2749007Y341830D02*
X2748023D01*
G01X2749007Y340649D02*
X2748023D01*
G01Y340544D02*
X2749007D01*
G01Y340248D02*
X2748023D01*
G01Y338885D02*
X2749007D01*
G01Y338589D02*
X2748023D01*
G01X2749007Y338484D02*
X2748023D01*
G01X2749007Y337303D02*
X2748023D01*
G01X2743526Y336514D02*
X2745941D01*
G01X2743965Y336836D02*
X2743746Y336621D01*
G01Y344680D02*
X2743526Y344465D01*
G01Y345217D02*
X2743197Y344894D01*
G01X2747901Y337732D02*
X2746702Y336533D01*
G01X2747205Y338428D02*
X2746006Y337229D01*
G01X2743307Y339307D02*
X2742868Y339415D01*
G01X2743526Y337051D02*
X2743307Y336729D01*
G01X2743965Y345002D02*
X2743746Y344680D01*
G01X2744075Y337051D02*
X2743965Y336836D01*
G01X2743636Y345432D02*
X2743526Y345217D01*
G01X2743087Y338770D02*
X2743307Y338663D01*
G01X2744075Y345324D02*
X2743965Y345002D01*
G01X2744185Y337481D02*
X2744075Y337051D01*
G01X2743636Y337481D02*
X2743526Y337051D01*
G01X2743746Y345862D02*
X2743636Y345432D01*
G01X2743307Y339307D02*
X2743856Y338878D01*
G01X2744185Y345969D02*
X2744075Y345324D01*
G01X2749007Y349187D02*
X2748475Y339021D01*
G01X2748023Y349212D02*
X2747492Y339072D01*
G01X2745941Y336514D02*
Y335976D01*
G01X2744185Y338126D02*
Y337481D01*
G01Y340812D02*
Y340274D01*
G01Y343283D02*
Y342746D01*
G01X2743636Y337911D02*
Y337481D01*
G01X2744075Y346721D02*
X2744185Y345969D01*
G01X2743636Y346614D02*
X2743746Y345862D01*
G01X2744075Y338555D02*
X2744185Y338126D01*
G01X2743526Y338341D02*
X2743636Y337911D01*
G01X2743856Y338878D02*
X2744075Y338555D01*
G01X2743307Y338663D02*
X2743526Y338341D01*
G01X2750090Y353051D02*
G03I-1575J0D01*
G01X2749007Y351082D02*
X2748023D01*
G01X2749007Y350196D02*
X2748023D01*
G01X2749007Y349212D02*
X2748023D01*
G01X2743526Y347473D02*
X2743087Y347581D01*
G01X2743417Y346936D02*
X2743087Y347044D01*
G01X2743526Y347473D02*
X2743856Y347151D01*
G01X2744185Y348978D02*
Y348441D01*
G01Y351449D02*
Y350912D01*
G01X2743087Y347044D02*
Y347581D01*
G01X2743856Y347151D02*
X2744075Y346721D01*
G01X2743417Y346936D02*
X2743636Y346614D01*
G01X2749006Y360236D02*
G03X2748907Y360774I-1967J-84D01*
G01X2749007Y355610D02*
X2748023D01*
G01X2749007Y354429D02*
X2748023D01*
G01Y354323D02*
X2749007D01*
G01Y354028D02*
X2748023D01*
G01Y352664D02*
X2749007D01*
G01Y352369D02*
X2748023D01*
G01X2749007Y352263D02*
X2748023D01*
G01X2743746Y352738D02*
X2743417Y352524D01*
G01Y353168D02*
X2743087Y352953D01*
G01X2743965D02*
X2743746Y352738D01*
G01X2743636Y353383D02*
X2743417Y353168D01*
G01X2744075D02*
X2743965Y352953D01*
G01X2743417Y355532D02*
X2743746Y355317D01*
G01X2743087Y355102D02*
X2743417Y354887D01*
G01X2743746Y355317D02*
X2743965Y355102D01*
G01X2743417Y354887D02*
X2743636Y354672D01*
G01X2744185Y353598D02*
X2744075Y353168D01*
G01X2743746Y353813D02*
X2743636Y353383D01*
G01X2744185Y354457D02*
Y353598D01*
G01Y357144D02*
Y356606D01*
G01X2743746Y354243D02*
Y353813D01*
G01X2744075Y354887D02*
X2744185Y354457D01*
G01X2743636Y354672D02*
X2743746Y354243D01*
G01X2747828Y364029D02*
X2748907Y360774D01*
G01X2746794Y364020D02*
X2748023Y360313D01*
G01X2743965Y355102D02*
X2744075Y354887D01*
G01X2746744Y364330D02*
G03X2746794Y364020I984J0D01*
G01X2743004Y366023D02*
G03X2744185Y364842I1181J0D01*
G01X2747728Y364648D02*
G03X2747828Y364029I1969J0D01*
G01X2747728Y364842D02*
X2744185D01*
G01X2747275Y364153D02*
X2744578Y366850D01*
G01X2745759Y365137D02*
X2746744Y364153D01*
G01X2747728D02*
Y409429D01*
G01X2746744Y364153D02*
Y388130D01*
G01X2745759Y365137D02*
Y364842D01*
G01Y373602D02*
Y365137D01*
G01X2744578Y366850D02*
Y388248D01*
G01X2743004Y372322D02*
Y366023D01*
G01X2744185Y373504D02*
G03X2743004Y372322I0J-1181D01*
G01X2743259Y374600D02*
G03Y376541I1713J970D01*
G01X2744185Y373504D02*
X2747728D01*
G01X2743259Y376541D02*
Y374600D01*
G01X2745759Y381043D02*
X2746744D01*
G01Y380551D02*
X2747728D01*
G01X2746765Y381466D02*
X2745799Y381653D01*
G01X2747728Y386441D02*
X2746765Y381466D01*
G01X2746744Y386535D02*
X2745799Y381653D01*
G01X2745759Y398011D02*
Y381043D01*
G01X2746744Y388228D02*
X2747728D01*
G01Y388130D02*
X2746744D01*
G01Y387047D02*
X2747728D01*
G01Y386653D02*
X2746744D01*
G01X2747728Y385866D02*
X2746614D01*
G01X2746744Y388130D02*
Y388228D01*
G01X2744578Y404704D02*
Y399586D01*
G01X2747728Y409429D02*
X2744578D01*
G01Y408641D02*
X2747728D01*
G01X2744578Y405098D02*
X2747728D01*
G01X2744578Y404704D02*
X2747728D01*
G01Y403917D02*
X2744578D01*
G01Y403130D02*
X2747728D01*
G01X2744578Y405098D02*
Y409429D01*
G01X2814618Y809409D02*
X2757718D01*
G01D02*
Y814409D01*
G01X2756862Y821909D02*
G03I-2244J0D01*
G01X2745368Y822659D02*
X2743868D01*
G01X2755368D02*
X2753868D01*
G01Y821159D02*
X2755368D01*
G01X2743868D02*
X2745368D01*
G01X2753368Y820659D02*
X2755868D01*
G01X2743368D02*
X2745868D01*
G01X2753868Y822659D02*
X2753368Y823159D01*
G01X2755368Y821159D02*
X2755868Y820659D01*
G01X2743868Y822659D02*
X2743368Y823159D01*
G01X2745368Y821159D02*
X2745868Y820659D01*
G01X2755868D02*
Y823159D01*
G01X2755368Y821159D02*
Y822659D01*
G01X2753868D02*
Y821159D01*
G01X2753368Y823159D02*
Y820659D01*
G01X2751118Y838409D02*
Y815409D01*
G01X2748118D02*
Y838409D01*
G01X2745868Y820659D02*
Y823159D01*
G01X2745368Y821159D02*
Y822659D01*
G01X2743868D02*
Y821159D01*
G01X2743368Y823159D02*
Y820659D01*
G01X2755368Y822659D02*
X2755868Y823159D01*
G01X2753868Y821159D02*
X2753368Y820659D01*
G01X2745368Y822659D02*
X2745868Y823159D01*
G01X2743868Y821159D02*
X2743368Y820659D01*
G01X2745868Y823159D02*
X2743368D01*
G01X2755868D02*
X2753368D01*
G01X2810405Y813622D02*
X2757718D01*
G01X2758118Y815409D02*
Y838409D01*
G01X2756862Y831909D02*
G03I-2244J0D01*
G01X2745868Y833159D02*
X2743368D01*
G01X2755868D02*
X2753368D01*
G01X2745368Y832659D02*
X2743868D01*
G01X2755368D02*
X2753868D01*
G01Y831159D02*
X2755368D01*
G01X2743868D02*
X2745368D01*
G01X2753368Y830659D02*
X2755868D01*
G01X2743368D02*
X2745868D01*
G01X2753868Y832659D02*
X2753368Y833159D01*
G01X2755368Y831159D02*
X2755868Y830659D01*
G01X2743868Y832659D02*
X2743368Y833159D01*
G01X2745368Y831159D02*
X2745868Y830659D01*
G01X2755868D02*
Y833159D01*
G01X2755368Y831159D02*
Y832659D01*
G01X2753868D02*
Y831159D01*
G01X2753368Y833159D02*
Y830659D01*
G01X2745868D02*
Y833159D01*
G01X2745368Y831159D02*
Y832659D01*
G01X2743868D02*
Y831159D01*
G01X2743368Y833159D02*
Y830659D01*
G01X2755368Y832659D02*
X2755868Y833159D01*
G01X2753868Y831159D02*
X2753368Y830659D01*
G01X2745368Y832659D02*
X2745868Y833159D01*
G01X2743868Y831159D02*
X2743368Y830659D01*
G01X2762144Y-1205714D02*
X2800739Y-1242398D01*
G01X2772038Y-1207611D02*
X2807896Y-1223075D01*
G01X2762875Y-1134972D02*
X2784994Y-1120736D01*
G01X2765747Y-1124918D02*
X2777838Y-1104992D01*
G01X2765581Y-291925D02*
X2768473D01*
G01X2761644D02*
X2764536D01*
G01X2765581Y-275389D02*
Y-291925D01*
G01X2764536D02*
Y-275389D01*
G01X2761644D02*
Y-291925D01*
G01X2760599D02*
Y-275389D01*
G01X2773455Y-291925D02*
X2776347D01*
G01X2769518D02*
X2772410D01*
G01X2773455Y-275389D02*
Y-291925D01*
G01X2772410D02*
Y-275389D01*
G01X2769518D02*
Y-291925D01*
G01X2768473D02*
Y-275389D01*
G01X2764536D02*
X2761644D01*
G01X2768473D02*
X2765581D01*
G01X2772410D02*
X2769518D01*
G01X2776347D02*
X2773455D01*
G01X2768397Y163366D02*
G03X2772334Y159429I3937J0D01*
G01X2768397Y163366D02*
G03X2772334Y159429I3937J0D01*
G01D02*
X2813673D01*
G01X2772334D02*
X2813673D01*
G01X2768397Y267696D02*
Y163366D01*
G01Y316948D02*
Y163366D01*
G01X2876271Y188956D02*
X2773101D01*
G01X2817610Y267696D02*
X2768397D01*
G01Y316948D02*
G03X2764460Y320885I-3937J0D01*
G01X2769301Y503523D02*
Y512184D01*
X2768002Y510452D01*
G01Y503523D02*
X2770600D01*
G01X2777962Y512184D02*
X2777096Y511895D01*
X2776446Y511174D01*
X2776013Y510308D01*
X2775688Y509153D01*
X2775580Y507853D01*
X2775688Y506554D01*
X2776013Y505399D01*
X2776446Y504533D01*
X2777096Y503812D01*
X2777962Y503523D01*
X2778828Y503812D01*
X2779478Y504533D01*
X2779911Y505399D01*
X2780236Y506554D01*
X2780344Y507853D01*
X2780236Y509153D01*
X2779911Y510308D01*
X2779478Y511174D01*
X2778828Y511895D01*
X2777962Y512184D01*
G01X2784241Y505255D02*
X2784891Y504245D01*
X2785757Y503667D01*
X2786731Y503523D01*
X2787597Y503667D01*
X2788464Y504389D01*
X2789005Y505255D01*
X2789113Y506121D01*
X2788897Y507132D01*
X2788139Y507853D01*
X2787381Y508142D01*
X2786406D01*
G01X2787381D02*
X2788030Y508575D01*
X2788572Y509297D01*
X2788788Y510163D01*
X2788572Y511029D01*
X2788030Y511751D01*
X2787056Y512184D01*
X2786082Y512040D01*
X2785107Y511462D01*
G01X2795284Y503234D02*
X2795067Y503379D01*
Y503667D01*
X2795284Y503812D01*
X2795501Y503667D01*
Y503379D01*
X2795284Y503234D01*
G01X2803945Y503523D02*
X2804703Y503667D01*
X2805569Y504100D01*
X2806110Y504822D01*
X2806327Y505833D01*
X2806110Y506843D01*
X2805461Y507709D01*
X2804486Y508142D01*
X2803404D01*
X2802754Y508431D01*
X2802213Y509153D01*
X2801996Y510163D01*
X2802321Y511174D01*
X2803079Y511895D01*
X2803945Y512184D01*
X2804811Y511895D01*
X2805569Y511174D01*
X2805894Y510163D01*
X2805677Y509153D01*
X2805136Y508431D01*
X2804486Y508142D01*
X2803404D01*
X2802429Y507709D01*
X2801780Y506843D01*
X2801563Y505833D01*
X2801780Y504822D01*
X2802321Y504100D01*
X2803187Y503667D01*
X2803945Y503523D01*
G01X2810224Y504822D02*
X2810874Y504100D01*
X2811632Y503667D01*
X2812606Y503523D01*
X2813580Y503812D01*
X2814338Y504389D01*
X2814880Y505399D01*
X2814988Y506554D01*
X2814771Y507709D01*
X2814230Y508431D01*
X2813472Y509008D01*
X2812714Y509153D01*
X2811956Y509008D01*
X2810982Y508431D01*
X2811307Y512184D01*
X2814230D01*
G01X2776862Y821909D02*
G03I-2244J0D01*
G01X2766862D02*
G03I-2244J0D01*
G01X2765368Y822659D02*
X2763868D01*
G01Y821159D02*
X2765368D01*
G01X2763368Y820659D02*
X2765868D01*
G01X2763868Y822659D02*
X2763368Y823159D01*
G01X2765368Y821159D02*
X2765868Y820659D01*
G01X2771118Y838409D02*
Y815409D01*
G01X2768118D02*
Y838409D01*
G01X2765868Y820659D02*
Y823159D01*
G01X2765368Y821159D02*
Y822659D01*
G01X2763868D02*
Y821159D01*
G01X2763368Y823159D02*
Y820659D01*
G01X2761118Y838409D02*
Y815409D01*
G01X2765368Y822659D02*
X2765868Y823159D01*
G01X2763868Y821159D02*
X2763368Y820659D01*
G01X2765868Y823159D02*
X2763368D01*
G01X2775368Y822659D02*
X2773868D01*
G01Y821159D02*
X2775368D01*
G01X2775868Y820659D02*
X2773368D01*
G01X2773868Y822659D02*
X2773368Y823159D01*
G01X2775368Y821159D02*
X2775868Y820659D01*
G01X2775368Y821159D02*
Y822659D01*
G01X2773868D02*
Y821159D01*
G01X2773368Y823159D02*
Y820659D01*
G01X2775368Y822659D02*
X2775868Y823159D01*
G01X2773868Y821159D02*
X2773368Y820659D01*
G01X2775868Y823159D02*
X2773368D01*
G01X2776862Y831909D02*
G03I-2244J0D01*
G01X2766862D02*
G03I-2244J0D01*
G01X2765868Y833159D02*
X2763368D01*
G01X2765368Y832659D02*
X2763868D01*
G01Y831159D02*
X2765368D01*
G01X2763368Y830659D02*
X2765868D01*
G01X2763868Y832659D02*
X2763368Y833159D01*
G01X2765368Y831159D02*
X2765868Y830659D01*
G01D02*
Y833159D01*
G01X2765368Y831159D02*
Y832659D01*
G01X2763868D02*
Y831159D01*
G01X2763368Y833159D02*
Y830659D01*
G01X2765368Y832659D02*
X2765868Y833159D01*
G01X2763868Y831159D02*
X2763368Y830659D01*
G01X2775868Y833159D02*
X2773368D01*
G01X2775368Y832659D02*
X2773868D01*
G01Y831159D02*
X2775368D01*
G01X2775868Y830659D02*
X2773368D01*
G01X2773868Y832659D02*
X2773368Y833159D01*
G01X2775368Y831159D02*
X2775868Y830659D01*
G01X2775368Y831159D02*
Y832659D01*
G01X2773868D02*
Y831159D01*
G01X2773368Y833159D02*
Y830659D01*
G01X2775368Y832659D02*
X2775868Y833159D01*
G01X2773868Y831159D02*
X2773368Y830659D01*
G01X2793751Y-1852994D02*
Y-1841587D01*
X2792040Y-1843868D01*
G01Y-1852994D02*
X2795462D01*
G01X2802022Y-1851283D02*
X2802877Y-1852234D01*
X2803875Y-1852804D01*
X2805159Y-1852994D01*
X2806443Y-1852614D01*
X2807441Y-1851854D01*
X2808154Y-1850523D01*
X2808296Y-1849002D01*
X2808011Y-1847481D01*
X2807298Y-1846530D01*
X2806300Y-1845770D01*
X2805302Y-1845580D01*
X2804303Y-1845770D01*
X2803020Y-1846530D01*
X2803448Y-1841587D01*
X2807298D01*
G01X2780610Y-1289563D02*
G03X2784547Y-1293500I3937J0D01*
G01D02*
X3595708D01*
G01X2780610Y-1230507D02*
Y-1289563D01*
G01Y-1230507D02*
G03X2776673Y-1226570I-3937J0D01*
G01X2788144Y-1120736D02*
X2894968D01*
G01X2784994D02*
X2788144D01*
G01X2791056Y-1102826D02*
Y-1097052D01*
G01Y-1098496D02*
X2791490Y-1097774D01*
X2792139Y-1097196D01*
X2793005Y-1097052D01*
X2793763Y-1097196D01*
X2794413Y-1097774D01*
X2794738Y-1098784D01*
Y-1102826D01*
G01X2780987Y-1104992D02*
X2880016D01*
G01X2777838D02*
X2780987D01*
G01X2777392Y-291925D02*
X2780284D01*
G01X2781329D02*
X2784221D01*
G01D02*
Y-275389D01*
G01X2781329D02*
Y-291925D01*
G01X2780284D02*
Y-275389D01*
G01X2777392D02*
Y-291925D01*
G01X2776347D02*
Y-275389D01*
G01X2789203Y-291925D02*
X2792095D01*
G01X2785266D02*
X2788158D01*
G01X2792095D02*
Y-275389D01*
G01X2789203D02*
Y-291925D01*
G01X2788158D02*
Y-275389D01*
G01X2785266D02*
Y-291925D01*
G01X2780284Y-275389D02*
X2777392D01*
G01X2784221D02*
X2781329D01*
G01X2788158D02*
X2785266D01*
G01X2792095D02*
X2789203D01*
G01X2800878Y184626D02*
G03I-6300J0D01*
G01X2777797Y214802D02*
X2782712D01*
G01X2787978D02*
X2785169D01*
G01X2782712Y213727D02*
X2777797D01*
G01X2785169Y213368D02*
X2787978D01*
G01Y212651D02*
X2785169D01*
G01X2777797Y209783D02*
X2776744D01*
G01X2783765D02*
X2782712D01*
G01X2787978Y213368D02*
Y212651D01*
G01Y215519D02*
Y214802D01*
G01X2785169D02*
Y215519D01*
G01Y212651D02*
Y213368D01*
G01X2783765Y218208D02*
Y209783D01*
G01X2782712Y214802D02*
Y218208D01*
G01Y209783D02*
Y213727D01*
G01X2777797D02*
Y209783D01*
G01Y218208D02*
Y214802D01*
G01X2776744Y209783D02*
Y218208D01*
G01X2782712D02*
X2783765D01*
G01X2776744D02*
X2777797D01*
G01X2785169Y215519D02*
X2787978D01*
G01X2791663Y210859D02*
X2792541Y210680D01*
G01X2791488Y209962D02*
X2792541Y209783D01*
G01X2789557Y215699D02*
X2789382Y214802D01*
G01X2790435Y215699D02*
X2790259Y214623D01*
G01Y213368D02*
X2790435Y212293D01*
G01X2789382Y213189D02*
X2789557Y212293D01*
G01X2790259Y214623D02*
Y213368D01*
G01X2789382Y214802D02*
Y213189D01*
G01X2789557Y212293D02*
X2789733Y211755D01*
G01D02*
X2790084Y211038D01*
G01X2790435Y212293D02*
X2791137Y211217D01*
G01X2790084Y211038D02*
X2790610Y210500D01*
G01X2791137Y211217D02*
X2791663Y210859D01*
G01X2790610Y210500D02*
X2791488Y209962D01*
G01Y218029D02*
X2790610Y217491D01*
G01X2791663Y217133D02*
X2791137Y216774D01*
G01X2790610Y217491D02*
X2790084Y216954D01*
G01X2792541Y218208D02*
X2791488Y218029D01*
G01X2792541Y217312D02*
X2791663Y217133D01*
G01X2791137Y216774D02*
X2790435Y215699D01*
G01X2790084Y216954D02*
X2789733Y216237D01*
G01D02*
X2789557Y215699D01*
G01X2800878Y247618D02*
G03I-6300J0D01*
G01X2787009Y410531D02*
X2793791D01*
G01X2779303D02*
X2785160D01*
G01X2793791Y408720D02*
X2779303D01*
G01X2787009Y418983D02*
Y410531D01*
G01X2785160D02*
Y418983D01*
G01X2779303Y408720D02*
Y410531D01*
G01X2787626Y428038D02*
X2788859D01*
G01X2783927D02*
X2785160D01*
G01Y423208D02*
X2783927D01*
G01X2788859D02*
X2787626D01*
G01X2779303Y420794D02*
X2793791D01*
G01X2785160Y418983D02*
X2779303D01*
G01X2793791D02*
X2787009D01*
G01X2787626Y423208D02*
Y428038D01*
G01X2785160D02*
Y423208D01*
G01X2783927D02*
Y428038D01*
G01X2779303Y418983D02*
Y420794D01*
G01X2787626Y430452D02*
X2789784Y430754D01*
G01X2788551Y432263D02*
X2789476D01*
G01X2786085Y431961D02*
X2785468D01*
G01Y430452D02*
X2787626D01*
G01X2785468Y431961D02*
X2783619Y432263D01*
G01X2783310Y430754D02*
X2785468Y430452D01*
G01X2787626Y432565D02*
X2788551Y432263D01*
G01X2783619D02*
X2782694Y432565D01*
G01X2781769Y431358D02*
X2783310Y430754D01*
G01X2780536Y432263D02*
X2781769Y431358D01*
G01X2782694Y432565D02*
X2781769Y433169D01*
G01X2779611Y433772D02*
X2780536Y432263D01*
G01X2786393Y434074D02*
X2787009Y433169D01*
G01X2784852Y433772D02*
X2786085Y431961D01*
G01X2781769Y433169D02*
X2781152Y434074D01*
G01X2787009Y433169D02*
X2787626Y432565D01*
G01X2784543Y435282D02*
X2784852Y433772D01*
G01X2779303Y435282D02*
X2779611Y433772D01*
G01X2788859Y428038D02*
Y423208D01*
G01X2789476Y432263D02*
X2790400Y432565D01*
G01X2789784Y430754D02*
X2791325Y431358D01*
G01X2790400Y432565D02*
X2791325Y433169D01*
G01Y431358D02*
X2792558Y432263D01*
G01X2791325Y433169D02*
X2791941Y434074D01*
G01X2793791Y443733D02*
X2783927D01*
G01X2789784Y441318D02*
X2788243D01*
G01X2789476Y439809D02*
X2788551D01*
G01D02*
X2787626Y439507D01*
G01X2782694Y440715D02*
X2781769Y440413D01*
G01X2788243Y441318D02*
X2786701Y440715D01*
G01X2781769Y438602D02*
X2782694Y439206D01*
G01X2781769Y440413D02*
X2780536Y439507D01*
G01X2787626D02*
X2787009Y438904D01*
G01X2786701Y440715D02*
X2785776Y439809D01*
G01X2787009Y438904D02*
X2786393Y437998D01*
G01X2781152Y437696D02*
X2781769Y438602D01*
G01X2785776Y439809D02*
X2784852Y438300D01*
G01X2780536Y439507D02*
X2779611Y437998D01*
G01X2786393D02*
X2786085Y437093D01*
G01X2780844Y436791D02*
X2781152Y437696D01*
G01X2784852Y438300D02*
X2784543Y436791D01*
G01X2779611Y437998D02*
X2779303Y436489D01*
G01X2786085Y434980D02*
X2786393Y434074D01*
G01X2781152D02*
X2780844Y434980D01*
G01X2786085Y437093D02*
Y434980D01*
G01X2784543Y436791D02*
Y435282D01*
G01X2783927Y443733D02*
Y445243D01*
G01X2782694Y439206D02*
Y440715D01*
G01X2780844Y434980D02*
Y436791D01*
G01X2779303Y436489D02*
Y435282D01*
G01X2786393Y450072D02*
X2793791D01*
G01Y448563D02*
X2786393D01*
G01X2783927Y445243D02*
X2784852D01*
G01X2786085D02*
X2793791D01*
G01X2786393Y448563D02*
X2785776Y448261D01*
G01Y450374D02*
X2786393Y450072D01*
G01X2785776Y448261D02*
X2785468Y447959D01*
G01X2784235Y448865D02*
X2785160Y449770D01*
G01X2785468Y450676D02*
X2785776Y450374D01*
G01X2785160Y449770D02*
X2784235Y450676D01*
G01X2785468Y445846D02*
X2786085Y445243D01*
G01X2784852D02*
X2784235Y445846D01*
G01X2785468Y447959D02*
X2785160Y447355D01*
G01X2783927Y447959D02*
X2784235Y448865D01*
G01X2785160Y446752D02*
X2785468Y445846D01*
G01X2784235D02*
X2783927Y446752D01*
G01X2785160Y447355D02*
Y446752D01*
G01X2783927D02*
Y447959D01*
G01X2791325Y440715D02*
X2789784Y441318D01*
G01X2790400Y439507D02*
X2789476Y439809D01*
G01X2792558D02*
X2791325Y440715D01*
G01Y438904D02*
X2790400Y439507D01*
G01X2791941Y437998D02*
X2791325Y438904D01*
G01X2791941Y434074D02*
X2792250Y434980D01*
G01Y437093D02*
X2791941Y437998D01*
G01X2783927Y458825D02*
X2784852D01*
G01X2786085D02*
X2793791D01*
G01Y457316D02*
X2783927D01*
G01X2786393Y454901D02*
X2793791D01*
G01Y453392D02*
X2786393D01*
G01X2784852Y454298D02*
X2786393Y454901D01*
G01Y453392D02*
X2785776Y453090D01*
G01D02*
X2785468Y452788D01*
G01X2784235Y453694D02*
X2784852Y454298D01*
G01X2785468Y459429D02*
X2786085Y458825D01*
G01X2784852D02*
X2784235Y459429D01*
G01X2785468Y452788D02*
X2785160Y452185D01*
G01Y451279D02*
X2785468Y450676D01*
G01Y461542D02*
X2785160Y460938D01*
G01X2783927Y452788D02*
X2784235Y453694D01*
G01X2785160Y460334D02*
X2785468Y459429D01*
G01X2784235D02*
X2783927Y460334D01*
G01X2784235Y450676D02*
X2783927Y451581D01*
G01X2785160Y452185D02*
Y451279D01*
G01Y460938D02*
Y460334D01*
G01X2783927Y457316D02*
Y458825D01*
G01Y460334D02*
Y461542D01*
G01Y451581D02*
Y452788D01*
G01X2786393Y463654D02*
X2793791D01*
G01Y462145D02*
X2786393D01*
G01D02*
X2785776Y461843D01*
G01X2786393Y466975D02*
X2785776Y466673D01*
G01Y463956D02*
X2786393Y463654D01*
G01X2785776Y461843D02*
X2785468Y461542D01*
G01X2784235Y462447D02*
X2785160Y463353D01*
G01X2785776Y466673D02*
X2785468Y466371D01*
G01Y464258D02*
X2785776Y463956D01*
G01X2785160Y463353D02*
X2784235Y464258D01*
G01X2785160Y464862D02*
X2785468Y464258D01*
G01Y466371D02*
X2785160Y465767D01*
G01X2783927Y461542D02*
X2784235Y462447D01*
G01X2783927Y466371D02*
X2784235Y467276D01*
G01Y464258D02*
X2783927Y465164D01*
G01X2785160Y465767D02*
Y464862D01*
G01X2783927Y465164D02*
Y466371D01*
G01X2786393Y468484D02*
X2793791D01*
G01Y466975D02*
X2786393D01*
G01X2784852Y467880D02*
X2786393Y468484D01*
G01X2784235Y467276D02*
X2784852Y467880D01*
G01X2786862Y821909D02*
G03I-2244J0D01*
G01X2785368Y822659D02*
X2783868D01*
G01Y821159D02*
X2785368D01*
G01X2783368Y820659D02*
X2785868D01*
G01X2783868Y822659D02*
X2783368Y823159D01*
G01X2785368Y821159D02*
X2785868Y820659D01*
G01X2788118Y815409D02*
Y838409D01*
G01X2785868Y820659D02*
Y823159D01*
G01X2785368Y821159D02*
Y822659D01*
G01X2783868D02*
Y821159D01*
G01X2783368Y823159D02*
Y820659D01*
G01X2781118Y838409D02*
Y815409D01*
G01X2778118D02*
Y838409D01*
G01X2775868Y820659D02*
Y823159D01*
G01X2785368Y822659D02*
X2785868Y823159D01*
G01X2783868Y821159D02*
X2783368Y820659D01*
G01X2785868Y823159D02*
X2783368D01*
G01X2791118Y838409D02*
Y815409D01*
G01X2786862Y831909D02*
G03I-2244J0D01*
G01X2785868Y833159D02*
X2783368D01*
G01X2785368Y832659D02*
X2783868D01*
G01Y831159D02*
X2785368D01*
G01X2783368Y830659D02*
X2785868D01*
G01X2783868Y832659D02*
X2783368Y833159D01*
G01X2785368Y831159D02*
X2785868Y830659D01*
G01D02*
Y833159D01*
G01X2785368Y831159D02*
Y832659D01*
G01X2783868D02*
Y831159D01*
G01X2783368Y833159D02*
Y830659D01*
G01X2775868D02*
Y833159D01*
G01X2785368Y832659D02*
X2785868Y833159D01*
G01X2783868Y831159D02*
X2783368Y830659D01*
G01X2785720Y1080689D02*
G03X2789657Y1084626I0J3937D01*
G01Y1114153D02*
Y1084626D01*
G01X2790838Y1094074D02*
X2793594D01*
G01X2790838Y1110610D02*
Y1094074D01*
G01X3068004Y1116122D02*
X2791626D01*
G01X2793594Y1110610D02*
X2790838D01*
G01X3069972D02*
X2789657D01*
G01X2791626Y1116122D02*
X2789657Y1114153D01*
G01X2793751Y1438719D02*
Y1450126D01*
X2792040Y1447845D01*
G01Y1438719D02*
X2795462D01*
G01X2802022Y1440430D02*
X2802877Y1439479D01*
X2803875Y1438909D01*
X2805159Y1438719D01*
X2806443Y1439099D01*
X2807441Y1439859D01*
X2808154Y1441190D01*
X2808296Y1442711D01*
X2808011Y1444232D01*
X2807298Y1445183D01*
X2806300Y1445943D01*
X2805302Y1446133D01*
X2804303Y1445943D01*
X2803020Y1445183D01*
X2803448Y1450126D01*
X2807298D01*
G01X2800739Y-1242398D02*
X2803888D01*
G01D02*
X2910713D01*
G01X2807896Y-1223075D02*
X2811045D01*
G01X2798212Y-1118571D02*
Y-1112797D01*
G01Y-1114241D02*
X2798646Y-1113519D01*
X2799295Y-1112941D01*
X2800161Y-1112797D01*
X2800919Y-1112941D01*
X2801569Y-1113519D01*
X2801894Y-1114529D01*
Y-1118571D01*
G01X2809220Y-1116839D02*
X2809870Y-1117849D01*
X2810736Y-1118427D01*
X2811710Y-1118571D01*
X2812576Y-1118427D01*
X2813443Y-1117705D01*
X2813984Y-1116839D01*
X2814092Y-1115973D01*
X2813876Y-1114962D01*
X2813118Y-1114241D01*
X2812360Y-1113952D01*
X2811385D01*
G01X2812360D02*
X2813009Y-1113519D01*
X2813551Y-1112797D01*
X2813767Y-1111931D01*
X2813551Y-1111065D01*
X2813009Y-1110343D01*
X2812035Y-1109910D01*
X2811061Y-1110054D01*
X2810086Y-1110632D01*
G01X2820263Y-1118860D02*
X2820046Y-1118715D01*
Y-1118427D01*
X2820263Y-1118282D01*
X2820480Y-1118427D01*
Y-1118715D01*
X2820263Y-1118860D01*
G01X2826867Y-1111353D02*
X2827517Y-1110488D01*
X2828274Y-1110054D01*
X2829141Y-1109910D01*
X2830223Y-1110199D01*
X2830981Y-1110920D01*
X2831198Y-1111786D01*
X2831089Y-1112653D01*
X2830656Y-1113374D01*
X2828491Y-1114818D01*
X2827517Y-1115828D01*
X2826867Y-1117272D01*
X2826650Y-1118571D01*
X2831198D01*
G01X2837585Y-1109910D02*
X2836719Y-1110199D01*
X2836069Y-1110920D01*
X2835636Y-1111786D01*
X2835311Y-1112941D01*
X2835203Y-1114241D01*
X2835311Y-1115540D01*
X2835636Y-1116695D01*
X2836069Y-1117561D01*
X2836719Y-1118282D01*
X2837585Y-1118571D01*
X2838451Y-1118282D01*
X2839101Y-1117561D01*
X2839534Y-1116695D01*
X2839859Y-1115540D01*
X2839967Y-1114241D01*
X2839859Y-1112941D01*
X2839534Y-1111786D01*
X2839101Y-1110920D01*
X2838451Y-1110199D01*
X2837585Y-1109910D01*
G01X2804446Y-1102826D02*
X2805204Y-1102682D01*
X2806070Y-1102249D01*
X2806611Y-1101527D01*
X2806828Y-1100516D01*
X2806611Y-1099506D01*
X2805962Y-1098640D01*
X2804987Y-1098207D01*
X2803905D01*
X2803255Y-1097918D01*
X2802714Y-1097196D01*
X2802497Y-1096186D01*
X2802822Y-1095175D01*
X2803580Y-1094454D01*
X2804446Y-1094165D01*
X2805312Y-1094454D01*
X2806070Y-1095175D01*
X2806395Y-1096186D01*
X2806178Y-1097196D01*
X2805637Y-1097918D01*
X2804987Y-1098207D01*
X2803905D01*
X2802930Y-1098640D01*
X2802281Y-1099506D01*
X2802064Y-1100516D01*
X2802281Y-1101527D01*
X2802822Y-1102249D01*
X2803688Y-1102682D01*
X2804446Y-1102826D01*
G01X2813107Y-1103115D02*
X2812890Y-1102970D01*
Y-1102682D01*
X2813107Y-1102537D01*
X2813324Y-1102682D01*
Y-1102970D01*
X2813107Y-1103115D01*
G01X2821768Y-1094165D02*
X2820902Y-1094454D01*
X2820252Y-1095175D01*
X2819819Y-1096041D01*
X2819494Y-1097196D01*
X2819386Y-1098496D01*
X2819494Y-1099795D01*
X2819819Y-1100950D01*
X2820252Y-1101816D01*
X2820902Y-1102537D01*
X2821768Y-1102826D01*
X2822634Y-1102537D01*
X2823284Y-1101816D01*
X2823717Y-1100950D01*
X2824042Y-1099795D01*
X2824150Y-1098496D01*
X2824042Y-1097196D01*
X2823717Y-1096041D01*
X2823284Y-1095175D01*
X2822634Y-1094454D01*
X2821768Y-1094165D01*
G01X2830429D02*
X2829563Y-1094454D01*
X2828913Y-1095175D01*
X2828480Y-1096041D01*
X2828155Y-1097196D01*
X2828047Y-1098496D01*
X2828155Y-1099795D01*
X2828480Y-1100950D01*
X2828913Y-1101816D01*
X2829563Y-1102537D01*
X2830429Y-1102826D01*
X2831295Y-1102537D01*
X2831945Y-1101816D01*
X2832378Y-1100950D01*
X2832703Y-1099795D01*
X2832811Y-1098496D01*
X2832703Y-1097196D01*
X2832378Y-1096041D01*
X2831945Y-1095175D01*
X2831295Y-1094454D01*
X2830429Y-1094165D01*
G01X2833366Y-884641D02*
G03I-13780J0D01*
G01X2801014Y-291925D02*
X2803906D01*
G01X2797077D02*
X2799969D01*
G01X2793140D02*
X2796032D01*
G01X2801014Y-275389D02*
Y-291925D01*
G01X2799969D02*
Y-275389D01*
G01X2797077D02*
Y-291925D01*
G01X2796032D02*
Y-275389D01*
G01X2793140D02*
Y-291925D01*
G01X2804951D02*
X2807843D01*
G01D02*
Y-275389D01*
G01X2804951D02*
Y-291925D01*
G01X2803906D02*
Y-275389D01*
G01X2796032D02*
X2793140D01*
G01X2799969D02*
X2797077D01*
G01X2803906D02*
X2801014D01*
G01X2807843D02*
X2804951D01*
G01X2798860Y214802D02*
X2798333Y214623D01*
G01X2801493Y214802D02*
X2801142Y214623D01*
G01X2793594Y209962D02*
X2794472Y210500D01*
G01X2793419Y210859D02*
X2793945Y211217D01*
G01X2801142Y214623D02*
X2800966Y214444D01*
G01X2800615Y214802D02*
X2801142Y215340D01*
G01X2794472Y210500D02*
X2794998Y211038D01*
G01X2798333Y214623D02*
X2797982Y214265D01*
G01Y214981D02*
X2798333Y215340D01*
G01X2792541Y209783D02*
X2793594Y209962D01*
G01X2792541Y210680D02*
X2793419Y210859D01*
G01X2793945Y211217D02*
X2794647Y212293D01*
G01X2800966Y214444D02*
X2800791Y214085D01*
G01X2794998Y211038D02*
X2795350Y211755D01*
G01X2799211Y214802D02*
X2798860D01*
G01X2802019D02*
X2801493D01*
G01X2797982Y209783D02*
X2797105D01*
G01X2800791D02*
X2799913D01*
G01X2805881D02*
X2805003D01*
G01X2803599D02*
X2802722D01*
G01X2795350Y211755D02*
X2795525Y212293D01*
G01D02*
X2795700Y213189D01*
G01X2794647Y212293D02*
X2794823Y213368D01*
G01X2805003Y209783D02*
Y215519D01*
G01X2803599Y214085D02*
Y209783D01*
G01X2802722D02*
Y214085D01*
G01X2800791D02*
Y209783D01*
G01X2794823Y214623D02*
X2794647Y215699D01*
G01X2795700Y214802D02*
X2795525Y215699D01*
G01X2802370Y214623D02*
X2802019Y214802D01*
G01X2799562Y214623D02*
X2799211Y214802D01*
G01X2799913Y209783D02*
Y214085D01*
G01X2797982Y215519D02*
Y214981D01*
G01Y214265D02*
Y209783D01*
G01X2797105D02*
Y215519D01*
G01X2795700Y213189D02*
Y214802D01*
G01X2794823Y213368D02*
Y214623D01*
G01X2803248Y214981D02*
X2803599Y214085D01*
G01X2802722D02*
X2802546Y214444D01*
G01X2799913Y214085D02*
X2799737Y214444D01*
G01X2802897Y215340D02*
X2803248Y214981D01*
G01X2802546Y214444D02*
X2802370Y214623D01*
G01X2800089Y215340D02*
X2800615Y214802D01*
G01X2799737Y214444D02*
X2799562Y214623D01*
G01X2801142Y215340D02*
X2801669Y215519D01*
G01X2798333Y215340D02*
X2798860Y215519D01*
G01X2805003D02*
X2805881D01*
G01X2801669D02*
X2802370D01*
G01X2797105D02*
X2797982D01*
G01X2798860D02*
X2799562D01*
G01X2802370D02*
X2802897Y215340D01*
G01X2799562Y215519D02*
X2800089Y215340D01*
G01X2793419Y217133D02*
X2792541Y217312D01*
G01X2793594Y218029D02*
X2792541Y218208D01*
G01X2794472Y217491D02*
X2793594Y218029D01*
G01X2795525Y215699D02*
X2795350Y216237D01*
G01D02*
X2794998Y216954D01*
G01X2794647Y215699D02*
X2793945Y216774D01*
G01X2794998Y216954D02*
X2794472Y217491D01*
G01X2793945Y216774D02*
X2793419Y217133D01*
G01X2806759Y214802D02*
X2806232Y214623D01*
G01D02*
X2805881Y214265D01*
G01Y214981D02*
X2806232Y215340D01*
G01X2807109Y214802D02*
X2806759D01*
G01X2808689Y209783D02*
X2807812D01*
G01D02*
Y214085D01*
G01X2805881Y215519D02*
Y214981D01*
G01Y214265D02*
Y209783D01*
G01X2807461Y214623D02*
X2807109Y214802D01*
G01X2807812Y214085D02*
X2807636Y214444D01*
G01X2807987Y215340D02*
X2808514Y214802D01*
G01X2807636Y214444D02*
X2807461Y214623D01*
G01X2806232Y215340D02*
X2806759Y215519D01*
G01D02*
X2807461D01*
G01D02*
X2807987Y215340D01*
G01X2793791Y410531D02*
Y408720D01*
G01Y420794D02*
Y418983D01*
G01X2792558Y432263D02*
X2793483Y433772D01*
G01D02*
X2793791Y435282D01*
G01X2793483Y438300D02*
X2792558Y439809D01*
G01X2793791Y436791D02*
X2793483Y438300D01*
G01X2793791Y435282D02*
Y436791D01*
G01Y445243D02*
Y443733D01*
G01X2792250Y434980D02*
Y437093D01*
G01X2793791Y450072D02*
Y448563D01*
G01Y454901D02*
Y453392D01*
G01Y458825D02*
Y457316D01*
G01Y463654D02*
Y462145D01*
G01Y468484D02*
Y466975D01*
G01X2808614Y811409D02*
X2798114D01*
G01D02*
Y838409D01*
G01X2796862Y821909D02*
G03I-2244J0D01*
G01X2795368Y822659D02*
X2793868D01*
G01Y821159D02*
X2795368D01*
G01X2793368Y820659D02*
X2795868D01*
G01X2808614Y815409D02*
X2802614D01*
G01X2793868Y822659D02*
X2793368Y823159D01*
G01X2795368Y821159D02*
X2795868Y820659D01*
G01X2802614Y838409D02*
Y815409D01*
G01X2795868Y820659D02*
Y823159D01*
G01X2795368Y821159D02*
Y822659D01*
G01X2793868D02*
Y821159D01*
G01X2793368Y823159D02*
Y820659D01*
G01X2795368Y822659D02*
X2795868Y823159D01*
G01X2793868Y821159D02*
X2793368Y820659D01*
G01X2795868Y823159D02*
X2793368D01*
G01X2796862Y831909D02*
G03I-2244J0D01*
G01X2795868Y833159D02*
X2793368D01*
G01X2795368Y832659D02*
X2793868D01*
G01Y831159D02*
X2795368D01*
G01X2793368Y830659D02*
X2795868D01*
G01X2793868Y832659D02*
X2793368Y833159D01*
G01X2795368Y831159D02*
X2795868Y830659D01*
G01D02*
Y833159D01*
G01X2795368Y831159D02*
Y832659D01*
G01X2793868D02*
Y831159D01*
G01X2793368Y833159D02*
Y830659D01*
G01X2795368Y832659D02*
X2795868Y833159D01*
G01X2793868Y831159D02*
X2793368Y830659D01*
G01X2802649Y1094074D02*
X2805405D01*
G01X2798712D02*
X2801468D01*
G01X2797531D02*
X2794775D01*
G01X2802649Y1110610D02*
Y1094074D01*
G01X2801468D02*
Y1110610D01*
G01X2798712D02*
Y1094074D01*
G01X2797531Y1106673D02*
Y1094074D01*
G01X2794775D02*
Y1106673D01*
G01X2793594Y1094074D02*
Y1110610D01*
G01X2794775Y1106673D02*
X2797531D01*
G01X2806586Y1094074D02*
X2809342D01*
G01X2806586Y1110610D02*
Y1094074D01*
G01X2805405D02*
Y1110610D01*
G01X2801468D02*
X2798712D01*
G01X2805405D02*
X2802649D01*
G01X2809342D02*
X2806586D01*
G01X2813957Y-1240233D02*
Y-1234459D01*
G01Y-1235903D02*
X2814391Y-1235181D01*
X2815040Y-1234603D01*
X2815906Y-1234459D01*
X2816664Y-1234603D01*
X2817314Y-1235181D01*
X2817639Y-1236191D01*
Y-1240233D01*
G01X2824964Y-1238501D02*
X2825614Y-1239511D01*
X2826480Y-1240089D01*
X2827454Y-1240233D01*
X2828320Y-1240089D01*
X2829187Y-1239367D01*
X2829728Y-1238501D01*
X2829836Y-1237635D01*
X2829620Y-1236624D01*
X2828862Y-1235903D01*
X2828104Y-1235614D01*
X2827129D01*
G01X2828104D02*
X2828753Y-1235181D01*
X2829295Y-1234459D01*
X2829511Y-1233593D01*
X2829295Y-1232727D01*
X2828753Y-1232005D01*
X2827779Y-1231572D01*
X2826805Y-1231716D01*
X2825830Y-1232294D01*
G01X2836007Y-1240522D02*
X2835790Y-1240377D01*
Y-1240089D01*
X2836007Y-1239944D01*
X2836224Y-1240089D01*
Y-1240377D01*
X2836007Y-1240522D01*
G01X2842611Y-1233015D02*
X2843261Y-1232150D01*
X2844018Y-1231716D01*
X2844885Y-1231572D01*
X2845967Y-1231861D01*
X2846725Y-1232582D01*
X2846942Y-1233448D01*
X2846833Y-1234315D01*
X2846400Y-1235036D01*
X2844235Y-1236480D01*
X2843261Y-1237490D01*
X2842611Y-1238934D01*
X2842394Y-1240233D01*
X2846942D01*
G01X2853329Y-1231572D02*
X2852463Y-1231861D01*
X2851813Y-1232582D01*
X2851380Y-1233448D01*
X2851055Y-1234603D01*
X2850947Y-1235903D01*
X2851055Y-1237202D01*
X2851380Y-1238357D01*
X2851813Y-1239223D01*
X2852463Y-1239944D01*
X2853329Y-1240233D01*
X2854195Y-1239944D01*
X2854845Y-1239223D01*
X2855278Y-1238357D01*
X2855603Y-1237202D01*
X2855711Y-1235903D01*
X2855603Y-1234603D01*
X2855278Y-1233448D01*
X2854845Y-1232582D01*
X2854195Y-1231861D01*
X2853329Y-1231572D01*
G01X2821114Y-1220910D02*
Y-1215136D01*
G01Y-1216580D02*
X2821548Y-1215858D01*
X2822197Y-1215280D01*
X2823063Y-1215136D01*
X2823821Y-1215280D01*
X2824471Y-1215858D01*
X2824796Y-1216868D01*
Y-1220910D01*
G01X2811045Y-1223075D02*
X2910074D01*
G01X2826476Y-884641D02*
G03I-6890J0D01*
G01X2816762Y-291925D02*
X2819654D01*
G01X2812825D02*
X2815717D01*
G01X2808888D02*
X2811780D01*
G01X2816762Y-275389D02*
Y-291925D01*
G01X2815717D02*
Y-275389D01*
G01X2812825D02*
Y-291925D01*
G01X2811780D02*
Y-275389D01*
G01X2808888D02*
Y-291925D01*
G01X2824636D02*
X2827528D01*
G01X2820699D02*
X2823591D01*
G01X2824636Y-275389D02*
Y-291925D01*
G01X2823591D02*
Y-275389D01*
G01X2820699D02*
Y-291925D01*
G01X2819654D02*
Y-275389D01*
G01X2811780D02*
X2808888D01*
G01X2815717D02*
X2812825D01*
G01X2819654D02*
X2816762D01*
G01X2823591D02*
X2820699D01*
G01X2827528D02*
X2824636D01*
G01X2817610Y96437D02*
G03X2821547Y92500I3937J0D01*
G01X2817610Y155492D02*
Y96437D01*
G01X2821547Y92500D02*
X3632708D01*
G01X2817610Y155492D02*
G03X2813673Y159429I-3937J0D01*
G01X2817610Y155492D02*
G03X2813673Y159429I-3937J0D01*
G01X2817610Y267696D02*
Y158248D01*
G01X2809391Y214802D02*
X2809041Y214623D01*
G01D02*
X2808865Y214444D01*
G01X2808514Y214802D02*
X2809041Y215340D01*
G01X2808865Y214444D02*
X2808689Y214085D01*
G01X2809918Y214802D02*
X2809391D01*
G01X2811498Y209783D02*
X2810620D01*
G01X2811498Y214085D02*
Y209783D01*
G01X2810620D02*
Y214085D01*
G01X2808689D02*
Y209783D01*
G01X2810269Y214623D02*
X2809918Y214802D01*
G01X2811147Y214981D02*
X2811498Y214085D01*
G01X2810620D02*
X2810445Y214444D01*
G01X2810796Y215340D02*
X2811147Y214981D01*
G01X2810445Y214444D02*
X2810269Y214623D01*
G01X2809041Y215340D02*
X2809567Y215519D01*
G01D02*
X2810269D01*
G01D02*
X2810796Y215340D01*
G01X2810917Y267696D02*
Y521633D01*
G01X2825650Y356148D02*
X2826408Y357158D01*
X2827057Y357736D01*
X2827924Y358024D01*
X2828681Y357736D01*
X2829223Y357158D01*
X2829656Y356292D01*
X2829764Y355282D01*
X2829656Y354415D01*
X2829223Y353549D01*
X2828573Y352828D01*
X2827815Y352539D01*
X2826949Y352828D01*
X2826191Y353694D01*
X2825758Y354993D01*
X2825650Y356436D01*
X2825866Y358313D01*
X2826191Y359324D01*
X2826733Y360334D01*
X2827490Y361056D01*
X2828248Y361200D01*
X2829006Y360911D01*
X2829548Y360190D01*
G01X2833986Y353838D02*
X2834636Y353116D01*
X2835394Y352683D01*
X2836368Y352539D01*
X2837342Y352828D01*
X2838100Y353405D01*
X2838642Y354415D01*
X2838750Y355570D01*
X2838533Y356725D01*
X2837992Y357447D01*
X2837234Y358024D01*
X2836476Y358169D01*
X2835718Y358024D01*
X2834744Y357447D01*
X2835069Y361200D01*
X2837992D01*
G01X2845029Y352250D02*
X2844812Y352395D01*
Y352683D01*
X2845029Y352828D01*
X2845246Y352683D01*
Y352395D01*
X2845029Y352250D01*
G01X2851308Y353838D02*
X2851958Y353116D01*
X2852716Y352683D01*
X2853690Y352539D01*
X2854664Y352828D01*
X2855422Y353405D01*
X2855964Y354415D01*
X2856072Y355570D01*
X2855855Y356725D01*
X2855314Y357447D01*
X2854556Y358024D01*
X2853798Y358169D01*
X2853040Y358024D01*
X2852066Y357447D01*
X2852391Y361200D01*
X2855314D01*
G01X2862351D02*
X2861485Y360911D01*
X2860835Y360190D01*
X2860402Y359324D01*
X2860077Y358169D01*
X2859969Y356869D01*
X2860077Y355570D01*
X2860402Y354415D01*
X2860835Y353549D01*
X2861485Y352828D01*
X2862351Y352539D01*
X2863217Y352828D01*
X2863867Y353549D01*
X2864300Y354415D01*
X2864625Y355570D01*
X2864733Y356869D01*
X2864625Y358169D01*
X2864300Y359324D01*
X2863867Y360190D01*
X2863217Y360911D01*
X2862351Y361200D01*
G01X2852649Y501358D02*
X2820185D01*
G01X2814618Y844409D02*
Y809409D01*
G01X2808614Y838409D02*
Y811409D01*
G01X2810405Y813622D02*
X2809618Y814409D01*
G01X2810405Y813622D02*
Y840196D01*
G01X2809618Y814409D02*
Y839409D01*
G01X2810405Y840196D02*
X2809618Y839409D01*
G01X2818397Y1094074D02*
X2821153D01*
G01X2810523D02*
X2813279D01*
G01X2814460D02*
X2817216D01*
G01X2821153D02*
Y1110610D01*
G01X2818397D02*
Y1094074D01*
G01X2817216D02*
Y1110610D01*
G01X2814460D02*
Y1094074D01*
G01X2813279D02*
Y1110610D01*
G01X2810523D02*
Y1094074D01*
G01X2809342D02*
Y1110610D01*
G01X2822334Y1094074D02*
X2825090D01*
G01X2822334Y1110610D02*
Y1094074D01*
G01X2813279Y1110610D02*
X2810523D01*
G01X2817216D02*
X2814460D01*
G01X2821153D02*
X2818397D01*
G01X2825090D02*
X2822334D01*
G01X2834503Y-1220910D02*
X2835261Y-1220766D01*
X2836127Y-1220333D01*
X2836668Y-1219611D01*
X2836885Y-1218600D01*
X2836668Y-1217590D01*
X2836019Y-1216724D01*
X2835044Y-1216291D01*
X2833962D01*
X2833312Y-1216002D01*
X2832771Y-1215280D01*
X2832554Y-1214270D01*
X2832879Y-1213259D01*
X2833637Y-1212538D01*
X2834503Y-1212249D01*
X2835369Y-1212538D01*
X2836127Y-1213259D01*
X2836452Y-1214270D01*
X2836235Y-1215280D01*
X2835694Y-1216002D01*
X2835044Y-1216291D01*
X2833962D01*
X2832987Y-1216724D01*
X2832338Y-1217590D01*
X2832121Y-1218600D01*
X2832338Y-1219611D01*
X2832879Y-1220333D01*
X2833745Y-1220766D01*
X2834503Y-1220910D01*
G01X2843164Y-1221199D02*
X2842947Y-1221054D01*
Y-1220766D01*
X2843164Y-1220621D01*
X2843381Y-1220766D01*
Y-1221054D01*
X2843164Y-1221199D01*
G01X2851825Y-1212249D02*
X2850959Y-1212538D01*
X2850309Y-1213259D01*
X2849876Y-1214125D01*
X2849551Y-1215280D01*
X2849443Y-1216580D01*
X2849551Y-1217879D01*
X2849876Y-1219034D01*
X2850309Y-1219900D01*
X2850959Y-1220621D01*
X2851825Y-1220910D01*
X2852691Y-1220621D01*
X2853341Y-1219900D01*
X2853774Y-1219034D01*
X2854099Y-1217879D01*
X2854207Y-1216580D01*
X2854099Y-1215280D01*
X2853774Y-1214125D01*
X2853341Y-1213259D01*
X2852691Y-1212538D01*
X2851825Y-1212249D01*
G01X2860486D02*
X2859620Y-1212538D01*
X2858970Y-1213259D01*
X2858537Y-1214125D01*
X2858212Y-1215280D01*
X2858104Y-1216580D01*
X2858212Y-1217879D01*
X2858537Y-1219034D01*
X2858970Y-1219900D01*
X2859620Y-1220621D01*
X2860486Y-1220910D01*
X2861352Y-1220621D01*
X2862002Y-1219900D01*
X2862435Y-1219034D01*
X2862760Y-1217879D01*
X2862868Y-1216580D01*
X2862760Y-1215280D01*
X2862435Y-1214125D01*
X2862002Y-1213259D01*
X2861352Y-1212538D01*
X2860486Y-1212249D01*
G01X2856988Y-1197043D02*
G03I-13780J0D01*
G01X2850098D02*
G03I-6890J0D01*
G01X2842242Y-1121458D02*
X2841159Y-1120014D01*
X2840618Y-1118571D01*
Y-1112797D01*
X2841159Y-1111353D01*
X2842242Y-1109910D01*
G01X2848954Y-1118571D02*
Y-1109910D01*
X2853934Y-1118571D01*
Y-1109910D01*
G01X2857940Y-1118571D02*
Y-1109910D01*
X2860538D01*
X2861404Y-1110343D01*
X2862054Y-1111353D01*
X2862270Y-1112508D01*
X2862054Y-1113663D01*
X2861512Y-1114529D01*
X2860538Y-1114962D01*
X2857940D01*
G01X2868766Y-1109910D02*
Y-1118571D01*
G01X2866276Y-1109910D02*
X2871256D01*
G01X2875153Y-1118571D02*
Y-1109910D01*
G01X2879701D02*
Y-1118571D01*
G01Y-1114241D02*
X2875153D01*
G01X2886629Y-1121458D02*
X2887712Y-1120014D01*
X2888253Y-1118571D01*
Y-1112797D01*
X2887712Y-1111353D01*
X2886629Y-1109910D01*
G01X2835086Y-1105713D02*
X2834003Y-1104269D01*
X2833462Y-1102826D01*
Y-1097052D01*
X2834003Y-1095608D01*
X2835086Y-1094165D01*
G01X2842123Y-1102826D02*
Y-1094165D01*
X2844721D01*
X2845587Y-1094598D01*
X2846237Y-1095608D01*
X2846453Y-1096763D01*
X2846237Y-1097918D01*
X2845695Y-1098784D01*
X2844721Y-1099217D01*
X2842123D01*
G01X2850242Y-1102826D02*
X2852949Y-1094165D01*
X2855656Y-1102826D01*
G01X2854681Y-1099795D02*
X2851217D01*
G01X2859228Y-1102826D02*
Y-1094165D01*
X2861393D01*
X2862260Y-1094598D01*
X2862909Y-1095175D01*
X2863451Y-1096041D01*
X2863884Y-1097052D01*
X2863992Y-1098496D01*
X2863884Y-1099939D01*
X2863451Y-1100950D01*
X2862909Y-1101816D01*
X2862260Y-1102393D01*
X2861393Y-1102826D01*
X2859228D01*
G01X2870812Y-1105713D02*
X2871895Y-1104269D01*
X2872436Y-1102826D01*
Y-1097052D01*
X2871895Y-1095608D01*
X2870812Y-1094165D01*
G01X2825383Y-880918D02*
X2862035Y-857373D01*
G01X2828831Y-874423D02*
X2862306Y-837420D01*
G01X2828573Y-291925D02*
X2831465D01*
G01X2832510D02*
X2835402D01*
G01X2832510Y-275389D02*
Y-291925D01*
G01X2831465D02*
Y-275389D01*
G01X2828573D02*
Y-291925D01*
G01X2827528D02*
Y-275389D01*
G01X2840384Y-291925D02*
X2843276D01*
G01X2836447D02*
X2839339D01*
G01X2840384Y-275389D02*
Y-291925D01*
G01X2839339D02*
Y-275389D01*
G01X2836447D02*
Y-291925D01*
G01X2835402D02*
Y-275389D01*
G01X2831465D02*
X2828573D01*
G01X2835402D02*
X2832510D01*
G01X2839339D02*
X2836447D01*
G01X2843276D02*
X2840384D01*
G01X2834145Y1094074D02*
X2836901D01*
G01X2838082D02*
X2840838D01*
G01X2830208D02*
X2832964D01*
G01X2826271D02*
X2829027D01*
G01X2838082Y1110610D02*
Y1094074D01*
G01X2836901D02*
Y1110610D01*
G01X2834145D02*
Y1094074D01*
G01X2832964D02*
Y1110610D01*
G01X2830208D02*
Y1094074D01*
G01X2829027D02*
Y1110610D01*
G01X2826271D02*
Y1094074D01*
G01X2825090D02*
Y1110610D01*
G01X2840838Y1094074D02*
Y1110610D01*
G01X2829027D02*
X2826271D01*
G01X2832964D02*
X2830208D01*
G01X2836901D02*
X2834145D01*
G01X2840838D02*
X2838082D01*
G01X2857986Y-1243120D02*
X2856903Y-1241676D01*
X2856362Y-1240233D01*
Y-1234459D01*
X2856903Y-1233015D01*
X2857986Y-1231572D01*
G01X2864698Y-1240233D02*
Y-1231572D01*
X2869678Y-1240233D01*
Y-1231572D01*
G01X2873684Y-1240233D02*
Y-1231572D01*
X2876282D01*
X2877148Y-1232005D01*
X2877798Y-1233015D01*
X2878014Y-1234170D01*
X2877798Y-1235325D01*
X2877256Y-1236191D01*
X2876282Y-1236624D01*
X2873684D01*
G01X2884510Y-1231572D02*
Y-1240233D01*
G01X2882020Y-1231572D02*
X2887000D01*
G01X2890897Y-1240233D02*
Y-1231572D01*
G01X2895445D02*
Y-1240233D01*
G01Y-1235903D02*
X2890897D01*
G01X2902373Y-1243120D02*
X2903456Y-1241676D01*
X2903997Y-1240233D01*
Y-1234459D01*
X2903456Y-1233015D01*
X2902373Y-1231572D01*
G01X2847831Y-1191935D02*
X2862690Y-1175519D01*
G01X2849374Y-1184720D02*
X2861536Y-1160411D01*
G01X2848258Y-291925D02*
X2851150D01*
G01X2844321D02*
X2847213D01*
G01X2848258Y-275389D02*
Y-291925D01*
G01X2847213D02*
Y-275389D01*
G01X2844321D02*
Y-291925D01*
G01X2843276D02*
Y-275389D01*
G01X2852195Y-291925D02*
X2855087D01*
G01X2856132D02*
X2859024D01*
G01X2856132Y-275389D02*
Y-291925D01*
G01X2855087D02*
Y-275389D01*
G01X2852195D02*
Y-291925D01*
G01X2851150D02*
Y-275389D01*
G01X2847213D02*
X2844321D01*
G01X2851150D02*
X2848258D01*
G01X2855087D02*
X2852195D01*
G01X2859024D02*
X2856132D01*
G01X2856409Y380492D02*
X2854933D01*
G01X2856409Y386020D02*
Y380492D01*
G01X2854933D02*
Y392303D01*
G01D02*
X2856409D01*
G01Y387528D02*
X2863299D01*
G01Y386020D02*
X2856409D01*
G01Y392303D02*
Y387528D01*
G01X2856586Y515137D02*
G03Y487578I0J-13779D01*
G01X2863476Y501358D02*
G03I-6890J0D01*
G01D02*
G03I-6890J0D01*
G01X2856586Y487578D02*
X2860523D01*
G01X2856586Y505295D02*
Y545804D01*
G01X3084933Y515137D02*
X2856586D01*
G01X2854421Y553383D02*
X2854277Y554141D01*
X2853844Y555007D01*
X2853122Y555548D01*
X2852111Y555765D01*
X2851101Y555548D01*
X2850235Y554899D01*
X2849802Y553924D01*
Y552842D01*
X2849513Y552192D01*
X2848791Y551651D01*
X2847781Y551434D01*
X2846770Y551759D01*
X2846049Y552517D01*
X2845760Y553383D01*
X2846049Y554249D01*
X2846770Y555007D01*
X2847781Y555332D01*
X2848791Y555115D01*
X2849513Y554574D01*
X2849802Y553924D01*
Y552842D01*
X2850235Y551867D01*
X2851101Y551218D01*
X2852111Y551001D01*
X2853122Y551218D01*
X2853844Y551759D01*
X2854277Y552625D01*
X2854421Y553383D01*
G01Y563343D02*
X2845760D01*
X2851967Y559337D01*
Y564751D01*
G01X2854710Y570705D02*
X2854565Y570488D01*
X2854277D01*
X2854132Y570705D01*
X2854277Y570922D01*
X2854565D01*
X2854710Y570705D01*
G01X2852689Y576984D02*
X2853699Y577634D01*
X2854277Y578500D01*
X2854421Y579474D01*
X2854277Y580340D01*
X2853555Y581207D01*
X2852689Y581748D01*
X2851823Y581856D01*
X2850812Y581640D01*
X2850091Y580882D01*
X2849802Y580124D01*
Y579149D01*
G01Y580124D02*
X2849369Y580773D01*
X2848647Y581315D01*
X2847781Y581531D01*
X2846915Y581315D01*
X2846193Y580773D01*
X2845760Y579799D01*
X2845904Y578825D01*
X2846482Y577850D01*
G01X2853122Y585645D02*
X2853844Y586295D01*
X2854277Y587053D01*
X2854421Y588027D01*
X2854132Y589001D01*
X2853555Y589759D01*
X2852545Y590301D01*
X2851390Y590409D01*
X2850235Y590192D01*
X2849513Y589651D01*
X2848936Y588893D01*
X2848791Y588135D01*
X2848936Y587377D01*
X2849513Y586403D01*
X2845760Y586728D01*
Y589651D01*
G01X2853830Y1094074D02*
X2856586D01*
G01X2849893D02*
X2852649D01*
G01X2845956D02*
X2848712D01*
G01X2842019D02*
X2844775D01*
G01X2853830Y1110610D02*
Y1094074D01*
G01X2852649D02*
Y1110610D01*
G01X2849893D02*
Y1094074D01*
G01X2848712D02*
Y1110610D01*
G01X2845956D02*
Y1094074D01*
G01X2844775D02*
Y1110610D01*
G01X2842019D02*
Y1094074D01*
G01X2856586D02*
Y1110610D01*
G01X2844775D02*
X2842019D01*
G01X2848712D02*
X2845956D01*
G01X2852649D02*
X2849893D01*
G01X2856586D02*
X2853830D01*
G01X2865143Y-1223797D02*
X2864060Y-1222353D01*
X2863519Y-1220910D01*
Y-1215136D01*
X2864060Y-1213692D01*
X2865143Y-1212249D01*
G01X2872180Y-1220910D02*
Y-1212249D01*
X2874778D01*
X2875644Y-1212682D01*
X2876294Y-1213692D01*
X2876510Y-1214847D01*
X2876294Y-1216002D01*
X2875752Y-1216868D01*
X2874778Y-1217301D01*
X2872180D01*
G01X2880299Y-1220910D02*
X2883006Y-1212249D01*
X2885713Y-1220910D01*
G01X2884738Y-1217879D02*
X2881274D01*
G01X2889285Y-1220910D02*
Y-1212249D01*
X2891450D01*
X2892317Y-1212682D01*
X2892966Y-1213259D01*
X2893508Y-1214125D01*
X2893941Y-1215136D01*
X2894049Y-1216580D01*
X2893941Y-1218023D01*
X2893508Y-1219034D01*
X2892966Y-1219900D01*
X2892317Y-1220477D01*
X2891450Y-1220910D01*
X2889285D01*
G01X2900869Y-1223797D02*
X2901952Y-1222353D01*
X2902493Y-1220910D01*
Y-1215136D01*
X2901952Y-1213692D01*
X2900869Y-1212249D01*
G01X2865839Y-1175519D02*
X2972663D01*
G01X2862690D02*
X2865839D01*
G01X2874754Y-1158246D02*
Y-1152472D01*
G01Y-1153916D02*
X2875188Y-1153194D01*
X2875837Y-1152616D01*
X2876703Y-1152472D01*
X2877461Y-1152616D01*
X2878111Y-1153194D01*
X2878436Y-1154204D01*
Y-1158246D01*
G01X2864686Y-1160411D02*
X2979305D01*
G01X2861536D02*
X2864686D01*
G01X2875253Y-855208D02*
Y-849434D01*
G01Y-850878D02*
X2875687Y-850156D01*
X2876336Y-849578D01*
X2877202Y-849434D01*
X2877960Y-849578D01*
X2878610Y-850156D01*
X2878935Y-851166D01*
Y-855208D01*
G01X2865185Y-857373D02*
X2972009D01*
G01X2862035D02*
X2865185D01*
G01X2875524Y-835255D02*
Y-829481D01*
G01Y-830925D02*
X2875958Y-830203D01*
X2876607Y-829625D01*
X2877473Y-829481D01*
X2878231Y-829625D01*
X2878881Y-830203D01*
X2879206Y-831213D01*
Y-835255D01*
G01X2865455Y-837420D02*
X2980075D01*
G01X2862306D02*
X2865455D01*
G01X2864006Y-291925D02*
X2866898D01*
G01X2860069D02*
X2862961D01*
G01X2864006Y-275389D02*
Y-291925D01*
G01X2862961D02*
Y-275389D01*
G01X2860069D02*
Y-291925D01*
G01X2859024D02*
Y-275389D01*
G01X2871880Y-291925D02*
X2874772D01*
G01X2867943D02*
X2870835D01*
G01X2871880Y-275389D02*
Y-291925D01*
G01X2870835D02*
Y-275389D01*
G01X2867943D02*
Y-291925D01*
G01X2866898D02*
Y-275389D01*
G01X2862961D02*
X2860069D01*
G01X2866898D02*
X2864006D01*
G01X2870835D02*
X2867943D01*
G01X2874772D02*
X2871880D01*
G01X2864806Y181804D02*
X2865456Y182669D01*
X2866213Y183103D01*
X2867080Y183247D01*
X2868162Y182958D01*
X2868920Y182237D01*
X2869137Y181371D01*
X2869028Y180504D01*
X2868595Y179783D01*
X2866430Y178339D01*
X2865456Y177329D01*
X2864806Y175885D01*
X2864589Y174586D01*
X2869137D01*
G01X2875524Y183247D02*
X2874658Y182958D01*
X2874008Y182237D01*
X2873575Y181371D01*
X2873250Y180216D01*
X2873142Y178916D01*
X2873250Y177617D01*
X2873575Y176462D01*
X2874008Y175596D01*
X2874658Y174875D01*
X2875524Y174586D01*
X2876390Y174875D01*
X2877040Y175596D01*
X2877473Y176462D01*
X2877798Y177617D01*
X2877906Y178916D01*
X2877798Y180216D01*
X2877473Y181371D01*
X2877040Y182237D01*
X2876390Y182958D01*
X2875524Y183247D01*
G01X2884185Y174297D02*
X2883968Y174442D01*
Y174730D01*
X2884185Y174875D01*
X2884402Y174730D01*
Y174442D01*
X2884185Y174297D01*
G01X2890464Y176318D02*
X2891114Y175308D01*
X2891980Y174730D01*
X2892954Y174586D01*
X2893820Y174730D01*
X2894687Y175452D01*
X2895228Y176318D01*
X2895336Y177184D01*
X2895120Y178195D01*
X2894362Y178916D01*
X2893604Y179205D01*
X2892629D01*
G01X2893604D02*
X2894253Y179638D01*
X2894795Y180360D01*
X2895011Y181226D01*
X2894795Y182092D01*
X2894253Y182814D01*
X2893279Y183247D01*
X2892305Y183103D01*
X2891330Y182525D01*
G01X2901507Y183247D02*
X2900641Y182958D01*
X2899991Y182237D01*
X2899558Y181371D01*
X2899233Y180216D01*
X2899125Y178916D01*
X2899233Y177617D01*
X2899558Y176462D01*
X2899991Y175596D01*
X2900641Y174875D01*
X2901507Y174586D01*
X2902373Y174875D01*
X2903023Y175596D01*
X2903456Y176462D01*
X2903781Y177617D01*
X2903889Y178916D01*
X2903781Y180216D01*
X2903456Y181371D01*
X2903023Y182237D01*
X2902373Y182958D01*
X2901507Y183247D01*
G01X2866429Y188956D02*
G03X2893988I13779J0D01*
G01X2887098D02*
G03I-6890J0D01*
G01D02*
G03I-6890J0D01*
G01X2866429Y338563D02*
Y188956D01*
G01X2988476Y200767D02*
X2866429D01*
G01X2877033Y237254D02*
X2877754Y238012D01*
X2878043Y238878D01*
X2877754Y239745D01*
X2876888Y240502D01*
X2875589Y241044D01*
X2874290Y241260D01*
X2872702D01*
X2871403Y241044D01*
X2870248Y240502D01*
X2869671Y239853D01*
X2869382Y239095D01*
X2869671Y238229D01*
X2870248Y237579D01*
X2871114Y237146D01*
X2872269Y236930D01*
X2873279Y237146D01*
X2874290Y237688D01*
X2874867Y238337D01*
X2875012Y239095D01*
X2874723Y239961D01*
X2874001Y240611D01*
X2872702Y241260D01*
G01X2869382Y247756D02*
X2869671Y246890D01*
X2870392Y246240D01*
X2871258Y245807D01*
X2872413Y245482D01*
X2873713Y245374D01*
X2875012Y245482D01*
X2876167Y245807D01*
X2877033Y246240D01*
X2877754Y246890D01*
X2878043Y247756D01*
X2877754Y248622D01*
X2877033Y249272D01*
X2876167Y249705D01*
X2875012Y250030D01*
X2873713Y250138D01*
X2872413Y250030D01*
X2871258Y249705D01*
X2870392Y249272D01*
X2869671Y248622D01*
X2869382Y247756D01*
G01X2878332Y256417D02*
X2878187Y256200D01*
X2877899D01*
X2877754Y256417D01*
X2877899Y256634D01*
X2878187D01*
X2878332Y256417D01*
G01X2876311Y262696D02*
X2877321Y263346D01*
X2877899Y264212D01*
X2878043Y265186D01*
X2877899Y266052D01*
X2877177Y266919D01*
X2876311Y267460D01*
X2875445Y267568D01*
X2874434Y267352D01*
X2873713Y266594D01*
X2873424Y265836D01*
Y264861D01*
G01Y265836D02*
X2872991Y266485D01*
X2872269Y267027D01*
X2871403Y267243D01*
X2870537Y267027D01*
X2869815Y266485D01*
X2869382Y265511D01*
X2869526Y264537D01*
X2870104Y263562D01*
G01X2876744Y271357D02*
X2877466Y272007D01*
X2877899Y272765D01*
X2878043Y273739D01*
X2877754Y274713D01*
X2877177Y275471D01*
X2876167Y276013D01*
X2875012Y276121D01*
X2873857Y275904D01*
X2873135Y275363D01*
X2872558Y274605D01*
X2872413Y273847D01*
X2872558Y273089D01*
X2873135Y272115D01*
X2869382Y272440D01*
Y275363D01*
G01X2866429Y338563D02*
X2988476D01*
G01X2970759Y350374D02*
X2869930D01*
G01X2870681Y384513D02*
X2866744D01*
G01X2864775Y380492D02*
X2863299D01*
G01X2870681Y385518D02*
Y384513D01*
G01X2866744D02*
Y385518D01*
G01X2864775Y392303D02*
Y380492D01*
G01X2863299D02*
Y386020D01*
G01X2875602Y380492D02*
X2874126D01*
G01D02*
Y390293D01*
G01X2863299Y392303D02*
X2864775D01*
G01X2866744Y388533D02*
X2870681D01*
G01Y387528D02*
X2866744D01*
G01Y385518D02*
X2870681D01*
G01Y388533D02*
Y387528D01*
G01X2866744D02*
Y388533D01*
G01X2863299Y387528D02*
Y392303D01*
G01X2874126D02*
X2875602D01*
G01X2874126Y390293D02*
X2872649Y388533D01*
G01Y390544D02*
X2874126Y392303D01*
G01X2872649Y388533D02*
Y390544D01*
G01X3409145Y416712D02*
X2868397D01*
G01D02*
Y515137D01*
G01Y479704D02*
G03X2860523Y487578I-7874J0D01*
G01X2869578Y1094074D02*
X2872334D01*
G01X2865641D02*
X2868397D01*
G01X2857767D02*
X2860523D01*
G01X2861704D02*
X2864460D01*
G01X2869578Y1110610D02*
Y1094074D01*
G01X2868397D02*
Y1110610D01*
G01X2865641D02*
Y1094074D01*
G01X2864460D02*
Y1110610D01*
G01X2861704D02*
Y1094074D01*
G01X2860523D02*
Y1110610D01*
G01X2857767D02*
Y1094074D01*
G01X2873515D02*
X2876271D01*
G01X2873515Y1110610D02*
Y1094074D01*
G01X2872334D02*
Y1110610D01*
G01X2860523D02*
X2857767D01*
G01X2864460D02*
X2861704D01*
G01X2868397D02*
X2865641D01*
G01X2872334D02*
X2869578D01*
G01X2876271D02*
X2873515D01*
G01X2875908Y-1173354D02*
Y-1167580D01*
G01Y-1169024D02*
X2876342Y-1168302D01*
X2876991Y-1167724D01*
X2877857Y-1167580D01*
X2878615Y-1167724D01*
X2879265Y-1168302D01*
X2879590Y-1169312D01*
Y-1173354D01*
G01X2886915Y-1171622D02*
X2887565Y-1172632D01*
X2888431Y-1173210D01*
X2889405Y-1173354D01*
X2890271Y-1173210D01*
X2891138Y-1172488D01*
X2891679Y-1171622D01*
X2891787Y-1170756D01*
X2891571Y-1169745D01*
X2890813Y-1169024D01*
X2890055Y-1168735D01*
X2889080D01*
G01X2890055D02*
X2890704Y-1168302D01*
X2891246Y-1167580D01*
X2891462Y-1166714D01*
X2891246Y-1165848D01*
X2890704Y-1165126D01*
X2889730Y-1164693D01*
X2888756Y-1164837D01*
X2887781Y-1165415D01*
G01X2897958Y-1173643D02*
X2897741Y-1173498D01*
Y-1173210D01*
X2897958Y-1173065D01*
X2898175Y-1173210D01*
Y-1173498D01*
X2897958Y-1173643D01*
G01X2904237Y-1172055D02*
X2904887Y-1172777D01*
X2905645Y-1173210D01*
X2906619Y-1173354D01*
X2907593Y-1173065D01*
X2908351Y-1172488D01*
X2908893Y-1171478D01*
X2909001Y-1170323D01*
X2908784Y-1169168D01*
X2908243Y-1168446D01*
X2907485Y-1167869D01*
X2906727Y-1167724D01*
X2905969Y-1167869D01*
X2904995Y-1168446D01*
X2905320Y-1164693D01*
X2908243D01*
G01X2915280D02*
X2914414Y-1164982D01*
X2913764Y-1165703D01*
X2913331Y-1166569D01*
X2913006Y-1167724D01*
X2912898Y-1169024D01*
X2913006Y-1170323D01*
X2913331Y-1171478D01*
X2913764Y-1172344D01*
X2914414Y-1173065D01*
X2915280Y-1173354D01*
X2916146Y-1173065D01*
X2916796Y-1172344D01*
X2917229Y-1171478D01*
X2917554Y-1170323D01*
X2917662Y-1169024D01*
X2917554Y-1167724D01*
X2917229Y-1166569D01*
X2916796Y-1165703D01*
X2916146Y-1164982D01*
X2915280Y-1164693D01*
G01X2887927Y-1158246D02*
X2888144Y-1156370D01*
X2888469Y-1154782D01*
X2888902Y-1153338D01*
X2889443Y-1151750D01*
X2890309Y-1149585D01*
X2885979D01*
G01X2896805Y-1158535D02*
X2896588Y-1158390D01*
Y-1158102D01*
X2896805Y-1157957D01*
X2897022Y-1158102D01*
Y-1158390D01*
X2896805Y-1158535D01*
G01X2905466Y-1149585D02*
X2904600Y-1149874D01*
X2903950Y-1150595D01*
X2903517Y-1151461D01*
X2903192Y-1152616D01*
X2903084Y-1153916D01*
X2903192Y-1155215D01*
X2903517Y-1156370D01*
X2903950Y-1157236D01*
X2904600Y-1157957D01*
X2905466Y-1158246D01*
X2906332Y-1157957D01*
X2906982Y-1157236D01*
X2907415Y-1156370D01*
X2907740Y-1155215D01*
X2907848Y-1153916D01*
X2907740Y-1152616D01*
X2907415Y-1151461D01*
X2906982Y-1150595D01*
X2906332Y-1149874D01*
X2905466Y-1149585D01*
G01X2914127D02*
X2913261Y-1149874D01*
X2912611Y-1150595D01*
X2912178Y-1151461D01*
X2911853Y-1152616D01*
X2911745Y-1153916D01*
X2911853Y-1155215D01*
X2912178Y-1156370D01*
X2912611Y-1157236D01*
X2913261Y-1157957D01*
X2914127Y-1158246D01*
X2914993Y-1157957D01*
X2915643Y-1157236D01*
X2916076Y-1156370D01*
X2916401Y-1155215D01*
X2916509Y-1153916D01*
X2916401Y-1152616D01*
X2916076Y-1151461D01*
X2915643Y-1150595D01*
X2914993Y-1149874D01*
X2914127Y-1149585D01*
G01X2886261Y-853476D02*
X2886911Y-854486D01*
X2887777Y-855064D01*
X2888751Y-855208D01*
X2889617Y-855064D01*
X2890484Y-854342D01*
X2891025Y-853476D01*
X2891133Y-852610D01*
X2890917Y-851599D01*
X2890159Y-850878D01*
X2889401Y-850589D01*
X2888426D01*
G01X2889401D02*
X2890050Y-850156D01*
X2890592Y-849434D01*
X2890808Y-848568D01*
X2890592Y-847702D01*
X2890050Y-846980D01*
X2889076Y-846547D01*
X2888102Y-846691D01*
X2887127Y-847269D01*
G01X2897304Y-855497D02*
X2897087Y-855352D01*
Y-855064D01*
X2897304Y-854919D01*
X2897521Y-855064D01*
Y-855352D01*
X2897304Y-855497D01*
G01X2903583Y-853909D02*
X2904233Y-854631D01*
X2904991Y-855064D01*
X2905965Y-855208D01*
X2906939Y-854919D01*
X2907697Y-854342D01*
X2908239Y-853332D01*
X2908347Y-852177D01*
X2908130Y-851022D01*
X2907589Y-850300D01*
X2906831Y-849723D01*
X2906073Y-849578D01*
X2905315Y-849723D01*
X2904341Y-850300D01*
X2904666Y-846547D01*
X2907589D01*
G01X2914626D02*
X2913760Y-846836D01*
X2913110Y-847557D01*
X2912677Y-848423D01*
X2912352Y-849578D01*
X2912244Y-850878D01*
X2912352Y-852177D01*
X2912677Y-853332D01*
X2913110Y-854198D01*
X2913760Y-854919D01*
X2914626Y-855208D01*
X2915492Y-854919D01*
X2916142Y-854198D01*
X2916575Y-853332D01*
X2916900Y-852177D01*
X2917008Y-850878D01*
X2916900Y-849578D01*
X2916575Y-848423D01*
X2916142Y-847557D01*
X2915492Y-846836D01*
X2914626Y-846547D01*
G01X2888697Y-835255D02*
X2888914Y-833379D01*
X2889239Y-831791D01*
X2889672Y-830347D01*
X2890213Y-828759D01*
X2891079Y-826594D01*
X2886749D01*
G01X2897575Y-835544D02*
X2897358Y-835399D01*
Y-835111D01*
X2897575Y-834966D01*
X2897792Y-835111D01*
Y-835399D01*
X2897575Y-835544D01*
G01X2906236Y-826594D02*
X2905370Y-826883D01*
X2904720Y-827604D01*
X2904287Y-828470D01*
X2903962Y-829625D01*
X2903854Y-830925D01*
X2903962Y-832224D01*
X2904287Y-833379D01*
X2904720Y-834245D01*
X2905370Y-834966D01*
X2906236Y-835255D01*
X2907102Y-834966D01*
X2907752Y-834245D01*
X2908185Y-833379D01*
X2908510Y-832224D01*
X2908618Y-830925D01*
X2908510Y-829625D01*
X2908185Y-828470D01*
X2907752Y-827604D01*
X2907102Y-826883D01*
X2906236Y-826594D01*
G01X2914897D02*
X2914031Y-826883D01*
X2913381Y-827604D01*
X2912948Y-828470D01*
X2912623Y-829625D01*
X2912515Y-830925D01*
X2912623Y-832224D01*
X2912948Y-833379D01*
X2913381Y-834245D01*
X2914031Y-834966D01*
X2914897Y-835255D01*
X2915763Y-834966D01*
X2916413Y-834245D01*
X2916846Y-833379D01*
X2917171Y-832224D01*
X2917279Y-830925D01*
X2917171Y-829625D01*
X2916846Y-828470D01*
X2916413Y-827604D01*
X2915763Y-826883D01*
X2914897Y-826594D01*
G01X2879754Y-291925D02*
X2882646D01*
G01X2875817D02*
X2878709D01*
G01X2882646D02*
Y-275389D01*
G01X2879754D02*
Y-291925D01*
G01X2878709D02*
Y-275389D01*
G01X2875817D02*
Y-291925D01*
G01X2874772D02*
Y-275389D01*
G01X2887628Y-291925D02*
X2890520D01*
G01X2883691D02*
X2886583D01*
G01X2890520D02*
Y-275389D01*
G01X2887628D02*
Y-291925D01*
G01X2886583D02*
Y-275389D01*
G01X2883691D02*
Y-291925D01*
G01X2878709Y-275389D02*
X2875817D01*
G01X2882646D02*
X2879754D01*
G01X2886583D02*
X2883691D01*
G01X2890520D02*
X2887628D01*
G01X2880208Y192893D02*
Y231517D01*
G01X2976665Y220452D02*
X2878240D01*
G01D02*
Y318878D01*
G01X2880405Y313326D02*
X2883791Y316712D01*
G01X2880405D02*
Y313326D01*
G01X2878240Y318878D02*
X2976665D01*
G01X2880405Y316712D02*
X2883791D01*
G01X2879539Y381748D02*
X2886429D01*
G01Y380492D02*
X2877570D01*
G01X2885691Y387277D02*
X2879539Y381748D01*
G01X2877570D02*
X2884460Y388031D01*
G01X2886429Y381748D02*
Y380492D01*
G01X2877570D02*
Y381748D01*
G01X2875602Y392303D02*
Y380492D01*
G01X2889628D02*
X2888397D01*
G01X2889628Y386774D02*
Y380492D01*
G01X2888397D02*
Y388533D01*
G01X2879047Y391549D02*
X2880031Y392052D01*
G01D02*
X2881754Y392303D01*
G01X2881507Y391046D02*
X2880277Y390795D01*
G01D02*
X2879539Y390293D01*
G01X2881754Y392303D02*
X2882738D01*
G01X2882492Y391046D02*
X2881507D01*
G01X2879047Y389539D02*
X2877817D01*
G01X2878063Y390544D02*
X2879047Y391549D01*
G01X2883722Y390795D02*
X2882492Y391046D01*
G01X2882738Y392303D02*
X2884214Y392052D01*
G01X2886183Y388031D02*
X2885691Y387277D01*
G01X2879539Y390293D02*
X2879047Y389539D01*
G01X2884460Y390293D02*
X2883722Y390795D01*
G01X2884214Y392052D02*
X2885198Y391549D01*
G01X2884460Y388031D02*
X2884952Y389036D01*
G01X2886429D02*
X2886183Y388031D01*
G01Y390544D02*
X2886429Y389539D01*
G01X2884952D02*
X2884460Y390293D01*
G01X2885198Y391549D02*
X2886183Y390544D01*
G01X2877817Y389539D02*
X2878063Y390544D01*
G01X2886429Y389539D02*
Y389036D01*
G01X2884952D02*
Y389539D01*
G01X2890858Y387528D02*
X2890120Y387277D01*
G01Y388282D02*
X2890858Y388533D01*
G01X2888397D02*
X2889628D01*
G01X2890120Y387277D02*
X2889628Y386774D01*
G01Y387780D02*
X2890120Y388282D01*
G01X2889628Y388533D02*
Y387780D01*
G01X2881389Y1094074D02*
X2884145D01*
G01X2885326D02*
X2888082D01*
G01X2877452D02*
X2880208D01*
G01X2885326Y1110610D02*
Y1094074D01*
G01X2884145D02*
Y1110610D01*
G01X2881389D02*
Y1094074D01*
G01X2880208D02*
Y1110610D01*
G01X2877452D02*
Y1094074D01*
G01X2876271D02*
Y1110610D01*
G01X2889263Y1094074D02*
X2892019D01*
G01X2889263Y1110610D02*
Y1094074D01*
G01X2888082D02*
Y1110610D01*
G01X2880208D02*
X2877452D01*
G01X2884145D02*
X2881389D01*
G01X2888082D02*
X2885326D01*
G01X2892019D02*
X2889263D01*
G01X2899439Y-291925D02*
X2902331D01*
G01X2895502D02*
X2898394D01*
G01X2891565D02*
X2894457D01*
G01X2899439Y-275389D02*
Y-291925D01*
G01X2898394D02*
Y-275389D01*
G01X2895502D02*
Y-291925D01*
G01X2894457D02*
Y-275389D01*
G01X2891565D02*
Y-291925D01*
G01X2903376D02*
X2906268D01*
G01D02*
Y-275389D01*
G01X2903376D02*
Y-291925D01*
G01X2902331D02*
Y-275389D01*
G01X2894457D02*
X2891565D01*
G01X2898394D02*
X2895502D01*
G01X2902331D02*
X2899439D01*
G01X2906268D02*
X2903376D01*
G01X2900641Y98523D02*
G03X2908515I3937J0D01*
G01X2901035D02*
Y102460D01*
G01X2900413Y99647D02*
Y99303D01*
G01X2899709Y101025D02*
Y99877D01*
G01X2899475Y100968D02*
Y99934D01*
G01X2898673Y102460D02*
Y98523D01*
G01X2897098Y102460D02*
Y98523D01*
G01D02*
X2901035D01*
G01X2900413Y99303D02*
X2897657Y100221D01*
G01X2899709Y99877D02*
X2900413Y99647D01*
G01X2899475Y99934D02*
X2897892Y100451D01*
G01X2900413Y101255D02*
X2899709Y101025D01*
G01X2897892Y100451D02*
X2899475Y100968D01*
G01X2897657Y100681D02*
X2900413Y101599D01*
G01D02*
Y101255D01*
G01X2897657Y100221D02*
Y100681D01*
G01X2901035Y102460D02*
X2897098D01*
G01X2908122D02*
X2901035D01*
G01X2901862Y200767D02*
G03X2893988Y192893I0J-7874D01*
G01Y188956D02*
Y192893D01*
G01X2903023Y214260D02*
X2909913D01*
G01Y212753D02*
X2903023D01*
G01Y207224D02*
X2901547D01*
G01X2903023Y212753D02*
Y207224D01*
G01Y219035D02*
Y214260D01*
G01X2901547Y207224D02*
Y219035D01*
G01D02*
X2903023D01*
G01X2893565Y380492D02*
X2892334D01*
G01X2897502D02*
X2896271D01*
G01X2900700D02*
X2899470D01*
G01X2904637D02*
X2903407D01*
G01D02*
Y386523D01*
G01X2900700Y386774D02*
Y380492D01*
G01X2899470D02*
Y388533D01*
G01X2897502Y386523D02*
Y380492D01*
G01X2896271D02*
Y386523D01*
G01X2893565D02*
Y380492D01*
G01X2892334D02*
Y386523D01*
G01X2904637D02*
Y380492D01*
G01X2901931Y387528D02*
X2901193Y387277D01*
G01Y388282D02*
X2901931Y388533D01*
G01X2894057Y388282D02*
X2894795Y388533D01*
G01X2894549Y387528D02*
X2894057Y387277D01*
G01X2899470Y388533D02*
X2900700D01*
G01X2901931D02*
X2902915D01*
G01X2894795D02*
X2895779D01*
G01X2890858D02*
X2891842D01*
G01X2895287Y387528D02*
X2894549D01*
G01X2891350D02*
X2890858D01*
G01X2902423D02*
X2901931D01*
G01X2901193Y387277D02*
X2900700Y386774D01*
G01Y387780D02*
X2901193Y388282D01*
G01X2894057Y387277D02*
X2893811Y387026D01*
G01X2893319Y387528D02*
X2894057Y388282D01*
G01X2902915Y388533D02*
X2903653Y388282D01*
G01X2895779Y388533D02*
X2896517Y388282D01*
G01X2891842Y388533D02*
X2892580Y388282D01*
G01X2902915Y387277D02*
X2902423Y387528D01*
G01X2895779Y387277D02*
X2895287Y387528D01*
G01X2891842Y387277D02*
X2891350Y387528D01*
G01X2893811Y387026D02*
X2893565Y386523D01*
G01X2897009Y387780D02*
X2897502Y386523D01*
G01X2903407D02*
X2903161Y387026D01*
G01X2896271Y386523D02*
X2896025Y387026D01*
G01X2892334Y386523D02*
X2892088Y387026D01*
G01X2903653Y388282D02*
X2904391Y387528D01*
G01X2903161Y387026D02*
X2902915Y387277D01*
G01X2896517Y388282D02*
X2897009Y387780D01*
G01X2896025Y387026D02*
X2895779Y387277D01*
G01X2892580Y388282D02*
X2893319Y387528D01*
G01X2892088Y387026D02*
X2891842Y387277D01*
G01X2900700Y388533D02*
Y387780D01*
G01X2905130Y388282D02*
X2905868Y388533D01*
G01X2905622Y387528D02*
X2905130Y387277D01*
G01X2905868Y388533D02*
X2906852D01*
G01X2906360Y387528D02*
X2905622D01*
G01X2905130Y387277D02*
X2904883Y387026D01*
G01X2904391Y387528D02*
X2905130Y388282D01*
G01X2906852Y388533D02*
X2907590Y388282D01*
G01X2904883Y387026D02*
X2904637Y386523D01*
G01X2906852Y387277D02*
X2906360Y387528D01*
G01X2907098Y387026D02*
X2906852Y387277D01*
G01X2894145Y722933D02*
X2891193D01*
G01X2894145Y733990D02*
Y722933D01*
G01X2891193D02*
Y746555D01*
G01X2894145Y737006D02*
X2907925D01*
G01Y733990D02*
X2894145D01*
G01Y746555D02*
Y737006D01*
G01X2891193Y746555D02*
X2894145D01*
G01X2901074Y1094074D02*
X2903830D01*
G01X2897137D02*
X2899893D01*
G01X2893200D02*
X2895956D01*
G01X2901074Y1110610D02*
Y1094074D01*
G01X2899893D02*
Y1110610D01*
G01X2897137D02*
Y1094074D01*
G01X2895956D02*
Y1110610D01*
G01X2893200D02*
Y1094074D01*
G01X2892019D02*
Y1110610D01*
G01X2905011Y1094074D02*
X2907767D01*
G01X2905011Y1110610D02*
Y1094074D01*
G01X2903830D02*
Y1110610D01*
G01X2895956D02*
X2893200D01*
G01X2899893D02*
X2897137D01*
G01X2903830D02*
X2901074D01*
G01X2907767D02*
X2905011D01*
G01X2907348Y-1837784D02*
Y-1856796D01*
G01X2919937Y-1176241D02*
X2918854Y-1174797D01*
X2918313Y-1173354D01*
Y-1167580D01*
X2918854Y-1166136D01*
X2919937Y-1164693D01*
G01X2926649Y-1173354D02*
Y-1164693D01*
X2931629Y-1173354D01*
Y-1164693D01*
G01X2935635Y-1173354D02*
Y-1164693D01*
X2938233D01*
X2939099Y-1165126D01*
X2939749Y-1166136D01*
X2939965Y-1167291D01*
X2939749Y-1168446D01*
X2939207Y-1169312D01*
X2938233Y-1169745D01*
X2935635D01*
G01X2946461Y-1164693D02*
Y-1173354D01*
G01X2943971Y-1164693D02*
X2948951D01*
G01X2952848Y-1173354D02*
Y-1164693D01*
G01X2957396D02*
Y-1173354D01*
G01Y-1169024D02*
X2952848D01*
G01X2964324Y-1176241D02*
X2965407Y-1174797D01*
X2965948Y-1173354D01*
Y-1167580D01*
X2965407Y-1166136D01*
X2964324Y-1164693D01*
G01X2918784Y-1161133D02*
X2917701Y-1159689D01*
X2917160Y-1158246D01*
Y-1152472D01*
X2917701Y-1151028D01*
X2918784Y-1149585D01*
G01X2926145Y-1158246D02*
Y-1149585D01*
G01Y-1153771D02*
X2926687Y-1153049D01*
X2927228Y-1152616D01*
X2928094Y-1152472D01*
X2928744Y-1152616D01*
X2929502Y-1153194D01*
X2929827Y-1154060D01*
Y-1158246D01*
G01X2935240Y-1156658D02*
X2938054D01*
G01Y-1154060D02*
X2935240D01*
G01X2945308Y-1149585D02*
X2944442Y-1149874D01*
X2943792Y-1150595D01*
X2943359Y-1151461D01*
X2943034Y-1152616D01*
X2942926Y-1153916D01*
X2943034Y-1155215D01*
X2943359Y-1156370D01*
X2943792Y-1157236D01*
X2944442Y-1157957D01*
X2945308Y-1158246D01*
X2946174Y-1157957D01*
X2946824Y-1157236D01*
X2947257Y-1156370D01*
X2947582Y-1155215D01*
X2947690Y-1153916D01*
X2947582Y-1152616D01*
X2947257Y-1151461D01*
X2946824Y-1150595D01*
X2946174Y-1149874D01*
X2945308Y-1149585D01*
G01X2950721Y-1158246D02*
Y-1152472D01*
G01Y-1154060D02*
X2951046Y-1153338D01*
X2951587Y-1152761D01*
X2952345Y-1152472D01*
X2953103Y-1152761D01*
X2953644Y-1153338D01*
X2953969Y-1154060D01*
Y-1158246D01*
G01Y-1154060D02*
X2954294Y-1153338D01*
X2954835Y-1152761D01*
X2955593Y-1152472D01*
X2956351Y-1152761D01*
X2956892Y-1153338D01*
X2957217Y-1154204D01*
Y-1158246D01*
G01X2959382D02*
Y-1152472D01*
G01Y-1154060D02*
X2959707Y-1153338D01*
X2960248Y-1152761D01*
X2961006Y-1152472D01*
X2961764Y-1152761D01*
X2962305Y-1153338D01*
X2962630Y-1154060D01*
Y-1158246D01*
G01Y-1154060D02*
X2962955Y-1153338D01*
X2963496Y-1152761D01*
X2964254Y-1152472D01*
X2965012Y-1152761D01*
X2965553Y-1153338D01*
X2965878Y-1154204D01*
Y-1158246D01*
G01X2971832Y-1161133D02*
X2972915Y-1159689D01*
X2973456Y-1158246D01*
Y-1152472D01*
X2972915Y-1151028D01*
X2971832Y-1149585D01*
G01X2919283Y-858095D02*
X2918200Y-856651D01*
X2917659Y-855208D01*
Y-849434D01*
X2918200Y-847990D01*
X2919283Y-846547D01*
G01X2925995Y-855208D02*
Y-846547D01*
X2930975Y-855208D01*
Y-846547D01*
G01X2934981Y-855208D02*
Y-846547D01*
X2937579D01*
X2938445Y-846980D01*
X2939095Y-847990D01*
X2939311Y-849145D01*
X2939095Y-850300D01*
X2938553Y-851166D01*
X2937579Y-851599D01*
X2934981D01*
G01X2945807Y-846547D02*
Y-855208D01*
G01X2943317Y-846547D02*
X2948297D01*
G01X2952194Y-855208D02*
Y-846547D01*
G01X2956742D02*
Y-855208D01*
G01Y-850878D02*
X2952194D01*
G01X2963670Y-858095D02*
X2964753Y-856651D01*
X2965294Y-855208D01*
Y-849434D01*
X2964753Y-847990D01*
X2963670Y-846547D01*
G01X2919554Y-838142D02*
X2918471Y-836698D01*
X2917930Y-835255D01*
Y-829481D01*
X2918471Y-828037D01*
X2919554Y-826594D01*
G01X2926915Y-835255D02*
Y-826594D01*
G01Y-830780D02*
X2927457Y-830058D01*
X2927998Y-829625D01*
X2928864Y-829481D01*
X2929514Y-829625D01*
X2930272Y-830203D01*
X2930597Y-831069D01*
Y-835255D01*
G01X2936010Y-833667D02*
X2938824D01*
G01Y-831069D02*
X2936010D01*
G01X2946078Y-826594D02*
X2945212Y-826883D01*
X2944562Y-827604D01*
X2944129Y-828470D01*
X2943804Y-829625D01*
X2943696Y-830925D01*
X2943804Y-832224D01*
X2944129Y-833379D01*
X2944562Y-834245D01*
X2945212Y-834966D01*
X2946078Y-835255D01*
X2946944Y-834966D01*
X2947594Y-834245D01*
X2948027Y-833379D01*
X2948352Y-832224D01*
X2948460Y-830925D01*
X2948352Y-829625D01*
X2948027Y-828470D01*
X2947594Y-827604D01*
X2946944Y-826883D01*
X2946078Y-826594D01*
G01X2951491Y-835255D02*
Y-829481D01*
G01Y-831069D02*
X2951816Y-830347D01*
X2952357Y-829770D01*
X2953115Y-829481D01*
X2953873Y-829770D01*
X2954414Y-830347D01*
X2954739Y-831069D01*
Y-835255D01*
G01Y-831069D02*
X2955064Y-830347D01*
X2955605Y-829770D01*
X2956363Y-829481D01*
X2957121Y-829770D01*
X2957662Y-830347D01*
X2957987Y-831213D01*
Y-835255D01*
G01X2960152D02*
Y-829481D01*
G01Y-831069D02*
X2960477Y-830347D01*
X2961018Y-829770D01*
X2961776Y-829481D01*
X2962534Y-829770D01*
X2963075Y-830347D01*
X2963400Y-831069D01*
Y-835255D01*
G01Y-831069D02*
X2963725Y-830347D01*
X2964266Y-829770D01*
X2965024Y-829481D01*
X2965782Y-829770D01*
X2966323Y-830347D01*
X2966648Y-831213D01*
Y-835255D01*
G01X2972602Y-838142D02*
X2973685Y-836698D01*
X2974226Y-835255D01*
Y-829481D01*
X2973685Y-828037D01*
X2972602Y-826594D01*
G01X2915187Y-291925D02*
X2918079D01*
G01X2911250D02*
X2914142D01*
G01X2907313D02*
X2910205D01*
G01X2915187Y-275389D02*
Y-291925D01*
G01X2914142D02*
Y-275389D01*
G01X2911250D02*
Y-291925D01*
G01X2910205D02*
Y-275389D01*
G01X2907313D02*
Y-291925D01*
G01X2923061D02*
X2925953D01*
G01X2919124D02*
X2922016D01*
G01X2923061Y-275389D02*
Y-291925D01*
G01X2922016D02*
Y-275389D01*
G01X2919124D02*
Y-291925D01*
G01X2918079D02*
Y-275389D01*
G01X2910205D02*
X2907313D01*
G01X2914142D02*
X2911250D01*
G01X2918079D02*
X2915187D01*
G01X2922016D02*
X2919124D01*
G01X2925953D02*
X2923061D01*
G01X2912059Y102460D02*
Y98523D01*
G01X2911693Y99919D02*
Y99574D01*
G01X2910484Y98523D02*
Y102460D01*
G01X2908937Y99574D02*
Y99919D01*
G01X2908122Y98523D02*
Y102460D01*
G01X2908937Y99919D02*
X2910285D01*
G01X2910754D02*
X2911693D01*
G01Y99574D02*
X2908937D01*
G01X2912059Y98523D02*
X2908122D01*
G01X2910344Y100321D02*
X2910754Y99919D01*
G01X2910285D02*
X2908937Y101182D01*
G01X2955405Y116122D02*
G03I-17716J0D01*
G01X2910051Y100608D02*
X2911693Y101641D01*
G01Y101182D02*
X2910344Y100321D01*
G01X2911693Y101641D02*
Y101182D01*
G01X2908937D02*
Y101641D01*
G01X2908122Y102460D02*
X2912059D01*
G01X2908937Y101641D02*
X2910051Y100608D01*
G01X3011507Y172421D02*
X2909085D01*
G01X2917295Y214260D02*
X2913358D01*
G01Y212250D02*
X2917295D01*
G01Y211245D02*
X2913358D01*
G01X2911389Y207224D02*
X2909913D01*
G01X2917295Y212250D02*
Y211245D01*
G01Y215266D02*
Y214260D01*
G01X2913358D02*
Y215266D01*
G01Y211245D02*
Y212250D01*
G01X2911389Y219035D02*
Y207224D01*
G01X2909913Y214260D02*
Y219035D01*
G01Y207224D02*
Y212753D01*
G01X2920740Y217025D02*
X2919263Y215266D01*
G01Y217276D02*
X2920740Y219035D01*
G01X2909913D02*
X2911389D01*
G01X2913358Y215266D02*
X2917295D01*
G01X2919263D02*
Y217276D01*
G01X2922216Y207224D02*
X2920740D01*
G01X2922216Y219035D02*
Y207224D01*
G01X2920740D02*
Y217025D01*
G01Y219035D02*
X2922216D01*
G01X2947334Y247500D02*
X2907570D01*
G01D02*
Y291830D01*
G01D02*
X2947334D01*
G01X2908574Y380492D02*
X2907344D01*
G01X2908574Y386523D02*
Y380492D01*
G01X2907344D02*
Y386523D01*
G01X2908082Y387780D02*
X2908574Y386523D01*
G01X2907344D02*
X2907098Y387026D01*
G01X2907590Y388282D02*
X2908082Y387780D01*
G01X2910878Y722933D02*
X2907925D01*
G01X2910878Y746555D02*
Y722933D01*
G01X2907925D02*
Y733990D01*
G01X2914815Y739016D02*
X2922689D01*
G01Y737006D02*
X2914815D01*
G01Y732985D02*
X2922689D01*
G01Y730974D02*
X2914815D01*
G01Y737006D02*
Y739016D01*
G01Y730974D02*
Y732985D01*
G01X2907925Y737006D02*
Y746555D01*
G01X2922689Y732985D02*
Y730974D01*
G01Y739016D02*
Y737006D01*
G01X2907925Y746555D02*
X2910878D01*
G01X2916822Y1094074D02*
X2919578D01*
G01X2908948D02*
X2911704D01*
G01X2912885D02*
X2915641D01*
G01X2919578D02*
Y1110610D01*
G01X2916822D02*
Y1094074D01*
G01X2915641D02*
Y1110610D01*
G01X2912885D02*
Y1094074D01*
G01X2911704D02*
Y1110610D01*
G01X2908948D02*
Y1094074D01*
G01X2907767D02*
Y1110610D01*
G01X2920759Y1094074D02*
X2923515D01*
G01X2920759Y1110610D02*
Y1094074D01*
G01X2911704Y1110610D02*
X2908948D01*
G01X2915641D02*
X2912885D01*
G01X2919578D02*
X2916822D01*
G01X2923515D02*
X2920759D01*
G01X2907348Y1453929D02*
Y1434916D01*
G01X2951476Y-1035626D02*
G03I-13780J0D01*
G01X2944586D02*
G03I-6890J0D01*
G01X2926998Y-291925D02*
X2929890D01*
G01X2930935D02*
X2933827D01*
G01X2930935Y-275389D02*
Y-291925D01*
G01X2929890D02*
Y-275389D01*
G01X2926998D02*
Y-291925D01*
G01X2925953D02*
Y-275389D01*
G01X2938809Y-291925D02*
X2941701D01*
G01X2934872D02*
X2937764D01*
G01X2938809Y-275389D02*
Y-291925D01*
G01X2937764D02*
Y-275389D01*
G01X2934872D02*
Y-291925D01*
G01X2933827D02*
Y-275389D01*
G01X2929890D02*
X2926998D01*
G01X2933827D02*
X2930935D01*
G01X2937764D02*
X2934872D01*
G01X2941701D02*
X2938809D01*
G01X2945757Y109822D02*
G03X2929620I-8069J6300D01*
G01X2926700Y113896D02*
X2926193Y113292D01*
G01Y113982D02*
X2926700Y114586D01*
G01X2928437Y115137D02*
Y117106D01*
G01X2927206Y114586D02*
Y110531D01*
G01X2926700D02*
Y113896D01*
G01X2926468Y117106D02*
Y115137D01*
G01X2926193Y113292D02*
Y113982D01*
G01X2926468Y115137D02*
X2928437D01*
G01X2926700Y114586D02*
X2927206D01*
G01Y110531D02*
X2926700D01*
G01X2929620Y109822D02*
X2945757D01*
G01X2928437Y117106D02*
X2926468D01*
G01X2938673Y115137D02*
Y117106D01*
G01X2936704D02*
Y115137D01*
G01D02*
X2938673D01*
G01Y117106D02*
X2936704D01*
G01X2933781Y207475D02*
X2935011Y208229D01*
G01X2929844Y214512D02*
X2928614Y213758D01*
G01X2934273Y209235D02*
X2933535Y208732D01*
G01X2929106Y212501D02*
X2930090Y213255D01*
G01X2935011Y208229D02*
X2935750Y209235D01*
G01X2934765Y209988D02*
X2934273Y209235D01*
G01X2935750D02*
X2936242Y210491D01*
G01X2931074Y214763D02*
X2929844Y214512D01*
G01X2930090Y213255D02*
X2931074Y213507D01*
G01X2933535Y208732D02*
X2932551Y208481D01*
G01X2935011Y210742D02*
X2934765Y209988D01*
G01X2932551Y207224D02*
X2933781Y207475D01*
G01X2936242Y210491D02*
Y211496D01*
G01X2935011Y211245D02*
Y210742D01*
G01X2928614Y213758D02*
Y217779D01*
G01X2927383Y219035D02*
Y212501D01*
G01X2925415Y208481D02*
Y207224D01*
G01X2924185D02*
Y208481D01*
G01X2933781Y214512D02*
X2932551Y214763D01*
G01D02*
X2931074D01*
G01Y213507D02*
X2932551D01*
G01X2927383Y212501D02*
X2929106D01*
G01X2928860Y210240D02*
X2927383D01*
G01X2924185Y208481D02*
X2925415D01*
G01X2932551D02*
X2931074D01*
G01Y207224D02*
X2932551D01*
G01X2925415D02*
X2924185D01*
G01X2934765Y211999D02*
X2935011Y211245D01*
G01X2936242Y211496D02*
X2935750Y212753D01*
G01X2929352Y209235D02*
X2928860Y210240D01*
G01X2927383D02*
X2927876Y209235D01*
G01X2934273Y212753D02*
X2934765Y211999D01*
G01X2935750Y212753D02*
X2935011Y213758D01*
G01X2927876Y209235D02*
X2928614Y208229D01*
G01X2933535Y213255D02*
X2934273Y212753D01*
G01X2930090Y208732D02*
X2929352Y209235D01*
G01X2935011Y213758D02*
X2933781Y214512D01*
G01X2928614Y208229D02*
X2929844Y207475D01*
G01X2932551Y213507D02*
X2933535Y213255D01*
G01X2931074Y208481D02*
X2930090Y208732D01*
G01X2929844Y207475D02*
X2931074Y207224D01*
G01X2935750Y219035D02*
X2927383D01*
G01X2928614Y217779D02*
X2935750D01*
G01D02*
Y219035D01*
G01X2939933Y214009D02*
X2939441Y213507D01*
G01Y214512D02*
X2939933Y215014D01*
G01X2939441Y213507D02*
Y207224D01*
G01Y215266D02*
Y214512D01*
G01X2938210Y207224D02*
Y215266D01*
G01X2939441Y207224D02*
X2938210D01*
G01Y215266D02*
X2939441D01*
G01X2927814Y417074D02*
X2932263D01*
G01X3029815Y412775D02*
X2923515D01*
G01X2932263Y417074D02*
X2927814Y421522D01*
G01Y417074D02*
Y421522D01*
G01X2923515Y519074D02*
Y412775D01*
G01X3029815Y519074D02*
X2923515D01*
G01X2944342Y722933D02*
X2926626D01*
G01D02*
Y725446D01*
G01X2930563D02*
X2944342D01*
G01X2942866Y736503D02*
X2930563Y725446D01*
G01X2926626D02*
X2940405Y738011D01*
G01X2934500Y744042D02*
X2932039Y743539D01*
G01X2936468Y744042D02*
X2934500D01*
G01X2929578Y741026D02*
X2927118D01*
G01X2938929Y743539D02*
X2936468Y744042D01*
G01X2929578Y745047D02*
X2931547Y746052D01*
G01X2932039Y743539D02*
X2930563Y742534D01*
G01X2927118Y741026D02*
X2927610Y743037D01*
G01D02*
X2929578Y745047D01*
G01X2930563Y742534D02*
X2929578Y741026D01*
G01X2940405Y742534D02*
X2938929Y743539D01*
G01X2931547Y746052D02*
X2934992Y746555D01*
G01D02*
X2936960D01*
G01D02*
X2939913Y746052D01*
G01X2932570Y1094074D02*
X2935326D01*
G01X2936507D02*
X2939263D01*
G01X2928633D02*
X2931389D01*
G01X2924696D02*
X2927452D01*
G01X2936507Y1110610D02*
Y1094074D01*
G01X2935326D02*
Y1110610D01*
G01X2932570D02*
Y1094074D01*
G01X2931389D02*
Y1110610D01*
G01X2928633D02*
Y1094074D01*
G01X2927452D02*
Y1110610D01*
G01X2924696D02*
Y1094074D01*
G01X2923515D02*
Y1110610D01*
G01X2939263Y1094074D02*
Y1110610D01*
G01X2927452D02*
X2924696D01*
G01X2931389D02*
X2928633D01*
G01X2935326D02*
X2932570D01*
G01X2939263D02*
X2936507D01*
G01X2943644Y-1048056D02*
X2966302Y-1095411D01*
G01X2942181Y-1040856D02*
X2972955Y-1076752D01*
G01X2946683Y-291925D02*
X2949575D01*
G01X2942746D02*
X2945638D01*
G01X2946683Y-275389D02*
Y-291925D01*
G01X2945638D02*
Y-275389D01*
G01X2942746D02*
Y-291925D01*
G01X2941701D02*
Y-275389D01*
G01X2950620Y-291925D02*
X2953513D01*
G01X2954557D02*
X2957450D01*
G01X2954557Y-275389D02*
Y-291925D01*
G01X2953513D02*
Y-275389D01*
G01X2950620D02*
Y-291925D01*
G01X2949575D02*
Y-275389D01*
G01X2945638D02*
X2942746D01*
G01X2949575D02*
X2946683D01*
G01X2953513D02*
X2950620D01*
G01X2957450D02*
X2954557D01*
G01X2948279Y98523D02*
Y102460D01*
G01X2947885Y98523D02*
Y102460D01*
G01X2947657Y99647D02*
Y99303D01*
G01X2946954Y101025D02*
Y99877D01*
G01X2946719Y100968D02*
Y99934D01*
G01X2945917Y102460D02*
Y98523D01*
G01X2944342Y102460D02*
Y98523D01*
G01X2948279D02*
X2955366D01*
G01X2944342D02*
X2948279D01*
G01X2947657Y99303D02*
X2944901Y100221D01*
G01X2946954Y99877D02*
X2947657Y99647D01*
G01X2946719Y99934D02*
X2945136Y100451D01*
G01X2947657Y101255D02*
X2946954Y101025D01*
G01X2945136Y100451D02*
X2946719Y100968D01*
G01X2944901Y100681D02*
X2947657Y101599D01*
G01D02*
Y101255D01*
G01X2944901Y100221D02*
Y100681D01*
G01X2948279Y102460D02*
X2955366D01*
G01X2948279D02*
X2944342D01*
G01X2956181Y99574D02*
Y99919D01*
G01X2955759Y98523D02*
Y102460D01*
G01X2955366Y98523D02*
Y102460D01*
G01X2956181Y99919D02*
X2957530D01*
G01X2958937Y99574D02*
X2956181D01*
G01X2959303Y98523D02*
X2955366D01*
G01X2957530Y99919D02*
X2956181Y101182D01*
G01D02*
Y101641D01*
G01X2955366Y102460D02*
X2959303D01*
G01X2956181Y101641D02*
X2957295Y100608D01*
G01X2948909Y115137D02*
Y117106D01*
G01X2946941D02*
Y115137D01*
G01D02*
X2948909D01*
G01Y117106D02*
X2946941D01*
G01X2946407Y131545D02*
X2953091Y143369D01*
G01X2956241D02*
X3070860D01*
G01X2953091D02*
X2956241D01*
G01X2951744Y214260D02*
X2951006Y214009D01*
G01Y215014D02*
X2951744Y215266D01*
G01X2943870Y215014D02*
X2944608Y215266D01*
G01X2940671Y214260D02*
X2939933Y214009D01*
G01Y215014D02*
X2940671Y215266D01*
G01X2944362Y214260D02*
X2943870Y214009D01*
G01X2951006D02*
X2950513Y213507D01*
G01Y214512D02*
X2951006Y215014D01*
G01X2943870Y214009D02*
X2943624Y213758D01*
G01X2943132Y214260D02*
X2943870Y215014D01*
G01X2943624Y213758D02*
X2943378Y213255D01*
G01X2950513Y213507D02*
Y207224D01*
G01Y215266D02*
Y214512D01*
G01X2949283Y207224D02*
Y215266D01*
G01X2947315Y213255D02*
Y207224D01*
G01X2946084D02*
Y213255D01*
G01X2943378D02*
Y207224D01*
G01X2942147D02*
Y213255D01*
G01X2941163Y214260D02*
X2940671D01*
G01X2945100D02*
X2944362D01*
G01X2952236D02*
X2951744D01*
G01X2947315Y207224D02*
X2946084D01*
G01X2943378D02*
X2942147D01*
G01X2950513D02*
X2949283D01*
G01X2946822Y214512D02*
X2947315Y213255D01*
G01X2953220D02*
X2952974Y213758D01*
G01X2946084Y213255D02*
X2945838Y213758D01*
G01X2942147Y213255D02*
X2941901Y213758D01*
G01X2952974D02*
X2952728Y214009D01*
G01X2946330Y215014D02*
X2946822Y214512D01*
G01X2945838Y213758D02*
X2945592Y214009D01*
G01X2942393Y215014D02*
X2943132Y214260D01*
G01X2941901Y213758D02*
X2941655Y214009D01*
G01X2952728D02*
X2952236Y214260D01*
G01X2945592Y214009D02*
X2945100Y214260D01*
G01X2941655Y214009D02*
X2941163Y214260D01*
G01X2945592Y215266D02*
X2946330Y215014D01*
G01X2941655Y215266D02*
X2942393Y215014D01*
G01X2951744Y215266D02*
X2952728D01*
G01X2949283D02*
X2950513D01*
G01X2944608D02*
X2945592D01*
G01X2940671D02*
X2941655D01*
G01X2952728D02*
X2953466Y215014D01*
G01X2954943D02*
X2955681Y215266D01*
G01X2955435Y214260D02*
X2954943Y214009D01*
G01D02*
X2954696Y213758D01*
G01X2954204Y214260D02*
X2954943Y215014D01*
G01X2954696Y213758D02*
X2954450Y213255D01*
G01D02*
Y207224D01*
G01X2953220D02*
Y213255D01*
G01X2956173Y214260D02*
X2955435D01*
G01X2954450Y207224D02*
X2953220D01*
G01X2953466Y215014D02*
X2954204Y214260D01*
G01X2956665Y214009D02*
X2956173Y214260D01*
G01X2955681Y215266D02*
X2956665D01*
G01X2947334Y291830D02*
Y247500D01*
G01X2953043Y338563D02*
G03X2960917Y346437I0J7874D01*
G01X2947354Y425570D02*
X2945878D01*
G01X2947354Y431099D02*
Y425570D01*
G01X2945878D02*
Y437381D01*
G01X2947354Y432607D02*
X2954244D01*
G01Y431099D02*
X2947354D01*
G01Y437381D02*
Y432607D01*
G01X2955720Y425570D02*
X2954244D01*
G01X2955720Y437381D02*
Y425570D01*
G01X2954244D02*
Y431099D01*
G01Y432607D02*
Y437381D01*
G01X2945878D02*
X2947354D01*
G01X2954244D02*
X2955720D01*
G01X2950740Y722933D02*
X2948279D01*
G01X2950740Y725446D02*
Y722933D01*
G01X2948279D02*
Y725446D01*
G01X2944342D02*
Y722933D01*
G01X2948279Y725446D02*
X2950740D01*
G01X2944342Y741026D02*
Y740021D01*
G01X2941389D02*
Y741026D01*
G01X2943850Y738011D02*
X2942866Y736503D01*
G01X2940405Y738011D02*
X2941389Y740021D01*
G01X2944342D02*
X2943850Y738011D01*
G01X2939913Y746052D02*
X2941882Y745047D01*
G01D02*
X2943850Y743037D01*
G01X2941389Y741026D02*
X2940405Y742534D01*
G01X2943850Y743037D02*
X2944342Y741026D01*
G01X2954677Y739016D02*
Y743037D01*
G01X2957630Y742534D02*
X2954677Y739016D01*
G01Y743037D02*
X2957630Y746555D01*
G01X2952256Y1094074D02*
X2955011D01*
G01X2948319D02*
X2951074D01*
G01X2944382D02*
X2947137D01*
G01X2940445D02*
X2943200D01*
G01X2952256Y1110610D02*
Y1094074D01*
G01X2951074D02*
Y1110610D01*
G01X2948319D02*
Y1094074D01*
G01X2947137D02*
Y1110610D01*
G01X2944382D02*
Y1094074D01*
G01X2943200D02*
Y1110610D01*
G01X2940445D02*
Y1094074D01*
G01X2956193D02*
X2958948D01*
G01X2956193Y1110610D02*
Y1094074D01*
G01X2955011D02*
Y1110610D01*
G01X2943200D02*
X2940445D01*
G01X2947137D02*
X2944382D01*
G01X2951074D02*
X2948319D01*
G01X2955011D02*
X2952256D01*
G01X2958948D02*
X2956193D01*
G01X2994192Y-1213578D02*
G03I-15748J0D01*
G01X2984744D02*
G03I-6300J0D01*
G01X2969452Y-1095411D02*
X3084071D01*
G01X2966302D02*
X2969452D01*
G01X2994192Y-1038382D02*
G03I-15748J0D01*
G01X2984744D02*
G03I-6300J0D01*
G01X2962431Y-291925D02*
X2965324D01*
G01X2958494D02*
X2961387D01*
G01X2962431Y-275389D02*
Y-291925D01*
G01X2961387D02*
Y-275389D01*
G01X2958494D02*
Y-291925D01*
G01X2957450D02*
Y-275389D01*
G01X2970305Y-291925D02*
X2973198D01*
G01X2966368D02*
X2969261D01*
G01X2970305Y-275389D02*
Y-291925D01*
G01X2969261D02*
Y-275389D01*
G01X2966368D02*
Y-291925D01*
G01X2965324D02*
Y-275389D01*
G01X2961387D02*
X2958494D01*
G01X2965324D02*
X2962431D01*
G01X2969261D02*
X2966368D01*
G01X2973198D02*
X2970305D01*
G01X2959303Y102460D02*
Y98523D01*
G01X2958937Y99919D02*
Y99574D01*
G01X2957728Y98523D02*
Y102460D01*
G01X2957998Y99919D02*
X2958937D01*
G01X2957588Y100321D02*
X2957998Y99919D01*
G01X2957295Y100608D02*
X2958937Y101641D01*
G01Y101182D02*
X2957588Y100321D01*
G01X2958937Y101641D02*
Y101182D01*
G01X2966309Y145535D02*
Y151309D01*
G01Y149865D02*
X2966743Y150587D01*
X2967392Y151165D01*
X2968258Y151309D01*
X2969016Y151165D01*
X2969666Y150587D01*
X2969991Y149577D01*
Y145535D01*
G01X2958387Y213255D02*
Y207224D01*
G01X2957157D02*
Y213255D01*
G01X2957895Y214512D02*
X2958387Y213255D01*
G01Y207224D02*
X2957157D01*
G01Y213255D02*
X2956911Y213758D01*
G01X2957403Y215014D02*
X2957895Y214512D01*
G01X2956911Y213758D02*
X2956665Y214009D01*
G01Y215266D02*
X2957403Y215014D01*
G01X2981586Y350374D02*
G03I-6889J0D01*
G01D02*
G03I-6889J0D01*
G01X2960917D02*
Y346437D01*
G01X2988476Y350374D02*
G03X2960917I-13780J0D01*
G01X2968515Y426827D02*
X2969746D01*
G01Y425570D02*
X2968515D01*
G01X2966547D02*
X2965070D01*
G01X2968515D02*
Y426827D01*
G01X2966547Y437381D02*
Y425570D01*
G01X2965070D02*
Y435371D01*
G01X2957689Y433612D02*
X2961626D01*
G01Y432607D02*
X2957689D01*
G01Y430596D02*
X2961626D01*
G01Y429591D02*
X2957689D01*
G01X2965070Y435371D02*
X2963594Y433612D01*
G01D02*
Y435622D01*
G01X2961626Y430596D02*
Y429591D01*
G01Y433612D02*
Y432607D01*
G01X2957689Y429591D02*
Y430596D01*
G01Y432607D02*
Y433612D01*
G01X2971714Y428586D02*
X2972206Y427581D01*
G01D02*
X2972945Y426576D01*
G01X2969746Y426827D02*
Y425570D01*
G01X2971714Y430848D02*
X2973437D01*
G01X2973191Y428586D02*
X2971714D01*
G01Y437381D02*
Y430848D01*
G01X2994637Y442441D02*
X2958693D01*
G01X2965070Y437381D02*
X2966547D01*
G01X2963594Y435622D02*
X2965070Y437381D01*
G01X2958693Y442441D02*
Y489409D01*
G01X2980080Y437381D02*
X2971714D01*
G01X2958693Y489409D02*
X2994637D01*
G01X2972531Y537761D02*
X2963870D01*
X2965602Y536462D01*
G01X2972531D02*
Y539060D01*
G01Y546422D02*
X2963870D01*
X2965602Y545123D01*
G01X2972531D02*
Y547721D01*
G01Y556382D02*
X2963870D01*
X2970077Y552376D01*
Y557790D01*
G01X2972820Y563744D02*
X2972675Y563527D01*
X2972387D01*
X2972242Y563744D01*
X2972387Y563961D01*
X2972675D01*
X2972820Y563744D01*
G01X2970799Y570023D02*
X2971809Y570673D01*
X2972387Y571539D01*
X2972531Y572513D01*
X2972387Y573379D01*
X2971665Y574246D01*
X2970799Y574787D01*
X2969933Y574895D01*
X2968922Y574679D01*
X2968201Y573921D01*
X2967912Y573163D01*
Y572188D01*
G01Y573163D02*
X2967479Y573812D01*
X2966757Y574354D01*
X2965891Y574570D01*
X2965025Y574354D01*
X2964303Y573812D01*
X2963870Y572838D01*
X2964014Y571864D01*
X2964592Y570889D01*
G01X2971232Y578684D02*
X2971954Y579334D01*
X2972387Y580092D01*
X2972531Y581066D01*
X2972242Y582040D01*
X2971665Y582798D01*
X2970655Y583340D01*
X2969500Y583448D01*
X2968345Y583231D01*
X2967623Y582690D01*
X2967046Y581932D01*
X2966901Y581174D01*
X2967046Y580416D01*
X2967623Y579442D01*
X2963870Y579767D01*
Y582690D01*
G01X2960582Y722933D02*
X2957630D01*
G01X2970425D02*
X2967472D01*
G01D02*
Y742534D01*
G01X2960582Y746555D02*
Y722933D01*
G01X2957630D02*
Y742534D01*
G01X2970425Y746555D02*
Y722933D01*
G01X2964519Y739016D02*
Y743037D01*
G01X2967472Y742534D02*
X2964519Y739016D01*
G01Y743037D02*
X2967472Y746555D01*
G01D02*
X2970425D01*
G01X2957630D02*
X2960582D01*
G01X2968004Y1094074D02*
X2970759D01*
G01X2964067D02*
X2966822D01*
G01X2960130D02*
X2962885D01*
G01X2968004Y1110610D02*
Y1094074D01*
G01X2966822D02*
Y1110610D01*
G01X2964067D02*
Y1094074D01*
G01X2962885D02*
Y1110610D01*
G01X2960130D02*
Y1094074D01*
G01X2958948D02*
Y1110610D01*
G01X2971941Y1094074D02*
X2974696D01*
G01X2971941Y1110610D02*
Y1094074D01*
G01X2970759D02*
Y1110610D01*
G01X2962885D02*
X2960130D01*
G01X2966822D02*
X2964067D01*
G01X2970759D02*
X2968004D01*
G01X2974696D02*
X2971941D01*
G01X2983942Y-1210504D02*
X3001974Y-1200421D01*
G01X2979520Y-1093246D02*
Y-1087472D01*
G01Y-1088916D02*
X2979954Y-1088194D01*
X2980603Y-1087616D01*
X2981469Y-1087472D01*
X2982227Y-1087616D01*
X2982877Y-1088194D01*
X2983202Y-1089204D01*
Y-1093246D01*
G01X2986173Y-1074587D02*
Y-1068813D01*
G01Y-1070257D02*
X2986607Y-1069535D01*
X2987256Y-1068957D01*
X2988122Y-1068813D01*
X2988880Y-1068957D01*
X2989530Y-1069535D01*
X2989855Y-1070545D01*
Y-1074587D01*
G01X2976105Y-1076752D02*
X3082929D01*
G01X2972955D02*
X2976105D01*
G01X2983792Y-1035052D02*
X3002546Y-1023374D01*
G01X2985783Y-1024448D02*
X2997159Y-1002848D01*
G01X2978179Y-291925D02*
X2981072D01*
G01X2974242D02*
X2977135D01*
G01X2981072D02*
Y-275389D01*
G01X2978179D02*
Y-291925D01*
G01X2977135D02*
Y-275389D01*
G01X2974242D02*
Y-291925D01*
G01X2973198D02*
Y-275389D01*
G01X2986053Y-291925D02*
X2988946D01*
G01X2982116D02*
X2985009D01*
G01X2988946D02*
Y-275389D01*
G01X2986053D02*
Y-291925D01*
G01X2985009D02*
Y-275389D01*
G01X2982116D02*
Y-291925D01*
G01X2977135Y-275389D02*
X2974242D01*
G01X2981072D02*
X2978179D01*
G01X2985009D02*
X2982116D01*
G01X2988946D02*
X2986053D01*
G01X2977857Y146545D02*
X2978615Y145824D01*
X2979481Y145535D01*
X2980348Y145824D01*
X2981105Y146690D01*
X2981647Y147989D01*
X2981863Y149288D01*
Y150876D01*
X2981647Y152175D01*
X2981105Y153330D01*
X2980456Y153907D01*
X2979698Y154196D01*
X2978832Y153907D01*
X2978182Y153330D01*
X2977749Y152464D01*
X2977533Y151309D01*
X2977749Y150299D01*
X2978291Y149288D01*
X2978940Y148711D01*
X2979698Y148566D01*
X2980564Y148855D01*
X2981214Y149577D01*
X2981863Y150876D01*
G01X2988359Y145246D02*
X2988142Y145391D01*
Y145679D01*
X2988359Y145824D01*
X2988576Y145679D01*
Y145391D01*
X2988359Y145246D01*
G01X2997020Y154196D02*
X2996154Y153907D01*
X2995504Y153186D01*
X2995071Y152320D01*
X2994746Y151165D01*
X2994638Y149865D01*
X2994746Y148566D01*
X2995071Y147411D01*
X2995504Y146545D01*
X2996154Y145824D01*
X2997020Y145535D01*
X2997886Y145824D01*
X2998536Y146545D01*
X2998969Y147411D01*
X2999294Y148566D01*
X2999402Y149865D01*
X2999294Y151165D01*
X2998969Y152320D01*
X2998536Y153186D01*
X2997886Y153907D01*
X2997020Y154196D01*
G01X3005681D02*
X3004815Y153907D01*
X3004165Y153186D01*
X3003732Y152320D01*
X3003407Y151165D01*
X3003299Y149865D01*
X3003407Y148566D01*
X3003732Y147411D01*
X3004165Y146545D01*
X3004815Y145824D01*
X3005681Y145535D01*
X3006547Y145824D01*
X3007197Y146545D01*
X3007630Y147411D01*
X3007955Y148566D01*
X3008063Y149865D01*
X3007955Y151165D01*
X3007630Y152320D01*
X3007197Y153186D01*
X3006547Y153907D01*
X3005681Y154196D01*
G01X2988476Y200767D02*
Y350374D01*
G01X2976665Y318878D02*
Y220452D01*
G01X2974696Y354311D02*
Y530183D01*
G01X2976882Y425570D02*
X2978112Y425822D01*
G01X2977866Y427078D02*
X2976882Y426827D01*
G01X2978112Y425822D02*
X2979342Y426576D01*
G01X2976882Y426827D02*
X2975405D01*
G01Y425570D02*
X2976882D01*
G01X2983771D02*
X2982541D01*
G01X2978604Y427581D02*
X2977866Y427078D01*
G01X2975405Y426827D02*
X2974421Y427078D01*
G01X2974175Y425822D02*
X2975405Y425570D01*
G01X2979342Y426576D02*
X2980080Y427581D01*
G01X2979096Y428335D02*
X2978604Y427581D01*
G01X2974421Y427078D02*
X2973683Y427581D01*
G01X2972945Y426576D02*
X2974175Y425822D01*
G01X2980080Y427581D02*
X2980572Y428837D01*
G01X2979342Y429089D02*
X2979096Y428335D01*
G01X2973683Y427581D02*
X2973191Y428586D01*
G01X2983771Y431853D02*
Y425570D01*
G01X2982541D02*
Y433612D01*
G01X2975405Y433109D02*
X2974175Y432858D01*
G01X2974421Y431602D02*
X2975405Y431853D01*
G01X2985002Y432607D02*
X2984263Y432356D01*
G01Y433361D02*
X2985002Y433612D01*
G01D02*
X2985986D01*
G01X2982541D02*
X2983771D01*
G01X2976882Y433109D02*
X2975405D01*
G01X2985494Y432607D02*
X2985002D01*
G01X2975405Y431853D02*
X2976882D01*
G01X2974175Y432858D02*
X2972945Y432104D01*
G01X2973437Y430848D02*
X2974421Y431602D01*
G01X2984263Y432356D02*
X2983771Y431853D01*
G01Y432858D02*
X2984263Y433361D01*
G01X2976882Y431853D02*
X2977866Y431602D01*
G01X2978112Y432858D02*
X2976882Y433109D01*
G01X2977866Y431602D02*
X2978604Y431099D01*
G01X2979342Y432104D02*
X2978112Y432858D01*
G01X2985986Y432356D02*
X2985494Y432607D01*
G01X2979096Y430345D02*
X2979342Y429591D01*
G01X2980572Y429843D02*
X2980080Y431099D01*
G01X2978604D02*
X2979096Y430345D01*
G01X2980080Y431099D02*
X2979342Y432104D01*
G01X2983771Y433612D02*
Y432858D01*
G01X2980572Y428837D02*
Y429843D01*
G01X2979342Y429591D02*
Y429089D01*
G01X2972945Y432104D02*
Y436125D01*
G01X2987708Y425570D02*
X2986478D01*
G01X2987708Y431602D02*
Y425570D01*
G01X2986478D02*
Y431602D01*
G01X2988200Y433361D02*
X2988939Y433612D01*
G01X2988693Y432607D02*
X2988200Y432356D01*
G01X2988939Y433612D02*
X2989923D01*
G01X2989431Y432607D02*
X2988693D01*
G01X2988200Y432356D02*
X2987954Y432104D01*
G01X2987462Y432607D02*
X2988200Y433361D01*
G01X2985986Y433612D02*
X2986724Y433361D01*
G01X2987954Y432104D02*
X2987708Y431602D01*
G01X2986724Y433361D02*
X2987462Y432607D01*
G01X2986232Y432104D02*
X2985986Y432356D01*
G01X2986478Y431602D02*
X2986232Y432104D01*
G01X2972945Y436125D02*
X2980080D01*
G01D02*
Y437381D01*
G01X2976822Y722933D02*
X2974362D01*
G01X2984696D02*
X2982236D01*
G01X2984696Y734995D02*
Y722933D01*
G01X2982236D02*
Y734995D01*
G01X2976822Y735498D02*
Y722933D01*
G01X2974362D02*
Y739016D01*
G01X2979283D02*
X2981252D01*
G01X2974362D02*
X2976822D01*
G01X2980267Y737006D02*
X2979283D01*
G01X2981252Y736503D02*
X2980267Y737006D01*
G01X2981252Y739016D02*
X2982728Y738513D01*
G01D02*
X2984204Y737006D01*
G01X2981744Y736000D02*
X2981252Y736503D01*
G01X2982236Y734995D02*
X2981744Y736000D01*
G01X2985681Y738513D02*
X2987157Y739016D01*
G01X2979283Y737006D02*
X2977807Y736503D01*
G01Y738513D02*
X2979283Y739016D01*
G01X2976822D02*
Y737508D01*
G01X2986665Y737006D02*
X2985681Y736503D01*
G01D02*
X2985189Y736000D01*
G01X2984204Y737006D02*
X2985681Y738513D01*
G01X2977807Y736503D02*
X2976822Y735498D01*
G01Y737508D02*
X2977807Y738513D01*
G01X2985189Y736000D02*
X2984696Y734995D01*
G01X2987157Y739016D02*
X2989126D01*
G01X2988141Y737006D02*
X2986665D01*
G01X2989126Y736503D02*
X2988141Y737006D01*
G01X2983752Y1094074D02*
X2986507D01*
G01X2979815D02*
X2982570D01*
G01X2975878D02*
X2978633D01*
G01X2983752Y1110610D02*
Y1094074D01*
G01X2982570D02*
Y1110610D01*
G01X2979815D02*
Y1094074D01*
G01X2978633D02*
Y1110610D01*
G01X2975878D02*
Y1094074D01*
G01X2974696D02*
Y1110610D01*
G01X2987689Y1094074D02*
X2990445D01*
G01X2987689Y1110610D02*
Y1094074D01*
G01X2986507D02*
Y1110610D01*
G01X2978633D02*
X2975878D01*
G01X2982570D02*
X2979815D01*
G01X2986507D02*
X2983752D01*
G01X2990445D02*
X2987689D01*
G01X2989303Y-1202173D02*
X3011524Y-1178834D01*
G01X3005124Y-1200421D02*
X3111948D01*
G01X3001974D02*
X3005124D01*
G01X2992693Y-1093246D02*
X2992910Y-1091370D01*
X2993235Y-1089782D01*
X2993668Y-1088338D01*
X2994209Y-1086750D01*
X2995075Y-1084585D01*
X2990745D01*
G01X3001571Y-1093535D02*
X3001354Y-1093390D01*
Y-1093102D01*
X3001571Y-1092957D01*
X3001788Y-1093102D01*
Y-1093390D01*
X3001571Y-1093535D01*
G01X3010232Y-1084585D02*
X3009366Y-1084874D01*
X3008716Y-1085595D01*
X3008283Y-1086461D01*
X3007958Y-1087616D01*
X3007850Y-1088916D01*
X3007958Y-1090215D01*
X3008283Y-1091370D01*
X3008716Y-1092236D01*
X3009366Y-1092957D01*
X3010232Y-1093246D01*
X3011098Y-1092957D01*
X3011748Y-1092236D01*
X3012181Y-1091370D01*
X3012506Y-1090215D01*
X3012614Y-1088916D01*
X3012506Y-1087616D01*
X3012181Y-1086461D01*
X3011748Y-1085595D01*
X3011098Y-1084874D01*
X3010232Y-1084585D01*
G01X3018893D02*
X3018027Y-1084874D01*
X3017377Y-1085595D01*
X3016944Y-1086461D01*
X3016619Y-1087616D01*
X3016511Y-1088916D01*
X3016619Y-1090215D01*
X3016944Y-1091370D01*
X3017377Y-1092236D01*
X3018027Y-1092957D01*
X3018893Y-1093246D01*
X3019759Y-1092957D01*
X3020409Y-1092236D01*
X3020842Y-1091370D01*
X3021167Y-1090215D01*
X3021275Y-1088916D01*
X3021167Y-1087616D01*
X3020842Y-1086461D01*
X3020409Y-1085595D01*
X3019759Y-1084874D01*
X3018893Y-1084585D01*
G01X2997181Y-1072855D02*
X2997831Y-1073865D01*
X2998697Y-1074443D01*
X2999671Y-1074587D01*
X3000537Y-1074443D01*
X3001404Y-1073721D01*
X3001945Y-1072855D01*
X3002053Y-1071989D01*
X3001837Y-1070978D01*
X3001079Y-1070257D01*
X3000321Y-1069968D01*
X2999346D01*
G01X3000321D02*
X3000970Y-1069535D01*
X3001512Y-1068813D01*
X3001728Y-1067947D01*
X3001512Y-1067081D01*
X3000970Y-1066359D01*
X2999996Y-1065926D01*
X2999022Y-1066070D01*
X2998047Y-1066648D01*
G01X3008224Y-1074876D02*
X3008007Y-1074731D01*
Y-1074443D01*
X3008224Y-1074298D01*
X3008441Y-1074443D01*
Y-1074731D01*
X3008224Y-1074876D01*
G01X3014503Y-1073288D02*
X3015153Y-1074010D01*
X3015911Y-1074443D01*
X3016885Y-1074587D01*
X3017859Y-1074298D01*
X3018617Y-1073721D01*
X3019159Y-1072711D01*
X3019267Y-1071556D01*
X3019050Y-1070401D01*
X3018509Y-1069679D01*
X3017751Y-1069102D01*
X3016993Y-1068957D01*
X3016235Y-1069102D01*
X3015261Y-1069679D01*
X3015586Y-1065926D01*
X3018509D01*
G01X3025546D02*
X3024680Y-1066215D01*
X3024030Y-1066936D01*
X3023597Y-1067802D01*
X3023272Y-1068957D01*
X3023164Y-1070257D01*
X3023272Y-1071556D01*
X3023597Y-1072711D01*
X3024030Y-1073577D01*
X3024680Y-1074298D01*
X3025546Y-1074587D01*
X3026412Y-1074298D01*
X3027062Y-1073577D01*
X3027495Y-1072711D01*
X3027820Y-1071556D01*
X3027928Y-1070257D01*
X3027820Y-1068957D01*
X3027495Y-1067802D01*
X3027062Y-1066936D01*
X3026412Y-1066215D01*
X3025546Y-1065926D01*
G01X3002546Y-1023374D02*
X3005696D01*
G01X2997159Y-1002848D02*
X3000309D01*
G01D02*
X3099338D01*
G01X2997864Y-291925D02*
X3000757D01*
G01X2993927D02*
X2996820D01*
G01X2989990D02*
X2992883D01*
G01X2997864Y-275389D02*
Y-291925D01*
G01X2996820D02*
Y-275389D01*
G01X2993927D02*
Y-291925D01*
G01X2992883D02*
Y-275389D01*
G01X2989990D02*
Y-291925D01*
G01X3001801D02*
X3004694D01*
G01D02*
Y-275389D01*
G01X3001801D02*
Y-291925D01*
G01X3000757D02*
Y-275389D01*
G01X2992883D02*
X2989990D01*
G01X2996820D02*
X2993927D01*
G01X3000757D02*
X2997864D01*
G01X3004694D02*
X3001801D01*
G01X2993004Y416712D02*
Y92500D01*
G01Y150767D02*
X3038279D01*
G01X2993004Y194074D02*
X3038279D01*
G01Y325964D02*
X2993004D01*
G01Y369271D02*
X3038279D01*
G01X3007315Y432657D02*
X3008073Y432801D01*
X3008939Y433234D01*
X3009480Y433956D01*
X3009697Y434967D01*
X3009480Y435977D01*
X3008831Y436843D01*
X3007856Y437276D01*
X3006774D01*
X3006124Y437565D01*
X3005583Y438287D01*
X3005366Y439297D01*
X3005691Y440308D01*
X3006449Y441029D01*
X3007315Y441318D01*
X3008181Y441029D01*
X3008939Y440308D01*
X3009264Y439297D01*
X3009047Y438287D01*
X3008506Y437565D01*
X3007856Y437276D01*
X3006774D01*
X3005799Y436843D01*
X3005150Y435977D01*
X3004933Y434967D01*
X3005150Y433956D01*
X3005691Y433234D01*
X3006557Y432801D01*
X3007315Y432657D01*
G01X3013594Y433956D02*
X3014244Y433234D01*
X3015002Y432801D01*
X3015976Y432657D01*
X3016950Y432946D01*
X3017708Y433523D01*
X3018250Y434533D01*
X3018358Y435688D01*
X3018141Y436843D01*
X3017600Y437565D01*
X3016842Y438142D01*
X3016084Y438287D01*
X3015326Y438142D01*
X3014352Y437565D01*
X3014677Y441318D01*
X3017600D01*
G01X3024637Y432368D02*
X3024420Y432513D01*
Y432801D01*
X3024637Y432946D01*
X3024854Y432801D01*
Y432513D01*
X3024637Y432368D01*
G01X3033298Y432657D02*
X3034056Y432801D01*
X3034922Y433234D01*
X3035463Y433956D01*
X3035680Y434967D01*
X3035463Y435977D01*
X3034814Y436843D01*
X3033839Y437276D01*
X3032757D01*
X3032107Y437565D01*
X3031566Y438287D01*
X3031349Y439297D01*
X3031674Y440308D01*
X3032432Y441029D01*
X3033298Y441318D01*
X3034164Y441029D01*
X3034922Y440308D01*
X3035247Y439297D01*
X3035030Y438287D01*
X3034489Y437565D01*
X3033839Y437276D01*
X3032757D01*
X3031782Y436843D01*
X3031133Y435977D01*
X3030916Y434967D01*
X3031133Y433956D01*
X3031674Y433234D01*
X3032540Y432801D01*
X3033298Y432657D01*
G01X3039577Y433956D02*
X3040227Y433234D01*
X3040985Y432801D01*
X3041959Y432657D01*
X3042933Y432946D01*
X3043691Y433523D01*
X3044233Y434533D01*
X3044341Y435688D01*
X3044124Y436843D01*
X3043583Y437565D01*
X3042825Y438142D01*
X3042067Y438287D01*
X3041309Y438142D01*
X3040335Y437565D01*
X3040660Y441318D01*
X3043583D01*
G01X2991645Y425570D02*
X2990415D01*
G01X2994844D02*
X2993614D01*
G01X2998781D02*
X2997551D01*
G01X3002718D02*
X3001488D01*
G01D02*
Y431602D01*
G01X2998781D02*
Y425570D01*
G01X2997551D02*
Y431602D01*
G01X2994844Y431853D02*
Y425570D01*
G01X2993614D02*
Y433612D01*
G01X2991645Y431602D02*
Y425570D01*
G01X2990415D02*
Y431602D01*
G01X2999273Y433361D02*
X3000011Y433612D01*
G01X2996074Y432607D02*
X2995336Y432356D01*
G01Y433361D02*
X2996074Y433612D01*
G01X2999765Y432607D02*
X2999273Y432356D01*
G01X3000011Y433612D02*
X3000996D01*
G01X2993614D02*
X2994844D01*
G01X2996074D02*
X2997059D01*
G01X2996567Y432607D02*
X2996074D01*
G01X3000504D02*
X2999765D01*
G01X2999273Y432356D02*
X2999027Y432104D01*
G01X2998535Y432607D02*
X2999273Y433361D01*
G01X2995336Y432356D02*
X2994844Y431853D01*
G01Y432858D02*
X2995336Y433361D01*
G01X3000996Y433612D02*
X3001734Y433361D01*
G01X2997059Y433612D02*
X2997797Y433361D01*
G01X2989923Y433612D02*
X2990661Y433361D01*
G01X2999027Y432104D02*
X2998781Y431602D01*
G01X3002226Y432858D02*
X3002718Y431602D01*
G01X3001488D02*
X3001242Y432104D01*
G01X3001734Y433361D02*
X3002226Y432858D01*
G01X3001242Y432104D02*
X3000996Y432356D01*
G01X2997797Y433361D02*
X2998535Y432607D01*
G01X2997305Y432104D02*
X2997059Y432356D01*
G01X2990661Y433361D02*
X2991153Y432858D01*
G01X2990169Y432104D02*
X2989923Y432356D01*
G01X3000996D02*
X3000504Y432607D01*
G01X2997059Y432356D02*
X2996567Y432607D01*
G01X2989923Y432356D02*
X2989431Y432607D01*
G01X2994844Y433612D02*
Y432858D01*
G01X2991153D02*
X2991645Y431602D01*
G01X2997551D02*
X2997305Y432104D01*
G01X2990415Y431602D02*
X2990169Y432104D01*
G01X3002718Y431602D02*
Y425570D01*
G01X2994637Y489409D02*
Y442441D01*
G01X3013279Y535723D02*
X3004618D01*
X3006350Y534424D01*
G01X3013279D02*
Y537022D01*
G01X3006061Y542327D02*
X3005196Y542977D01*
X3004762Y543734D01*
X3004618Y544601D01*
X3004907Y545683D01*
X3005628Y546441D01*
X3006494Y546658D01*
X3007361Y546549D01*
X3008082Y546116D01*
X3009526Y543951D01*
X3010536Y542977D01*
X3011980Y542327D01*
X3013279Y542110D01*
Y546658D01*
G01Y554344D02*
X3004618D01*
X3010825Y550338D01*
Y555752D01*
G01X3013568Y561706D02*
X3013423Y561489D01*
X3013135D01*
X3012990Y561706D01*
X3013135Y561923D01*
X3013423D01*
X3013568Y561706D01*
G01X3013279Y570150D02*
X3011403Y570367D01*
X3009815Y570692D01*
X3008371Y571125D01*
X3006783Y571666D01*
X3004618Y572532D01*
Y568202D01*
G01Y579028D02*
X3004907Y578162D01*
X3005628Y577512D01*
X3006494Y577079D01*
X3007649Y576754D01*
X3008949Y576646D01*
X3010248Y576754D01*
X3011403Y577079D01*
X3012269Y577512D01*
X3012990Y578162D01*
X3013279Y579028D01*
X3012990Y579894D01*
X3012269Y580544D01*
X3011403Y580977D01*
X3010248Y581302D01*
X3008949Y581410D01*
X3007649Y581302D01*
X3006494Y580977D01*
X3005628Y580544D01*
X3004907Y579894D01*
X3004618Y579028D01*
G01X2992570Y722933D02*
X2990110D01*
G01X2998968D02*
X2996507D01*
G01X2998968Y735498D02*
Y722933D01*
G01X2996507D02*
Y739016D01*
G01X2992570Y734995D02*
Y722933D01*
G01X2990110D02*
Y734995D01*
G01X3006842Y722933D02*
X3004382D01*
G01D02*
Y734995D01*
G01X3001429Y739016D02*
X3003397D01*
G01X2996507D02*
X2998968D01*
G01X3002413Y737006D02*
X3001429D01*
G01X2989126Y739016D02*
X2990602Y738513D01*
G01D02*
X2991586Y737508D01*
G01X2989618Y736000D02*
X2989126Y736503D01*
G01X2990110Y734995D02*
X2989618Y736000D01*
G01X2991586Y737508D02*
X2992570Y734995D01*
G01X2998968Y739016D02*
Y737508D01*
G01X3001429Y737006D02*
X2999952Y736503D01*
G01Y738513D02*
X3001429Y739016D01*
G01X2999952Y736503D02*
X2998968Y735498D01*
G01Y737508D02*
X2999952Y738513D01*
G01X3003397Y739016D02*
X3004874Y738513D01*
G01X3003397Y736503D02*
X3002413Y737006D01*
G01X3004874Y738513D02*
X3006350Y737006D01*
G01X3003889Y736000D02*
X3003397Y736503D01*
G01X3004382Y734995D02*
X3003889Y736000D01*
G01X2999500Y1094074D02*
X3002256D01*
G01X2995563D02*
X2998319D01*
G01X2991626D02*
X2994382D01*
G01X3002256D02*
Y1110610D01*
G01X2999500D02*
Y1094074D01*
G01X2998319D02*
Y1110610D01*
G01X2995563D02*
Y1094074D01*
G01X2994382D02*
Y1110610D01*
G01X2991626D02*
Y1094074D01*
G01X2990445D02*
Y1110610D01*
G01X3003437Y1094074D02*
X3006193D01*
G01X3003437Y1110610D02*
Y1094074D01*
G01X2994382Y1110610D02*
X2991626D01*
G01X2998319D02*
X2995563D01*
G01X3002256D02*
X2999500D01*
G01X3006193D02*
X3003437D01*
G01X3014292Y-1852994D02*
Y-1841587D01*
X3012581Y-1843868D01*
G01Y-1852994D02*
X3016003D01*
G01X3022991Y-1848241D02*
X3023989Y-1846910D01*
X3024844Y-1846150D01*
X3025985Y-1845770D01*
X3026984Y-1846150D01*
X3027696Y-1846910D01*
X3028267Y-1848051D01*
X3028409Y-1849382D01*
X3028267Y-1850523D01*
X3027696Y-1851663D01*
X3026841Y-1852614D01*
X3025843Y-1852994D01*
X3024702Y-1852614D01*
X3023704Y-1851473D01*
X3023133Y-1849762D01*
X3022991Y-1847861D01*
X3023276Y-1845390D01*
X3023704Y-1844058D01*
X3024416Y-1842728D01*
X3025415Y-1841777D01*
X3026413Y-1841587D01*
X3027411Y-1841967D01*
X3028124Y-1842918D01*
G01X3015192Y-1198256D02*
Y-1192482D01*
G01Y-1193926D02*
X3015626Y-1193204D01*
X3016275Y-1192626D01*
X3017141Y-1192482D01*
X3017899Y-1192626D01*
X3018549Y-1193204D01*
X3018874Y-1194214D01*
Y-1198256D01*
G01X3011524Y-1178834D02*
X3014673D01*
G01D02*
X3113702D01*
G01X3023550Y-1096133D02*
X3022467Y-1094689D01*
X3021926Y-1093246D01*
Y-1087472D01*
X3022467Y-1086028D01*
X3023550Y-1084585D01*
G01X3030478Y-1093246D02*
Y-1084585D01*
G01X3035026D02*
Y-1093246D01*
G01Y-1088916D02*
X3030478D01*
G01X3040006Y-1091658D02*
X3042820D01*
G01Y-1089060D02*
X3040006D01*
G01X3050074Y-1084585D02*
X3049208Y-1084874D01*
X3048558Y-1085595D01*
X3048125Y-1086461D01*
X3047800Y-1087616D01*
X3047692Y-1088916D01*
X3047800Y-1090215D01*
X3048125Y-1091370D01*
X3048558Y-1092236D01*
X3049208Y-1092957D01*
X3050074Y-1093246D01*
X3050940Y-1092957D01*
X3051590Y-1092236D01*
X3052023Y-1091370D01*
X3052348Y-1090215D01*
X3052456Y-1088916D01*
X3052348Y-1087616D01*
X3052023Y-1086461D01*
X3051590Y-1085595D01*
X3050940Y-1084874D01*
X3050074Y-1084585D01*
G01X3055487Y-1093246D02*
Y-1087472D01*
G01Y-1089060D02*
X3055812Y-1088338D01*
X3056353Y-1087761D01*
X3057111Y-1087472D01*
X3057869Y-1087761D01*
X3058410Y-1088338D01*
X3058735Y-1089060D01*
Y-1093246D01*
G01Y-1089060D02*
X3059060Y-1088338D01*
X3059601Y-1087761D01*
X3060359Y-1087472D01*
X3061117Y-1087761D01*
X3061658Y-1088338D01*
X3061983Y-1089204D01*
Y-1093246D01*
G01X3064148D02*
Y-1087472D01*
G01Y-1089060D02*
X3064473Y-1088338D01*
X3065014Y-1087761D01*
X3065772Y-1087472D01*
X3066530Y-1087761D01*
X3067071Y-1088338D01*
X3067396Y-1089060D01*
Y-1093246D01*
G01Y-1089060D02*
X3067721Y-1088338D01*
X3068262Y-1087761D01*
X3069020Y-1087472D01*
X3069778Y-1087761D01*
X3070319Y-1088338D01*
X3070644Y-1089204D01*
Y-1093246D01*
G01X3076598Y-1096133D02*
X3077681Y-1094689D01*
X3078222Y-1093246D01*
Y-1087472D01*
X3077681Y-1086028D01*
X3076598Y-1084585D01*
G01X3015764Y-1021208D02*
Y-1015434D01*
G01Y-1016878D02*
X3016198Y-1016156D01*
X3016847Y-1015578D01*
X3017713Y-1015434D01*
X3018471Y-1015578D01*
X3019121Y-1016156D01*
X3019446Y-1017166D01*
Y-1021208D01*
G01X3005696Y-1023374D02*
X3112520D01*
G01X3010377Y-1000683D02*
Y-994909D01*
G01Y-996353D02*
X3010811Y-995631D01*
X3011460Y-995053D01*
X3012326Y-994909D01*
X3013084Y-995053D01*
X3013734Y-995631D01*
X3014059Y-996641D01*
Y-1000683D01*
G01X3023767D02*
X3024525Y-1000539D01*
X3025391Y-1000106D01*
X3025932Y-999384D01*
X3026149Y-998373D01*
X3025932Y-997363D01*
X3025283Y-996497D01*
X3024308Y-996064D01*
X3023226D01*
X3022576Y-995775D01*
X3022035Y-995053D01*
X3021818Y-994043D01*
X3022143Y-993032D01*
X3022901Y-992311D01*
X3023767Y-992022D01*
X3024633Y-992311D01*
X3025391Y-993032D01*
X3025716Y-994043D01*
X3025499Y-995053D01*
X3024958Y-995775D01*
X3024308Y-996064D01*
X3023226D01*
X3022251Y-996497D01*
X3021602Y-997363D01*
X3021385Y-998373D01*
X3021602Y-999384D01*
X3022143Y-1000106D01*
X3023009Y-1000539D01*
X3023767Y-1000683D01*
G01X3032428Y-1000972D02*
X3032211Y-1000827D01*
Y-1000539D01*
X3032428Y-1000394D01*
X3032645Y-1000539D01*
Y-1000827D01*
X3032428Y-1000972D01*
G01X3041089Y-992022D02*
X3040223Y-992311D01*
X3039573Y-993032D01*
X3039140Y-993898D01*
X3038815Y-995053D01*
X3038707Y-996353D01*
X3038815Y-997652D01*
X3039140Y-998807D01*
X3039573Y-999673D01*
X3040223Y-1000394D01*
X3041089Y-1000683D01*
X3041955Y-1000394D01*
X3042605Y-999673D01*
X3043038Y-998807D01*
X3043363Y-997652D01*
X3043471Y-996353D01*
X3043363Y-995053D01*
X3043038Y-993898D01*
X3042605Y-993032D01*
X3041955Y-992311D01*
X3041089Y-992022D01*
G01X3049750D02*
X3048884Y-992311D01*
X3048234Y-993032D01*
X3047801Y-993898D01*
X3047476Y-995053D01*
X3047368Y-996353D01*
X3047476Y-997652D01*
X3047801Y-998807D01*
X3048234Y-999673D01*
X3048884Y-1000394D01*
X3049750Y-1000683D01*
X3050616Y-1000394D01*
X3051266Y-999673D01*
X3051699Y-998807D01*
X3052024Y-997652D01*
X3052132Y-996353D01*
X3052024Y-995053D01*
X3051699Y-993898D01*
X3051266Y-993032D01*
X3050616Y-992311D01*
X3049750Y-992022D01*
G01X3013613Y-291925D02*
X3016505D01*
G01X3009675D02*
X3012568D01*
G01X3005738D02*
X3008631D01*
G01X3013613Y-275389D02*
Y-291925D01*
G01X3012568D02*
Y-275389D01*
G01X3009675D02*
Y-291925D01*
G01X3008631D02*
Y-275389D01*
G01X3005738D02*
Y-291925D01*
G01X3021487D02*
X3024379D01*
G01X3017550D02*
X3020442D01*
G01X3021487Y-275389D02*
Y-291925D01*
G01X3020442D02*
Y-275389D01*
G01X3017550D02*
Y-291925D01*
G01X3016505D02*
Y-275389D01*
G01X3008631D02*
X3005738D01*
G01X3012568D02*
X3009675D01*
G01X3016505D02*
X3013613D01*
G01X3020442D02*
X3017550D01*
G01X3024379D02*
X3021487D01*
G01X3010339Y142648D02*
X3009256Y144092D01*
X3008715Y145535D01*
Y151309D01*
X3009256Y152753D01*
X3010339Y154196D01*
G01X3017267Y145535D02*
Y154196D01*
G01X3021815D02*
Y145535D01*
G01Y149865D02*
X3017267D01*
G01X3026795Y147123D02*
X3029609D01*
G01Y149721D02*
X3026795D01*
G01X3036863Y154196D02*
X3035997Y153907D01*
X3035347Y153186D01*
X3034914Y152320D01*
X3034589Y151165D01*
X3034481Y149865D01*
X3034589Y148566D01*
X3034914Y147411D01*
X3035347Y146545D01*
X3035997Y145824D01*
X3036863Y145535D01*
X3037729Y145824D01*
X3038379Y146545D01*
X3038812Y147411D01*
X3039137Y148566D01*
X3039245Y149865D01*
X3039137Y151165D01*
X3038812Y152320D01*
X3038379Y153186D01*
X3037729Y153907D01*
X3036863Y154196D01*
G01X3042276Y145535D02*
Y151309D01*
G01Y149721D02*
X3042601Y150443D01*
X3043142Y151020D01*
X3043900Y151309D01*
X3044658Y151020D01*
X3045199Y150443D01*
X3045524Y149721D01*
Y145535D01*
G01Y149721D02*
X3045849Y150443D01*
X3046390Y151020D01*
X3047148Y151309D01*
X3047906Y151020D01*
X3048447Y150443D01*
X3048772Y149577D01*
Y145535D01*
G01X3050937D02*
Y151309D01*
G01Y149721D02*
X3051262Y150443D01*
X3051803Y151020D01*
X3052561Y151309D01*
X3053319Y151020D01*
X3053860Y150443D01*
X3054185Y149721D01*
Y145535D01*
G01Y149721D02*
X3054510Y150443D01*
X3055051Y151020D01*
X3055809Y151309D01*
X3056567Y151020D01*
X3057108Y150443D01*
X3057433Y149577D01*
Y145535D01*
G01X3063387Y142648D02*
X3064470Y144092D01*
X3065011Y145535D01*
Y151309D01*
X3064470Y152753D01*
X3063387Y154196D01*
G01X3021744Y172421D02*
G03I-6299J0D01*
G01X3009263Y246909D02*
Y248385D01*
G01X3021074Y246909D02*
X3009263D01*
G01X3015546Y255275D02*
Y248385D01*
G01X3014038D02*
Y255275D01*
G01X3015546Y248385D02*
X3021074D01*
G01X3009263D02*
X3014038D01*
G01X3021074D02*
Y246909D01*
G01X3017054Y262657D02*
Y258720D01*
G01X3016048D02*
Y262657D01*
G01X3014038D02*
Y258720D01*
G01X3013033D02*
Y262657D01*
G01X3009263Y255275D02*
Y256752D01*
G01X3016048Y262657D02*
X3017054D01*
G01X3013033D02*
X3014038D01*
G01X3017054Y258720D02*
X3016048D01*
G01X3014038D02*
X3013033D01*
G01X3009263Y256752D02*
X3021074D01*
G01X3014038Y255275D02*
X3009263D01*
G01X3021074D02*
X3015546D01*
G01X3017556Y264872D02*
X3018310Y265118D01*
G01D02*
X3019315Y265610D01*
G01X3017556Y266102D02*
X3019064Y267086D01*
G01X3010771Y270285D02*
X3010520Y269055D01*
G01X3009515Y270531D02*
X3009263Y269055D01*
G01X3016048Y265856D02*
X3017556Y266102D01*
G01X3016300Y264626D02*
X3017556Y264872D01*
G01X3009263Y269055D02*
X3009515Y267578D01*
G01X3010520Y269055D02*
X3010771Y267824D01*
G01X3012782Y264872D02*
X3014038Y264626D01*
G01X3012782Y266102D02*
X3014289Y265856D01*
G01D02*
X3016048D01*
G01X3014038Y264626D02*
X3016300D01*
G01X3009515Y267578D02*
X3010269Y266348D01*
G01X3010771Y267824D02*
X3011274Y267086D01*
G01X3010269Y266348D02*
X3011022Y265610D01*
G01X3011274Y267086D02*
X3012782Y266102D01*
G01X3011022Y265610D02*
X3012028Y265118D01*
G01D02*
X3012782Y264872D01*
G01X3021074Y256752D02*
Y255275D01*
G01X3019315Y265610D02*
X3020069Y266348D01*
G01X3019064Y267086D02*
X3019567Y267824D01*
G01X3020069Y266348D02*
X3020823Y267578D01*
G01X3019567Y267824D02*
X3019818Y269055D01*
G01X3020823Y267578D02*
X3021074Y269055D01*
G01D02*
X3020823Y270531D01*
G01X3019818Y269055D02*
X3019567Y270285D01*
G01X3012782Y273238D02*
X3012028Y272992D01*
G01D02*
X3011022Y272500D01*
G01X3015043Y279389D02*
X3014541Y279143D01*
G01X3012782Y272007D02*
X3011274Y271023D01*
G01X3011022Y272500D02*
X3010269Y271761D01*
G01X3014541Y279143D02*
X3014289Y278897D01*
G01X3013284Y279635D02*
X3014038Y280374D01*
G01X3011274Y271023D02*
X3010771Y270285D01*
G01X3010269Y271761D02*
X3009515Y270531D01*
G01X3014289Y278897D02*
X3014038Y278405D01*
G01X3013033Y278897D02*
X3013284Y279635D01*
G01X3015043Y280620D02*
X3021074D01*
G01Y279389D02*
X3015043D01*
G01X3014289Y272254D02*
X3012782Y272007D01*
G01X3014038Y273484D02*
X3012782Y273238D01*
G01X3014038Y278405D02*
Y277913D01*
G01X3013033Y275452D02*
Y276683D01*
G01Y277913D02*
Y278897D01*
G01X3014038Y277913D02*
X3014289Y277175D01*
G01X3013284D02*
X3013033Y277913D01*
G01X3018310Y272992D02*
X3017556Y273238D01*
G01D02*
X3016300Y273484D01*
G01X3017556Y272007D02*
X3016048Y272254D01*
G01X3013033Y276683D02*
X3013787D01*
G01X3014792D02*
X3021074D01*
G01Y275452D02*
X3013033D01*
G01X3016300Y273484D02*
X3014038D01*
G01X3016048Y272254D02*
X3014289D01*
G01X3014038Y280374D02*
X3013284Y281112D01*
G01X3014289Y277175D02*
X3014792Y276683D01*
G01X3013787D02*
X3013284Y277175D01*
G01X3019064Y271023D02*
X3017556Y272007D01*
G01X3014541Y280866D02*
X3015043Y280620D01*
G01X3019315Y272500D02*
X3018310Y272992D01*
G01X3013787Y284065D02*
X3015043Y284557D01*
G01Y283326D02*
X3014541Y283080D01*
G01D02*
X3014289Y282834D01*
G01X3013284Y283572D02*
X3013787Y284065D01*
G01X3014289Y282834D02*
X3014038Y282342D01*
G01X3013033Y282834D02*
X3013284Y283572D01*
G01X3015043Y284557D02*
X3021074D01*
G01Y283326D02*
X3015043D01*
G01X3014038Y282342D02*
Y281604D01*
G01X3013033Y281850D02*
Y282834D01*
G01X3013284Y281112D02*
X3013033Y281850D01*
G01X3014038Y281604D02*
X3014289Y281112D01*
G01D02*
X3014541Y280866D01*
G01X3021074Y276683D02*
Y275452D01*
G01Y280620D02*
Y279389D01*
G01X3020823Y270531D02*
X3020069Y271761D01*
G01X3019567Y270285D02*
X3019064Y271023D01*
G01X3020069Y271761D02*
X3019315Y272500D01*
G01X3021074Y284557D02*
Y283326D01*
G01X3013787Y295137D02*
X3015043Y295630D01*
G01Y290462D02*
X3014541Y290216D01*
G01X3015043Y294399D02*
X3014541Y294153D01*
G01Y290216D02*
X3014289Y289970D01*
G01X3013284Y290708D02*
X3014038Y291446D01*
G01X3014541Y294153D02*
X3014289Y293907D01*
G01X3013284Y294645D02*
X3013787Y295137D01*
G01X3014289Y289970D02*
X3014038Y289478D01*
G01X3014289Y293907D02*
X3014038Y293415D01*
G01X3013033Y289970D02*
X3013284Y290708D01*
G01X3013033Y293907D02*
X3013284Y294645D01*
G01X3015043Y295630D02*
X3021074D01*
G01Y294399D02*
X3015043D01*
G01Y291693D02*
X3021074D01*
G01Y290462D02*
X3015043D01*
G01X3013033Y287756D02*
X3013787D01*
G01X3014792D02*
X3021074D01*
G01Y286525D02*
X3013033D01*
G01X3014038Y293415D02*
Y292677D01*
G01Y289478D02*
Y288986D01*
G01X3013033Y292923D02*
Y293907D01*
G01Y288986D02*
Y289970D01*
G01Y286525D02*
Y287756D01*
G01X3013284Y292185D02*
X3013033Y292923D01*
G01X3014038Y288986D02*
X3014289Y288248D01*
G01X3013284D02*
X3013033Y288986D01*
G01X3014038Y292677D02*
X3014289Y292185D01*
G01X3014541Y291939D02*
X3015043Y291693D01*
G01X3014289Y292185D02*
X3014541Y291939D01*
G01X3014038Y291446D02*
X3013284Y292185D01*
G01X3014289Y288248D02*
X3014792Y287756D01*
G01X3013787D02*
X3013284Y288248D01*
G01X3021074Y287756D02*
Y286525D01*
G01Y291693D02*
Y290462D01*
G01Y295630D02*
Y294399D01*
G01X3021744Y347618D02*
G03I-6299J0D01*
G01X3015445Y351555D02*
Y528144D01*
G01X3019382Y347618D02*
X3042978D01*
G01X3014716Y722933D02*
X3012256D01*
G01X3014716Y734995D02*
Y722933D01*
G01X3012256D02*
Y734995D01*
G01X3006842D02*
Y722933D01*
G01X3009303Y739016D02*
X3011271D01*
G01X3010287Y737006D02*
X3008811D01*
G01X3011271Y739016D02*
X3012748Y738513D01*
G01X3011271Y736503D02*
X3010287Y737006D01*
G01X3012748Y738513D02*
X3013732Y737508D01*
G01X3011763Y736000D02*
X3011271Y736503D01*
G01X3012256Y734995D02*
X3011763Y736000D01*
G01X3013732Y737508D02*
X3014716Y734995D01*
G01X3007826Y738513D02*
X3009303Y739016D01*
G01X3008811Y737006D02*
X3007826Y736503D01*
G01X3007334Y736000D02*
X3006842Y734995D01*
G01X3007826Y736503D02*
X3007334Y736000D01*
G01X3006350Y737006D02*
X3007826Y738513D01*
G01X3015248Y1094074D02*
X3018004D01*
G01X3007374D02*
X3010130D01*
G01X3011311D02*
X3014067D01*
G01X3018004D02*
Y1110610D01*
G01X3015248D02*
Y1094074D01*
G01X3014067D02*
Y1110610D01*
G01X3011311D02*
Y1094074D01*
G01X3010130D02*
Y1110610D01*
G01X3007374D02*
Y1094074D01*
G01X3006193D02*
Y1110610D01*
G01X3019185Y1094074D02*
X3021941D01*
G01X3019185Y1110610D02*
Y1094074D01*
G01X3010130Y1110610D02*
X3007374D01*
G01X3014067D02*
X3011311D01*
G01X3018004D02*
X3015248D01*
G01X3021941D02*
X3019185D01*
G01X3014292Y1438719D02*
Y1450126D01*
X3012581Y1447845D01*
G01Y1438719D02*
X3016003D01*
G01X3022991Y1443472D02*
X3023989Y1444803D01*
X3024844Y1445563D01*
X3025985Y1445943D01*
X3026984Y1445563D01*
X3027696Y1444803D01*
X3028267Y1443662D01*
X3028409Y1442331D01*
X3028267Y1441190D01*
X3027696Y1440050D01*
X3026841Y1439099D01*
X3025843Y1438719D01*
X3024702Y1439099D01*
X3023704Y1440240D01*
X3023133Y1441951D01*
X3022991Y1443852D01*
X3023276Y1446323D01*
X3023704Y1447655D01*
X3024416Y1448985D01*
X3025415Y1449936D01*
X3026413Y1450126D01*
X3027411Y1449746D01*
X3028124Y1448795D01*
G01X3026200Y-1196524D02*
X3026850Y-1197534D01*
X3027716Y-1198112D01*
X3028690Y-1198256D01*
X3029556Y-1198112D01*
X3030423Y-1197390D01*
X3030964Y-1196524D01*
X3031072Y-1195658D01*
X3030856Y-1194647D01*
X3030098Y-1193926D01*
X3029340Y-1193637D01*
X3028365D01*
G01X3029340D02*
X3029989Y-1193204D01*
X3030531Y-1192482D01*
X3030747Y-1191616D01*
X3030531Y-1190750D01*
X3029989Y-1190028D01*
X3029015Y-1189595D01*
X3028041Y-1189739D01*
X3027066Y-1190317D01*
G01X3037243Y-1198545D02*
X3037026Y-1198400D01*
Y-1198112D01*
X3037243Y-1197967D01*
X3037460Y-1198112D01*
Y-1198400D01*
X3037243Y-1198545D01*
G01X3043847Y-1191038D02*
X3044497Y-1190173D01*
X3045254Y-1189739D01*
X3046121Y-1189595D01*
X3047203Y-1189884D01*
X3047961Y-1190605D01*
X3048178Y-1191471D01*
X3048069Y-1192338D01*
X3047636Y-1193059D01*
X3045471Y-1194503D01*
X3044497Y-1195513D01*
X3043847Y-1196957D01*
X3043630Y-1198256D01*
X3048178D01*
G01X3054565Y-1189595D02*
X3053699Y-1189884D01*
X3053049Y-1190605D01*
X3052616Y-1191471D01*
X3052291Y-1192626D01*
X3052183Y-1193926D01*
X3052291Y-1195225D01*
X3052616Y-1196380D01*
X3053049Y-1197246D01*
X3053699Y-1197967D01*
X3054565Y-1198256D01*
X3055431Y-1197967D01*
X3056081Y-1197246D01*
X3056514Y-1196380D01*
X3056839Y-1195225D01*
X3056947Y-1193926D01*
X3056839Y-1192626D01*
X3056514Y-1191471D01*
X3056081Y-1190605D01*
X3055431Y-1189884D01*
X3054565Y-1189595D01*
G01X3024742Y-1176668D02*
Y-1170894D01*
G01Y-1172338D02*
X3025176Y-1171616D01*
X3025825Y-1171038D01*
X3026691Y-1170894D01*
X3027449Y-1171038D01*
X3028099Y-1171616D01*
X3028424Y-1172626D01*
Y-1176668D01*
G01X3038131D02*
X3038889Y-1176524D01*
X3039755Y-1176091D01*
X3040296Y-1175369D01*
X3040513Y-1174358D01*
X3040296Y-1173348D01*
X3039647Y-1172482D01*
X3038672Y-1172049D01*
X3037590D01*
X3036940Y-1171760D01*
X3036399Y-1171038D01*
X3036182Y-1170028D01*
X3036507Y-1169017D01*
X3037265Y-1168296D01*
X3038131Y-1168007D01*
X3038997Y-1168296D01*
X3039755Y-1169017D01*
X3040080Y-1170028D01*
X3039863Y-1171038D01*
X3039322Y-1171760D01*
X3038672Y-1172049D01*
X3037590D01*
X3036615Y-1172482D01*
X3035966Y-1173348D01*
X3035749Y-1174358D01*
X3035966Y-1175369D01*
X3036507Y-1176091D01*
X3037373Y-1176524D01*
X3038131Y-1176668D01*
G01X3046792Y-1176957D02*
X3046575Y-1176812D01*
Y-1176524D01*
X3046792Y-1176379D01*
X3047009Y-1176524D01*
Y-1176812D01*
X3046792Y-1176957D01*
G01X3055453Y-1168007D02*
X3054587Y-1168296D01*
X3053937Y-1169017D01*
X3053504Y-1169883D01*
X3053179Y-1171038D01*
X3053071Y-1172338D01*
X3053179Y-1173637D01*
X3053504Y-1174792D01*
X3053937Y-1175658D01*
X3054587Y-1176379D01*
X3055453Y-1176668D01*
X3056319Y-1176379D01*
X3056969Y-1175658D01*
X3057402Y-1174792D01*
X3057727Y-1173637D01*
X3057835Y-1172338D01*
X3057727Y-1171038D01*
X3057402Y-1169883D01*
X3056969Y-1169017D01*
X3056319Y-1168296D01*
X3055453Y-1168007D01*
G01X3064114D02*
X3063248Y-1168296D01*
X3062598Y-1169017D01*
X3062165Y-1169883D01*
X3061840Y-1171038D01*
X3061732Y-1172338D01*
X3061840Y-1173637D01*
X3062165Y-1174792D01*
X3062598Y-1175658D01*
X3063248Y-1176379D01*
X3064114Y-1176668D01*
X3064980Y-1176379D01*
X3065630Y-1175658D01*
X3066063Y-1174792D01*
X3066388Y-1173637D01*
X3066496Y-1172338D01*
X3066388Y-1171038D01*
X3066063Y-1169883D01*
X3065630Y-1169017D01*
X3064980Y-1168296D01*
X3064114Y-1168007D01*
G01X3030203Y-1077474D02*
X3029120Y-1076030D01*
X3028579Y-1074587D01*
Y-1068813D01*
X3029120Y-1067369D01*
X3030203Y-1065926D01*
G01X3036915Y-1074587D02*
Y-1065926D01*
X3041895Y-1074587D01*
Y-1065926D01*
G01X3045901Y-1074587D02*
Y-1065926D01*
X3048499D01*
X3049365Y-1066359D01*
X3050015Y-1067369D01*
X3050231Y-1068524D01*
X3050015Y-1069679D01*
X3049473Y-1070545D01*
X3048499Y-1070978D01*
X3045901D01*
G01X3056727Y-1065926D02*
Y-1074587D01*
G01X3054237Y-1065926D02*
X3059217D01*
G01X3063114Y-1074587D02*
Y-1065926D01*
G01X3067662D02*
Y-1074587D01*
G01Y-1070257D02*
X3063114D01*
G01X3074590Y-1077474D02*
X3075673Y-1076030D01*
X3076214Y-1074587D01*
Y-1068813D01*
X3075673Y-1067369D01*
X3074590Y-1065926D01*
G01X3026772Y-1019476D02*
X3027422Y-1020486D01*
X3028288Y-1021064D01*
X3029262Y-1021208D01*
X3030128Y-1021064D01*
X3030995Y-1020342D01*
X3031536Y-1019476D01*
X3031644Y-1018610D01*
X3031428Y-1017599D01*
X3030670Y-1016878D01*
X3029912Y-1016589D01*
X3028937D01*
G01X3029912D02*
X3030561Y-1016156D01*
X3031103Y-1015434D01*
X3031319Y-1014568D01*
X3031103Y-1013702D01*
X3030561Y-1012980D01*
X3029587Y-1012547D01*
X3028613Y-1012691D01*
X3027638Y-1013269D01*
G01X3037815Y-1021497D02*
X3037598Y-1021352D01*
Y-1021064D01*
X3037815Y-1020919D01*
X3038032Y-1021064D01*
Y-1021352D01*
X3037815Y-1021497D01*
G01X3044419Y-1013990D02*
X3045069Y-1013125D01*
X3045826Y-1012691D01*
X3046693Y-1012547D01*
X3047775Y-1012836D01*
X3048533Y-1013557D01*
X3048750Y-1014423D01*
X3048641Y-1015290D01*
X3048208Y-1016011D01*
X3046043Y-1017455D01*
X3045069Y-1018465D01*
X3044419Y-1019909D01*
X3044202Y-1021208D01*
X3048750D01*
G01X3055137Y-1012547D02*
X3054271Y-1012836D01*
X3053621Y-1013557D01*
X3053188Y-1014423D01*
X3052863Y-1015578D01*
X3052755Y-1016878D01*
X3052863Y-1018177D01*
X3053188Y-1019332D01*
X3053621Y-1020198D01*
X3054271Y-1020919D01*
X3055137Y-1021208D01*
X3056003Y-1020919D01*
X3056653Y-1020198D01*
X3057086Y-1019332D01*
X3057411Y-1018177D01*
X3057519Y-1016878D01*
X3057411Y-1015578D01*
X3057086Y-1014423D01*
X3056653Y-1013557D01*
X3056003Y-1012836D01*
X3055137Y-1012547D01*
G01X3025424Y-291925D02*
X3028316D01*
G01X3029361D02*
X3032253D01*
G01X3029361Y-275389D02*
Y-291925D01*
G01X3028316D02*
Y-275389D01*
G01X3025424D02*
Y-291925D01*
G01X3024379D02*
Y-275389D01*
G01X3032972Y-299208D02*
G03X3040452I3740J0D01*
G01X3032972D02*
Y-271846D01*
G01X3032253Y-291925D02*
Y-275389D01*
G01X3028316D02*
X3025424D01*
G01X3032253D02*
X3029361D01*
G01X3032972Y-271846D02*
X3031003Y-269878D01*
G01X3030577Y150767D02*
X3038279Y158470D01*
G01Y369271D02*
Y141712D01*
G01X3636645D02*
X3038279D01*
G01X3029815Y519074D02*
Y412775D01*
G01X3030996Y1094074D02*
X3033752D01*
G01X3034933D02*
X3037689D01*
G01X3027059D02*
X3029815D01*
G01X3023122D02*
X3025878D01*
G01X3034933Y1110610D02*
Y1094074D01*
G01X3033752D02*
Y1110610D01*
G01X3030996D02*
Y1094074D01*
G01X3029815D02*
Y1110610D01*
G01X3027059D02*
Y1094074D01*
G01X3025878D02*
Y1110610D01*
G01X3023122D02*
Y1094074D01*
G01X3021941D02*
Y1110610D01*
G01X3037689Y1094074D02*
Y1110610D01*
G01X3025878D02*
X3023122D01*
G01X3029815D02*
X3027059D01*
G01X3033752D02*
X3030996D01*
G01X3037689D02*
X3034933D01*
G01X3054407Y-1003570D02*
X3053324Y-1002126D01*
X3052783Y-1000683D01*
Y-994909D01*
X3053324Y-993465D01*
X3054407Y-992022D01*
G01X3061444Y-1000683D02*
Y-992022D01*
X3064042D01*
X3064908Y-992455D01*
X3065558Y-993465D01*
X3065774Y-994620D01*
X3065558Y-995775D01*
X3065016Y-996641D01*
X3064042Y-997074D01*
X3061444D01*
G01X3069563Y-1000683D02*
X3072270Y-992022D01*
X3074977Y-1000683D01*
G01X3074002Y-997652D02*
X3070538D01*
G01X3078549Y-1000683D02*
Y-992022D01*
X3080714D01*
X3081581Y-992455D01*
X3082230Y-993032D01*
X3082772Y-993898D01*
X3083205Y-994909D01*
X3083313Y-996353D01*
X3083205Y-997796D01*
X3082772Y-998807D01*
X3082230Y-999673D01*
X3081581Y-1000250D01*
X3080714Y-1000683D01*
X3078549D01*
G01X3090133Y-1003570D02*
X3091216Y-1002126D01*
X3091757Y-1000683D01*
Y-994909D01*
X3091216Y-993465D01*
X3090133Y-992022D01*
G01X3073523Y-955508D02*
G03I-13779J0D01*
G01X3066633D02*
G03I-6889J0D01*
G01X3056520Y-682988D02*
X3051948D01*
G01D02*
Y-646413D01*
G01D02*
X3056520D01*
G01X3043996Y-291925D02*
X3041240D01*
G01X3047933D02*
X3045177D01*
G01D02*
Y-275389D01*
G01X3043996D02*
Y-291925D01*
G01X3041240D02*
Y-275389D01*
G01X3040452Y-271846D02*
Y-299208D01*
G01X3051870Y-291925D02*
X3049114D01*
G01X3055807D02*
X3053051D01*
G01D02*
Y-275389D01*
G01X3051870D02*
Y-291925D01*
G01X3049114D02*
Y-275389D01*
G01X3047933D02*
Y-291925D01*
G01X3045177Y-275389D02*
X3047933D01*
G01X3041240D02*
X3043996D01*
G01X3084547D02*
X3040452D01*
G01X3053051D02*
X3055807D01*
G01X3049114D02*
X3051870D01*
G01X3082578Y-269878D02*
X3042421D01*
G01D02*
X3040452Y-271846D01*
G01X3044236Y196229D02*
X3070374Y232753D01*
G01X3048500Y353392D02*
X3049258Y354402D01*
X3049907Y354980D01*
X3050774Y355268D01*
X3051531Y354980D01*
X3052073Y354402D01*
X3052506Y353536D01*
X3052614Y352526D01*
X3052506Y351659D01*
X3052073Y350793D01*
X3051423Y350072D01*
X3050665Y349783D01*
X3049799Y350072D01*
X3049041Y350938D01*
X3048608Y352237D01*
X3048500Y353680D01*
X3048716Y355557D01*
X3049041Y356568D01*
X3049583Y357578D01*
X3050340Y358300D01*
X3051098Y358444D01*
X3051856Y358155D01*
X3052398Y357434D01*
G01X3060517Y349783D02*
Y358444D01*
X3056511Y352237D01*
X3061925D01*
G01X3067879Y349494D02*
X3067662Y349639D01*
Y349927D01*
X3067879Y350072D01*
X3068096Y349927D01*
Y349639D01*
X3067879Y349494D01*
G01X3076540Y349783D02*
X3077298Y349927D01*
X3078164Y350360D01*
X3078705Y351082D01*
X3078922Y352093D01*
X3078705Y353103D01*
X3078056Y353969D01*
X3077081Y354402D01*
X3075999D01*
X3075349Y354691D01*
X3074808Y355413D01*
X3074591Y356423D01*
X3074916Y357434D01*
X3075674Y358155D01*
X3076540Y358444D01*
X3077406Y358155D01*
X3078164Y357434D01*
X3078489Y356423D01*
X3078272Y355413D01*
X3077731Y354691D01*
X3077081Y354402D01*
X3075999D01*
X3075024Y353969D01*
X3074375Y353103D01*
X3074158Y352093D01*
X3074375Y351082D01*
X3074916Y350360D01*
X3075782Y349927D01*
X3076540Y349783D01*
G01X3085201Y358444D02*
X3084335Y358155D01*
X3083685Y357434D01*
X3083252Y356568D01*
X3082927Y355413D01*
X3082819Y354113D01*
X3082927Y352814D01*
X3083252Y351659D01*
X3083685Y350793D01*
X3084335Y350072D01*
X3085201Y349783D01*
X3086067Y350072D01*
X3086717Y350793D01*
X3087150Y351659D01*
X3087475Y352814D01*
X3087583Y354113D01*
X3087475Y355413D01*
X3087150Y356568D01*
X3086717Y357434D01*
X3086067Y358155D01*
X3085201Y358444D01*
G01X3047403Y340381D02*
X3072870Y327430D01*
G01X3092807Y430492D02*
X3049538D01*
G01X3050681Y1094074D02*
X3053437D01*
G01X3046744D02*
X3049500D01*
G01X3042807D02*
X3045563D01*
G01X3038870D02*
X3041626D01*
G01X3050681Y1110610D02*
Y1094074D01*
G01X3049500D02*
Y1110610D01*
G01X3046744D02*
Y1094074D01*
G01X3045563D02*
Y1110610D01*
G01X3042807D02*
Y1094074D01*
G01X3041626D02*
Y1110610D01*
G01X3038870D02*
Y1094074D01*
G01X3054618D02*
X3057374D01*
G01X3054618Y1110610D02*
Y1094074D01*
G01X3053437D02*
Y1110610D01*
G01X3041626D02*
X3038870D01*
G01X3045563D02*
X3042807D01*
G01X3049500D02*
X3046744D01*
G01X3053437D02*
X3050681D01*
G01X3057374D02*
X3054618D01*
G01X3059222Y-1201143D02*
X3058139Y-1199699D01*
X3057598Y-1198256D01*
Y-1192482D01*
X3058139Y-1191038D01*
X3059222Y-1189595D01*
G01X3065934Y-1198256D02*
Y-1189595D01*
X3070914Y-1198256D01*
Y-1189595D01*
G01X3074920Y-1198256D02*
Y-1189595D01*
X3077518D01*
X3078384Y-1190028D01*
X3079034Y-1191038D01*
X3079250Y-1192193D01*
X3079034Y-1193348D01*
X3078492Y-1194214D01*
X3077518Y-1194647D01*
X3074920D01*
G01X3085746Y-1189595D02*
Y-1198256D01*
G01X3083256Y-1189595D02*
X3088236D01*
G01X3092133Y-1198256D02*
Y-1189595D01*
G01X3096681D02*
Y-1198256D01*
G01Y-1193926D02*
X3092133D01*
G01X3103609Y-1201143D02*
X3104692Y-1199699D01*
X3105233Y-1198256D01*
Y-1192482D01*
X3104692Y-1191038D01*
X3103609Y-1189595D01*
G01X3068771Y-1179555D02*
X3067688Y-1178111D01*
X3067147Y-1176668D01*
Y-1170894D01*
X3067688Y-1169450D01*
X3068771Y-1168007D01*
G01X3075808Y-1176668D02*
Y-1168007D01*
X3078406D01*
X3079272Y-1168440D01*
X3079922Y-1169450D01*
X3080138Y-1170605D01*
X3079922Y-1171760D01*
X3079380Y-1172626D01*
X3078406Y-1173059D01*
X3075808D01*
G01X3083927Y-1176668D02*
X3086634Y-1168007D01*
X3089341Y-1176668D01*
G01X3088366Y-1173637D02*
X3084902D01*
G01X3092913Y-1176668D02*
Y-1168007D01*
X3095078D01*
X3095945Y-1168440D01*
X3096594Y-1169017D01*
X3097136Y-1169883D01*
X3097569Y-1170894D01*
X3097677Y-1172338D01*
X3097569Y-1173781D01*
X3097136Y-1174792D01*
X3096594Y-1175658D01*
X3095945Y-1176235D01*
X3095078Y-1176668D01*
X3092913D01*
G01X3104497Y-1179555D02*
X3105580Y-1178111D01*
X3106121Y-1176668D01*
Y-1170894D01*
X3105580Y-1169450D01*
X3104497Y-1168007D01*
G01X3059794Y-1024095D02*
X3058711Y-1022651D01*
X3058170Y-1021208D01*
Y-1015434D01*
X3058711Y-1013990D01*
X3059794Y-1012547D01*
G01X3066506Y-1021208D02*
Y-1012547D01*
X3071486Y-1021208D01*
Y-1012547D01*
G01X3075492Y-1021208D02*
Y-1012547D01*
X3078090D01*
X3078956Y-1012980D01*
X3079606Y-1013990D01*
X3079822Y-1015145D01*
X3079606Y-1016300D01*
X3079064Y-1017166D01*
X3078090Y-1017599D01*
X3075492D01*
G01X3086318Y-1012547D02*
Y-1021208D01*
G01X3083828Y-1012547D02*
X3088808D01*
G01X3092705Y-1021208D02*
Y-1012547D01*
G01X3097253D02*
Y-1021208D01*
G01Y-1016878D02*
X3092705D01*
G01X3104181Y-1024095D02*
X3105264Y-1022651D01*
X3105805Y-1021208D01*
Y-1015434D01*
X3105264Y-1013990D01*
X3104181Y-1012547D01*
G01X3069186Y-965543D02*
X3103385Y-1001892D01*
G01X3065468Y-959342D02*
X3100953Y-983107D01*
G01X3056520Y-665868D02*
Y-682988D01*
G01X3077855Y-665868D02*
X3056520D01*
G01Y-661199D02*
X3077855D01*
G01X3056520Y-646413D02*
Y-661199D01*
G01X3059744Y-291925D02*
X3056988D01*
G01X3063681D02*
X3060925D01*
G01X3063681Y-275389D02*
Y-291925D01*
G01X3060925D02*
Y-275389D01*
G01X3059744D02*
Y-291925D01*
G01X3056988D02*
Y-275389D01*
G01X3055807D02*
Y-291925D01*
G01X3067618D02*
X3064862D01*
G01X3071555D02*
X3068799D01*
G01D02*
Y-275389D01*
G01X3067618D02*
Y-291925D01*
G01X3064862D02*
Y-275389D01*
G01X3060925D02*
X3063681D01*
G01X3056988D02*
X3059744D01*
G01X3068799D02*
X3071555D01*
G01X3064862D02*
X3067618D01*
G01X3070374Y232753D02*
X3082185D01*
G01X3066114Y384330D02*
X3061311D01*
G01X3400287Y382854D02*
X3065641D01*
G01X3057767Y381181D02*
X3408161D01*
G01X3066114Y384330D02*
Y388661D01*
G01X3065641Y385118D02*
Y381181D01*
G01X3061311Y388661D02*
Y384330D01*
G01X3057767Y381181D02*
Y415728D01*
G01X3069014Y384063D02*
X3070143D01*
G01X3070153Y383795D02*
X3069004D01*
G01X3070134Y383346D02*
X3069023D01*
G01X3070011Y382362D02*
X3070134D01*
G01X3069023D02*
X3070134D01*
G01X3069023D02*
X3069145D01*
G01X3070157Y385582D02*
X3070153Y383795D01*
G01X3070143Y384063D02*
X3070148Y385850D01*
G01X3070011Y383346D02*
Y382362D01*
G01X3069145Y383346D02*
Y382362D01*
G01X3069009Y385850D02*
X3069014Y384063D01*
G01X3069004Y383795D02*
X3068999Y385582D01*
G01X3063870Y390531D02*
X3065445Y392106D01*
G01Y395649D02*
G03I-2953J0D01*
G01X3066232Y397410D02*
G03Y393889I-3740J-1761D01*
G01X3058752Y393277D02*
G03X3066232I3740J2372D01*
G01X3065445Y392106D02*
X3400484D01*
G01X3063870Y390531D02*
X3348128D01*
G01X3061311Y388661D02*
X3066114D01*
G01X3065248Y386299D02*
X3061311D01*
G01X3065641Y385118D02*
X3057767D01*
G01X3066232Y398022D02*
Y393277D01*
G01X3065445Y392106D02*
Y399193D01*
G01X3065248Y388661D02*
Y386299D01*
G01X3063870Y400767D02*
Y390531D01*
G01X3058752Y393277D02*
Y393889D01*
G01X3065445Y399193D02*
X3063870Y400767D01*
G01X3066232Y398022D02*
G03X3058752I-3740J-2373D01*
G01X3348128Y400767D02*
X3063870D01*
G01X3065445Y399193D02*
X3400484D01*
G01X3058752Y397410D02*
Y398022D01*
G01X3068963Y393977D02*
X3070193D01*
G01X3068975Y393694D02*
X3070182D01*
G01X3070206Y393607D02*
X3068951D01*
G01X3068963Y392993D02*
X3070193D01*
G01X3070184Y392767D02*
X3068972D01*
G01X3068953Y392697D02*
X3070204D01*
G01X3068990Y387283D02*
X3070167D01*
G01Y386299D02*
X3068990D01*
G01X3070148Y385850D02*
X3069009D01*
G01X3068999Y385582D02*
X3070157D01*
G01X3070172Y392106D02*
X3070184Y392767D01*
G01X3070182Y393694D02*
X3070152Y392106D01*
G01X3068943D02*
X3068953Y392697D01*
G01X3068951Y393607D02*
X3068926Y392106D01*
G01X3070167Y386299D02*
Y387283D01*
G01X3068990D02*
Y386299D01*
G01X3070231Y392106D02*
X3070206Y393607D01*
G01X3070204Y392697D02*
X3070213Y392106D01*
G01X3069006D02*
X3068975Y393694D01*
G01X3068972Y392767D02*
X3068985Y392106D01*
G01X3070204Y398602D02*
X3068953D01*
G01X3068972Y398532D02*
X3070184D01*
G01X3070193Y398306D02*
X3068963D01*
G01X3068951Y397691D02*
X3070206D01*
G01X3070182Y397604D02*
X3068975D01*
G01X3070193Y397322D02*
X3068963D01*
G01X3068975Y397604D02*
X3069006Y399193D01*
G01X3068985D02*
X3068972Y398532D01*
G01X3070206Y397691D02*
X3070231Y399193D01*
G01X3070213D02*
X3070204Y398602D01*
G01X3068953D02*
X3068943Y399193D01*
G01X3068926D02*
X3068951Y397691D01*
G01X3070184Y398532D02*
X3070172Y399193D01*
G01X3070152D02*
X3070182Y397604D01*
G01X3065641Y410137D02*
X3057767D01*
G01X3408161Y410118D02*
X3057767D01*
G01X3065641Y408444D02*
X3400287D01*
G01X3066114Y406968D02*
X3061311D01*
G01X3057767Y406181D02*
X3065641D01*
G01X3065248Y405000D02*
X3061311D01*
G01X3066114Y402637D02*
X3061311D01*
G01X3066114Y406968D02*
Y402637D01*
G01X3065641Y406181D02*
Y410137D01*
G01X3065248Y402637D02*
Y405000D01*
G01X3061311Y402637D02*
Y406968D01*
G01X3074224Y415728D02*
X3057767D01*
G01X3069145Y408937D02*
X3069023D01*
G01X3070134D02*
X3069023D01*
G01X3070134D02*
X3070011D01*
G01X3070134Y407952D02*
X3069023D01*
G01X3069004Y407504D02*
X3070152D01*
G01X3070143Y407236D02*
X3069014D01*
G01X3070157Y405716D02*
X3068999D01*
G01X3069009Y405449D02*
X3070148D01*
G01X3070167Y405000D02*
X3068990D01*
G01X3070167Y404015D02*
X3068990D01*
G01X3069014Y407236D02*
X3069009Y405449D01*
G01X3068999Y405716D02*
X3069004Y407504D01*
G01X3070167Y404015D02*
Y405000D01*
G01X3070011Y408937D02*
Y407952D01*
G01X3069145D02*
Y408937D01*
G01X3068990Y405000D02*
Y404015D01*
G01X3070152Y407504D02*
X3070157Y405716D01*
G01X3070148Y405449D02*
X3070143Y407236D01*
G01X3069972Y1086791D02*
G03X3077452I3740J0D01*
G01X3069972D02*
Y1114153D01*
G01X3066429Y1094074D02*
X3069185D01*
G01X3062492D02*
X3065248D01*
G01X3058555D02*
X3061311D01*
G01X3066429Y1110610D02*
Y1094074D01*
G01X3065248D02*
Y1110610D01*
G01X3062492D02*
Y1094074D01*
G01X3061311D02*
Y1110610D01*
G01X3058555D02*
Y1094074D01*
G01X3057374D02*
Y1110610D01*
G01X3069185Y1094074D02*
Y1110610D01*
G01X3061311D02*
X3058555D01*
G01X3065248D02*
X3062492D01*
G01X3069185D02*
X3066429D01*
G01X3069972Y1114153D02*
X3068004Y1116122D01*
G01X3071547Y1166181D02*
X3062886D01*
X3064618Y1164882D01*
G01X3071547D02*
Y1167480D01*
G01X3069815Y1172460D02*
X3070825Y1173110D01*
X3071403Y1173976D01*
X3071547Y1174950D01*
X3071403Y1175816D01*
X3070681Y1176683D01*
X3069815Y1177224D01*
X3068949Y1177332D01*
X3067938Y1177116D01*
X3067217Y1176358D01*
X3066928Y1175600D01*
Y1174625D01*
G01Y1175600D02*
X3066495Y1176249D01*
X3065773Y1176791D01*
X3064907Y1177007D01*
X3064041Y1176791D01*
X3063319Y1176249D01*
X3062886Y1175275D01*
X3063030Y1174301D01*
X3063608Y1173326D01*
G01X3070537Y1181662D02*
X3071258Y1182420D01*
X3071547Y1183286D01*
X3071258Y1184153D01*
X3070392Y1184910D01*
X3069093Y1185452D01*
X3067794Y1185668D01*
X3066206D01*
X3064907Y1185452D01*
X3063752Y1184910D01*
X3063175Y1184261D01*
X3062886Y1183503D01*
X3063175Y1182637D01*
X3063752Y1181987D01*
X3064618Y1181554D01*
X3065773Y1181338D01*
X3066783Y1181554D01*
X3067794Y1182096D01*
X3068371Y1182745D01*
X3068516Y1183503D01*
X3068227Y1184369D01*
X3067505Y1185019D01*
X3066206Y1185668D01*
G01X3071836Y1192164D02*
X3071691Y1191947D01*
X3071403D01*
X3071258Y1192164D01*
X3071403Y1192381D01*
X3071691D01*
X3071836Y1192164D01*
G01X3070248Y1198443D02*
X3070970Y1199093D01*
X3071403Y1199851D01*
X3071547Y1200825D01*
X3071258Y1201799D01*
X3070681Y1202557D01*
X3069671Y1203099D01*
X3068516Y1203207D01*
X3067361Y1202990D01*
X3066639Y1202449D01*
X3066062Y1201691D01*
X3065917Y1200933D01*
X3066062Y1200175D01*
X3066639Y1199201D01*
X3062886Y1199526D01*
Y1202449D01*
G01Y1209486D02*
X3063175Y1208620D01*
X3063896Y1207970D01*
X3064762Y1207537D01*
X3065917Y1207212D01*
X3067217Y1207104D01*
X3068516Y1207212D01*
X3069671Y1207537D01*
X3070537Y1207970D01*
X3071258Y1208620D01*
X3071547Y1209486D01*
X3071258Y1210352D01*
X3070537Y1211002D01*
X3069671Y1211435D01*
X3068516Y1211760D01*
X3067217Y1211868D01*
X3065917Y1211760D01*
X3064762Y1211435D01*
X3063896Y1211002D01*
X3063175Y1210352D01*
X3062886Y1209486D01*
G01X3082427Y-682988D02*
X3077855D01*
G01D02*
Y-665868D01*
G01X3082427Y-646413D02*
Y-682988D01*
G01X3077855Y-661199D02*
Y-646413D01*
G01D02*
X3082427D01*
G01X3084547Y-301374D02*
G03X3088484Y-305311I3937J0D01*
G01X3075492Y-291925D02*
X3072736D01*
G01X3079429D02*
X3076673D01*
G01X3079429Y-275389D02*
Y-291925D01*
G01X3076673D02*
Y-275389D01*
G01X3075492D02*
Y-291925D01*
G01X3072736D02*
Y-275389D01*
G01X3071555D02*
Y-291925D01*
G01X3084547Y-301374D02*
Y-271846D01*
G01X3080610Y-291857D02*
X3083366D01*
G01D02*
Y-279241D01*
G01X3080610D02*
Y-291857D01*
G01X3076673Y-275389D02*
X3079429D01*
G01X3072736D02*
X3075492D01*
G01X3083366Y-279241D02*
X3080610D01*
G01X3076043Y-267830D02*
X3075059D01*
G01D02*
X3077683Y-259956D01*
G01X3076699Y-265820D02*
X3076043Y-267830D01*
G01X3077683Y-259956D02*
X3078996D01*
G01X3079816Y-265150D02*
X3076863D01*
G01X3079980Y-265820D02*
X3076699D01*
G01X3078339Y-260627D02*
X3079816Y-265150D01*
G01X3080636Y-267830D02*
X3079980Y-265820D01*
G01X3078996Y-259956D02*
X3081620Y-267830D01*
G01X3076863Y-265150D02*
X3078339Y-260627D01*
G01X3081620Y-267830D02*
X3080636D01*
G01X3084901D02*
X3083917D01*
G01X3084547Y-271846D02*
X3082578Y-269878D01*
G01X3084901Y-259956D02*
Y-267830D01*
G01X3083917D02*
Y-261297D01*
G01Y-259956D02*
X3084901D01*
G01X3082933Y-262469D02*
Y-261129D01*
G01X3083917Y-261297D02*
X3082933Y-262469D01*
G01Y-261129D02*
X3083917Y-259956D01*
G01X3082943Y228422D02*
Y237083D01*
X3087923Y228422D01*
Y237083D01*
G01X3094094Y228422D02*
X3093444Y228566D01*
X3092795Y229144D01*
X3092362Y230154D01*
X3092145Y231309D01*
X3092362Y232464D01*
X3092795Y233474D01*
X3093444Y234052D01*
X3094094Y234196D01*
X3094744Y234052D01*
X3095393Y233474D01*
X3095826Y232464D01*
X3095935Y231309D01*
X3095826Y230154D01*
X3095393Y229144D01*
X3094744Y228566D01*
X3094094Y228422D01*
G01X3111416Y237083D02*
Y228422D01*
G01X3109900Y234196D02*
X3112932D01*
G01X3118561Y228422D02*
Y234196D01*
G01Y233041D02*
X3119103Y233619D01*
X3119644Y234052D01*
X3120402Y234196D01*
X3120943Y234052D01*
X3121593Y233619D01*
G01X3130687Y228422D02*
Y234196D01*
G01Y233186D02*
X3130254Y233763D01*
X3129604Y234052D01*
X3128846Y234196D01*
X3128088Y233907D01*
X3127439Y233330D01*
X3127006Y232464D01*
X3126789Y231309D01*
X3127006Y230154D01*
X3127439Y229288D01*
X3128088Y228711D01*
X3128846Y228422D01*
X3129604Y228566D01*
X3130254Y228999D01*
X3130687Y229577D01*
G01X3139131Y233474D02*
X3138373Y234052D01*
X3137724Y234196D01*
X3136858Y233907D01*
X3136208Y233330D01*
X3135775Y232319D01*
X3135667Y231309D01*
X3135775Y230298D01*
X3136208Y229432D01*
X3136858Y228711D01*
X3137724Y228422D01*
X3138482Y228711D01*
X3139131Y229288D01*
G01X3144436Y232319D02*
X3147901D01*
X3147576Y233330D01*
X3147034Y233907D01*
X3146277Y234196D01*
X3145519Y234052D01*
X3144869Y233619D01*
X3144436Y232608D01*
X3144219Y231742D01*
Y230876D01*
X3144436Y230010D01*
X3144977Y229144D01*
X3145627Y228566D01*
X3146385Y228422D01*
X3147143Y228711D01*
X3147901Y229577D01*
G01X3165331Y228422D02*
Y234196D01*
G01Y233186D02*
X3164898Y233763D01*
X3164248Y234052D01*
X3163490Y234196D01*
X3162732Y233907D01*
X3162083Y233330D01*
X3161650Y232464D01*
X3161433Y231309D01*
X3161650Y230154D01*
X3162083Y229288D01*
X3162732Y228711D01*
X3163490Y228422D01*
X3164248Y228566D01*
X3164898Y228999D01*
X3165331Y229577D01*
G01X3172043Y237083D02*
Y228422D01*
G01X3170527Y234196D02*
X3173559D01*
G01X3187741Y229432D02*
X3188282Y228855D01*
X3189040Y228422D01*
X3189690D01*
X3190339Y228711D01*
X3190772Y229144D01*
X3190989Y229721D01*
X3190881Y230587D01*
X3190448Y231020D01*
X3188499Y231886D01*
X3188066Y232897D01*
X3188282Y233619D01*
X3188715Y234052D01*
X3189365Y234196D01*
X3190015Y234052D01*
X3190664Y233619D01*
G01X3196185Y234196D02*
Y230154D01*
X3196619Y229144D01*
X3197268Y228566D01*
X3198026Y228422D01*
X3198784Y228566D01*
X3199433Y229144D01*
X3199867Y230154D01*
G01Y228422D02*
Y234196D01*
G01X3205171Y228422D02*
Y234196D01*
G01Y233041D02*
X3205713Y233619D01*
X3206254Y234052D01*
X3207012Y234196D01*
X3207553Y234052D01*
X3208203Y233619D01*
G01X3214698Y228422D02*
Y235784D01*
X3214915Y236505D01*
X3215348Y236939D01*
X3215998Y237083D01*
X3216647Y236794D01*
X3216972Y236073D01*
G01X3215673Y233619D02*
X3213507D01*
G01X3225958Y228422D02*
Y234196D01*
G01Y233186D02*
X3225525Y233763D01*
X3224875Y234052D01*
X3224117Y234196D01*
X3223359Y233907D01*
X3222710Y233330D01*
X3222277Y232464D01*
X3222060Y231309D01*
X3222277Y230154D01*
X3222710Y229288D01*
X3223359Y228711D01*
X3224117Y228422D01*
X3224875Y228566D01*
X3225525Y228999D01*
X3225958Y229577D01*
G01X3234402Y233474D02*
X3233644Y234052D01*
X3232995Y234196D01*
X3232129Y233907D01*
X3231479Y233330D01*
X3231046Y232319D01*
X3230938Y231309D01*
X3231046Y230298D01*
X3231479Y229432D01*
X3232129Y228711D01*
X3232995Y228422D01*
X3233753Y228711D01*
X3234402Y229288D01*
G01X3239707Y232319D02*
X3243172D01*
X3242847Y233330D01*
X3242305Y233907D01*
X3241548Y234196D01*
X3240790Y234052D01*
X3240140Y233619D01*
X3239707Y232608D01*
X3239490Y231742D01*
Y230876D01*
X3239707Y230010D01*
X3240248Y229144D01*
X3240898Y228566D01*
X3241656Y228422D01*
X3242414Y228711D01*
X3243172Y229577D01*
G01X3085439Y323099D02*
Y331760D01*
X3090419Y323099D01*
Y331760D01*
G01X3096590Y323099D02*
X3095940Y323243D01*
X3095291Y323821D01*
X3094858Y324831D01*
X3094641Y325986D01*
X3094858Y327141D01*
X3095291Y328151D01*
X3095940Y328729D01*
X3096590Y328873D01*
X3097240Y328729D01*
X3097889Y328151D01*
X3098322Y327141D01*
X3098431Y325986D01*
X3098322Y324831D01*
X3097889Y323821D01*
X3097240Y323243D01*
X3096590Y323099D01*
G01X3113912Y331760D02*
Y323099D01*
G01X3112396Y328873D02*
X3115428D01*
G01X3121057Y323099D02*
Y328873D01*
G01Y327718D02*
X3121599Y328296D01*
X3122140Y328729D01*
X3122898Y328873D01*
X3123439Y328729D01*
X3124089Y328296D01*
G01X3133183Y323099D02*
Y328873D01*
G01Y327863D02*
X3132750Y328440D01*
X3132100Y328729D01*
X3131342Y328873D01*
X3130584Y328584D01*
X3129935Y328007D01*
X3129502Y327141D01*
X3129285Y325986D01*
X3129502Y324831D01*
X3129935Y323965D01*
X3130584Y323388D01*
X3131342Y323099D01*
X3132100Y323243D01*
X3132750Y323676D01*
X3133183Y324254D01*
G01X3141627Y328151D02*
X3140869Y328729D01*
X3140220Y328873D01*
X3139354Y328584D01*
X3138704Y328007D01*
X3138271Y326996D01*
X3138163Y325986D01*
X3138271Y324975D01*
X3138704Y324109D01*
X3139354Y323388D01*
X3140220Y323099D01*
X3140978Y323388D01*
X3141627Y323965D01*
G01X3146932Y326996D02*
X3150397D01*
X3150072Y328007D01*
X3149530Y328584D01*
X3148773Y328873D01*
X3148015Y328729D01*
X3147365Y328296D01*
X3146932Y327285D01*
X3146715Y326419D01*
Y325553D01*
X3146932Y324687D01*
X3147473Y323821D01*
X3148123Y323243D01*
X3148881Y323099D01*
X3149639Y323388D01*
X3150397Y324254D01*
G01X3159166Y323099D02*
Y328873D01*
G01Y327863D02*
X3158733Y328440D01*
X3158083Y328729D01*
X3157325Y328873D01*
X3156567Y328584D01*
X3155918Y328007D01*
X3155485Y327141D01*
X3155268Y325986D01*
X3155485Y324831D01*
X3155918Y323965D01*
X3156567Y323388D01*
X3157325Y323099D01*
X3158083Y323243D01*
X3158733Y323676D01*
X3159166Y324254D01*
G01X3165878Y331760D02*
Y323099D01*
G01X3164362Y328873D02*
X3167394D01*
G01X3181576Y324109D02*
X3182117Y323532D01*
X3182875Y323099D01*
X3183525D01*
X3184174Y323388D01*
X3184607Y323821D01*
X3184824Y324398D01*
X3184716Y325264D01*
X3184283Y325697D01*
X3182334Y326563D01*
X3181901Y327574D01*
X3182117Y328296D01*
X3182550Y328729D01*
X3183200Y328873D01*
X3183850Y328729D01*
X3184499Y328296D01*
G01X3190020Y328873D02*
Y324831D01*
X3190454Y323821D01*
X3191103Y323243D01*
X3191861Y323099D01*
X3192619Y323243D01*
X3193268Y323821D01*
X3193702Y324831D01*
G01Y323099D02*
Y328873D01*
G01X3199006Y323099D02*
Y328873D01*
G01Y327718D02*
X3199548Y328296D01*
X3200089Y328729D01*
X3200847Y328873D01*
X3201388Y328729D01*
X3202038Y328296D01*
G01X3208533Y323099D02*
Y330461D01*
X3208750Y331182D01*
X3209183Y331616D01*
X3209833Y331760D01*
X3210482Y331471D01*
X3210807Y330750D01*
G01X3209508Y328296D02*
X3207342D01*
G01X3219793Y323099D02*
Y328873D01*
G01Y327863D02*
X3219360Y328440D01*
X3218710Y328729D01*
X3217952Y328873D01*
X3217194Y328584D01*
X3216545Y328007D01*
X3216112Y327141D01*
X3215895Y325986D01*
X3216112Y324831D01*
X3216545Y323965D01*
X3217194Y323388D01*
X3217952Y323099D01*
X3218710Y323243D01*
X3219360Y323676D01*
X3219793Y324254D01*
G01X3228237Y328151D02*
X3227479Y328729D01*
X3226830Y328873D01*
X3225964Y328584D01*
X3225314Y328007D01*
X3224881Y326996D01*
X3224773Y325986D01*
X3224881Y324975D01*
X3225314Y324109D01*
X3225964Y323388D01*
X3226830Y323099D01*
X3227588Y323388D01*
X3228237Y323965D01*
G01X3233542Y326996D02*
X3237007D01*
X3236682Y328007D01*
X3236140Y328584D01*
X3235383Y328873D01*
X3234625Y328729D01*
X3233975Y328296D01*
X3233542Y327285D01*
X3233325Y326419D01*
Y325553D01*
X3233542Y324687D01*
X3234083Y323821D01*
X3234733Y323243D01*
X3235491Y323099D01*
X3236249Y323388D01*
X3237007Y324254D01*
G01X3072870Y327430D02*
X3084681D01*
G01X3076888Y384063D02*
X3078017D01*
G01X3078027Y383795D02*
X3076878D01*
G01X3078008Y383346D02*
X3076897D01*
G01Y382362D02*
X3078008D01*
G01X3076897D02*
X3077019D01*
G01X3078032Y385582D02*
X3078027Y383795D01*
G01X3078017Y384063D02*
X3078022Y385850D01*
G01X3077885Y383346D02*
Y382362D01*
G01X3077019Y383346D02*
Y382362D01*
G01X3076883Y385850D02*
X3076888Y384063D01*
G01X3076878Y383795D02*
X3076873Y385582D01*
G01X3084762Y384063D02*
X3085891D01*
G01X3085901Y383795D02*
X3084752D01*
G01X3085882Y383346D02*
X3084771D01*
G01Y382362D02*
X3085882D01*
G01X3085906Y385582D02*
X3085901Y383795D01*
G01X3085891Y384063D02*
X3085896Y385850D01*
G01X3085759Y383346D02*
Y382362D01*
G01X3084893Y383346D02*
Y382362D01*
G01X3084757Y385850D02*
X3084762Y384063D01*
G01X3084752Y383795D02*
X3084747Y385582D01*
G01X3080774Y393977D02*
X3082004D01*
G01X3076837D02*
X3078067D01*
G01X3072900D02*
X3074130D01*
G01X3080786Y393694D02*
X3081993D01*
G01X3076849D02*
X3078056D01*
G01X3072912D02*
X3074119D01*
G01X3078080Y393607D02*
X3076825D01*
G01X3074143D02*
X3072888D01*
G01X3082017D02*
X3080762D01*
G01X3080774Y392993D02*
X3082004D01*
G01X3076837D02*
X3078067D01*
G01X3072900D02*
X3074130D01*
G01X3078058Y392767D02*
X3076846D01*
G01X3074121D02*
X3072909D01*
G01X3081995D02*
X3080783D01*
G01X3080764Y392697D02*
X3082015D01*
G01X3076827D02*
X3078078D01*
G01X3072890D02*
X3074141D01*
G01X3073082Y391220D02*
X3072960D01*
G01X3074071D02*
X3072960D01*
G01X3081945D02*
X3080834D01*
G01X3074071D02*
X3073948D01*
G01X3080834Y390236D02*
X3081945D01*
G01X3072960D02*
X3074071D01*
G01X3080815Y389787D02*
X3081964D01*
G01X3072941D02*
X3074090D01*
G01X3074080Y389519D02*
X3072951D01*
G01X3081954D02*
X3080825D01*
G01X3074095Y388000D02*
X3072936D01*
G01X3081969D02*
X3080810D01*
G01X3080820Y387732D02*
X3081959D01*
G01X3072946D02*
X3074085D01*
G01X3080801Y387283D02*
X3081978D01*
G01X3072927D02*
X3074104D01*
G01X3076864D02*
X3078041D01*
G01X3074104Y386299D02*
X3072927D01*
G01X3078041D02*
X3076864D01*
G01X3081978D02*
X3080801D01*
G01X3078022Y385850D02*
X3076883D01*
G01X3076873Y385582D02*
X3078032D01*
G01X3081983Y392106D02*
X3081995Y392767D01*
G01X3081993Y393694D02*
X3081963Y392106D01*
G01X3078046D02*
X3078058Y392767D01*
G01X3078056Y393694D02*
X3078026Y392106D01*
G01X3074109D02*
X3074121Y392767D01*
G01X3074119Y393694D02*
X3074089Y392106D01*
G01X3080754D02*
X3080764Y392697D01*
G01X3080762Y393607D02*
X3080737Y392106D01*
G01X3076817D02*
X3076827Y392697D01*
G01X3076825Y393607D02*
X3076800Y392106D01*
G01X3072880D02*
X3072890Y392697D01*
G01X3072888Y393607D02*
X3072863Y392106D01*
G01X3080825Y389519D02*
X3080820Y387732D01*
G01X3080810Y388000D02*
X3080815Y389787D01*
G01X3072951Y389519D02*
X3072946Y387732D01*
G01X3072936Y388000D02*
X3072941Y389787D01*
G01X3081978Y387283D02*
Y386299D01*
G01X3081822Y391220D02*
Y390236D01*
G01X3080956Y391220D02*
Y390236D01*
G01X3080801Y386299D02*
Y387283D01*
G01X3078041Y386299D02*
Y387283D01*
G01X3076864D02*
Y386299D01*
G01X3074104Y387283D02*
Y386299D01*
G01X3073948Y391220D02*
Y390236D01*
G01X3073082Y391220D02*
Y390236D01*
G01X3072927Y386299D02*
Y387283D01*
G01X3081964Y389787D02*
X3081969Y388000D01*
G01X3081959Y387732D02*
X3081954Y389519D01*
G01X3074090Y389787D02*
X3074095Y388000D01*
G01X3074085Y387732D02*
X3074080Y389519D01*
G01X3082042Y392106D02*
X3082017Y393607D01*
G01X3082015Y392697D02*
X3082024Y392106D01*
G01X3078105D02*
X3078080Y393607D01*
G01X3078078Y392697D02*
X3078087Y392106D01*
G01X3074168D02*
X3074143Y393607D01*
G01X3074141Y392697D02*
X3074150Y392106D01*
G01X3080817D02*
X3080786Y393694D01*
G01X3080783Y392767D02*
X3080796Y392106D01*
G01X3076880D02*
X3076849Y393694D01*
G01X3076846Y392767D02*
X3076859Y392106D01*
G01X3072943D02*
X3072912Y393694D01*
G01X3072909Y392767D02*
X3072922Y392106D01*
G01X3074071Y401063D02*
X3072960D01*
G01X3081945D02*
X3080834D01*
G01X3073948Y400078D02*
X3074071D01*
G01D02*
X3072960D01*
G01X3081945D02*
X3080834D01*
G01X3072960D02*
X3073082D01*
G01X3078078Y398602D02*
X3076827D01*
G01X3074141D02*
X3072890D01*
G01X3082015D02*
X3080764D01*
G01X3080783Y398532D02*
X3081995D01*
G01X3076846D02*
X3078058D01*
G01X3072909D02*
X3074121D01*
G01X3078067Y398306D02*
X3076837D01*
G01X3074130D02*
X3072900D01*
G01X3082004D02*
X3080774D01*
G01X3080762Y397691D02*
X3082017D01*
G01X3076825D02*
X3078080D01*
G01X3072888D02*
X3074143D01*
G01X3078056Y397604D02*
X3076849D01*
G01X3074119D02*
X3072912D01*
G01X3081993D02*
X3080786D01*
G01X3078067Y397322D02*
X3076837D01*
G01X3074130D02*
X3072900D01*
G01X3082004D02*
X3080774D01*
G01X3080786Y397604D02*
X3080817Y399193D01*
G01X3080796D02*
X3080783Y398532D01*
G01X3076849Y397604D02*
X3076880Y399193D01*
G01X3076859D02*
X3076846Y398532D01*
G01X3072912Y397604D02*
X3072943Y399193D01*
G01X3072922D02*
X3072909Y398532D01*
G01X3082017Y397691D02*
X3082042Y399193D01*
G01X3082024D02*
X3082015Y398602D01*
G01X3078080Y397691D02*
X3078105Y399193D01*
G01X3078087D02*
X3078078Y398602D01*
G01X3074143Y397691D02*
X3074168Y399193D01*
G01X3074150D02*
X3074141Y398602D01*
G01X3081822Y401063D02*
Y400078D01*
G01X3080956D02*
Y401063D01*
G01X3073948D02*
Y400078D01*
G01X3073082D02*
Y401063D01*
G01X3080764Y398602D02*
X3080754Y399193D01*
G01X3080737D02*
X3080762Y397691D01*
G01X3076827Y398602D02*
X3076817Y399193D01*
G01X3076800D02*
X3076825Y397691D01*
G01X3072890Y398602D02*
X3072880Y399193D01*
G01X3072863D02*
X3072888Y397691D01*
G01X3081995Y398532D02*
X3081983Y399193D01*
G01X3081963D02*
X3081993Y397604D01*
G01X3078058Y398532D02*
X3078046Y399193D01*
G01X3078026D02*
X3078056Y397604D01*
G01X3074121Y398532D02*
X3074109Y399193D01*
G01X3074089D02*
X3074119Y397604D01*
G01X3084711Y393977D02*
X3085941D01*
G01X3084723Y393694D02*
X3085930D01*
G01X3085954Y393607D02*
X3084699D01*
G01X3084711Y392993D02*
X3085941D01*
G01X3085932Y392767D02*
X3084720D01*
G01X3084701Y392697D02*
X3085952D01*
G01X3084738Y387283D02*
X3085915D01*
G01Y386299D02*
X3084738D01*
G01X3085896Y385850D02*
X3084757D01*
G01X3084747Y385582D02*
X3085906D01*
G01X3085920Y392106D02*
X3085932Y392767D01*
G01X3085930Y393694D02*
X3085900Y392106D01*
G01X3084691D02*
X3084701Y392697D01*
G01X3084699Y393607D02*
X3084674Y392106D01*
G01X3085915Y386299D02*
Y387283D01*
G01X3084738D02*
Y386299D01*
G01X3085979Y392106D02*
X3085954Y393607D01*
G01X3085952Y392697D02*
X3085961Y392106D01*
G01X3084754D02*
X3084723Y393694D01*
G01X3084720Y392767D02*
X3084733Y392106D01*
G01X3085952Y398602D02*
X3084701D01*
G01X3084720Y398532D02*
X3085932D01*
G01X3085941Y398306D02*
X3084711D01*
G01X3084699Y397691D02*
X3085954D01*
G01X3085930Y397604D02*
X3084723D01*
G01X3085941Y397322D02*
X3084711D01*
G01X3084723Y397604D02*
X3084754Y399193D01*
G01X3084733D02*
X3084720Y398532D01*
G01X3085954Y397691D02*
X3085979Y399193D01*
G01X3085961D02*
X3085952Y398602D01*
G01X3084701D02*
X3084691Y399193D01*
G01X3084674D02*
X3084699Y397691D01*
G01X3085932Y398532D02*
X3085920Y399193D01*
G01X3085900D02*
X3085930Y397604D01*
G01X3078008Y408937D02*
X3076897D01*
G01X3078008Y407952D02*
X3076897D01*
G01X3076878Y407504D02*
X3078026D01*
G01X3078017Y407236D02*
X3076888D01*
G01X3078032Y405716D02*
X3076873D01*
G01X3076883Y405449D02*
X3078022D01*
G01X3074104Y405000D02*
X3072927D01*
G01X3078041D02*
X3076864D01*
G01X3081978D02*
X3080801D01*
G01X3074104Y404015D02*
X3072927D01*
G01X3078041D02*
X3076864D01*
G01X3081978D02*
X3080801D01*
G01X3074085Y403567D02*
X3072946D01*
G01X3081959D02*
X3080820D01*
G01X3080810Y403299D02*
X3081969D01*
G01X3072936D02*
X3074095D01*
G01X3080825Y401779D02*
X3081954D01*
G01X3072951D02*
X3074080D01*
G01X3074089Y401512D02*
X3072941D01*
G01X3081963D02*
X3080815D01*
G01X3081969Y403299D02*
X3081963Y401512D01*
G01X3081954Y401779D02*
X3081959Y403567D01*
G01X3076888Y407236D02*
X3076883Y405449D01*
G01X3076873Y405716D02*
X3076878Y407504D01*
G01X3074095Y403299D02*
X3074089Y401512D01*
G01X3074080Y401779D02*
X3074085Y403567D01*
G01X3081978Y405000D02*
Y404015D01*
G01X3080801D02*
Y405000D01*
G01X3079224Y415728D02*
Y410118D01*
G01X3078041Y404015D02*
Y405000D01*
G01X3077885Y408937D02*
Y407952D01*
G01X3077019D02*
Y408937D01*
G01X3076864Y405000D02*
Y404015D01*
G01X3074224Y415728D02*
Y410118D01*
G01X3074104Y405000D02*
Y404015D01*
G01X3072927D02*
Y405000D01*
G01X3080820Y403567D02*
X3080825Y401779D01*
G01X3080815Y401512D02*
X3080810Y403299D01*
G01X3078026Y407504D02*
X3078032Y405716D01*
G01X3078022Y405449D02*
X3078017Y407236D01*
G01X3072946Y403567D02*
X3072951Y401779D01*
G01X3072941Y401512D02*
X3072936Y403299D01*
G01X3095130Y415728D02*
X3079224D01*
G01X3085882Y408937D02*
X3084771D01*
G01X3085882Y407952D02*
X3084771D01*
G01X3084752Y407504D02*
X3085900D01*
G01X3085891Y407236D02*
X3084762D01*
G01X3085906Y405716D02*
X3084747D01*
G01X3084757Y405449D02*
X3085896D01*
G01X3085915Y405000D02*
X3084738D01*
G01X3085915Y404015D02*
X3084738D01*
G01X3084762Y407236D02*
X3084757Y405449D01*
G01X3084747Y405716D02*
X3084752Y407504D01*
G01X3085915Y404015D02*
Y405000D01*
G01X3085759Y408937D02*
Y407952D01*
G01X3084893D02*
Y408937D01*
G01X3084738Y405000D02*
Y404015D01*
G01X3085900Y407504D02*
X3085906Y405716D01*
G01X3085896Y405449D02*
X3085891Y407236D01*
G01X3084933Y515137D02*
Y416712D01*
G01X3084964Y452843D02*
G03X3092807Y444271I7843J-698D01*
G01X3084964Y452843D02*
X3084933Y515137D01*
G01X3094578Y544891D02*
X3085917D01*
X3087649Y543592D01*
G01X3094578D02*
Y546190D01*
G01Y554851D02*
X3085917D01*
X3092124Y550845D01*
Y556259D01*
G01X3093279Y559831D02*
X3094001Y560481D01*
X3094434Y561239D01*
X3094578Y562213D01*
X3094289Y563187D01*
X3093712Y563945D01*
X3092702Y564487D01*
X3091547Y564595D01*
X3090392Y564378D01*
X3089670Y563837D01*
X3089093Y563079D01*
X3088948Y562321D01*
X3089093Y561563D01*
X3089670Y560589D01*
X3085917Y560914D01*
Y563837D01*
G01X3094867Y570874D02*
X3094722Y570657D01*
X3094434D01*
X3094289Y570874D01*
X3094434Y571091D01*
X3094722D01*
X3094867Y570874D01*
G01X3092846Y577153D02*
X3093856Y577803D01*
X3094434Y578669D01*
X3094578Y579643D01*
X3094434Y580509D01*
X3093712Y581376D01*
X3092846Y581917D01*
X3091980Y582025D01*
X3090969Y581809D01*
X3090248Y581051D01*
X3089959Y580293D01*
Y579318D01*
G01Y580293D02*
X3089526Y580942D01*
X3088804Y581484D01*
X3087938Y581700D01*
X3087072Y581484D01*
X3086350Y580942D01*
X3085917Y579968D01*
X3086061Y578994D01*
X3086639Y578019D01*
G01X3093279Y585814D02*
X3094001Y586464D01*
X3094434Y587222D01*
X3094578Y588196D01*
X3094289Y589170D01*
X3093712Y589928D01*
X3092702Y590470D01*
X3091547Y590578D01*
X3090392Y590361D01*
X3089670Y589820D01*
X3089093Y589062D01*
X3088948Y588304D01*
X3089093Y587546D01*
X3089670Y586572D01*
X3085917Y586897D01*
Y589820D01*
G01X3077452Y1114153D02*
Y1086791D01*
G01X3073712Y1090728D02*
Y1158602D01*
G01X3080996Y1094074D02*
X3078240D01*
G01X3084933D02*
X3082177D01*
G01D02*
Y1110610D01*
G01X3080996D02*
Y1094074D01*
G01X3078240D02*
Y1110610D01*
G01X3088870Y1094074D02*
X3086114D01*
G01D02*
Y1110610D01*
G01X3084933D02*
Y1094074D01*
G01X3119578Y1116122D02*
X3079421D01*
G01X3082177Y1110610D02*
X3084933D01*
G01X3078240D02*
X3080996D01*
G01X3121547D02*
X3077452D01*
G01X3079421Y1116122D02*
X3077452Y1114153D01*
G01X3086114Y1110610D02*
X3088870D01*
G01X3103385Y-1001892D02*
X3106535D01*
G01X3100953Y-983107D02*
X3104103D01*
G01X3088523Y-667424D02*
X3100715D01*
G01Y-670537D02*
X3088523D01*
G01D02*
Y-667424D01*
G01X3100715D02*
Y-670537D01*
G01X3088523Y-658086D02*
X3100715D01*
G01Y-661199D02*
X3088523D01*
G01D02*
Y-658086D01*
G01X3100715D02*
Y-661199D01*
G01X3200688Y-305311D02*
X3088484D01*
G01X3100510Y384063D02*
X3101639D01*
G01X3092636D02*
X3093765D01*
G01X3093775Y383795D02*
X3092626D01*
G01X3101649D02*
X3100500D01*
G01X3093756Y383346D02*
X3092645D01*
G01X3101630D02*
X3100519D01*
G01Y382362D02*
X3101630D01*
G01X3092645D02*
X3093756D01*
G01X3093780Y385582D02*
X3093775Y383795D01*
G01X3093765Y384063D02*
X3093770Y385850D01*
G01X3100641Y383346D02*
Y382362D01*
G01X3093633Y383346D02*
Y382362D01*
G01X3092767Y383346D02*
Y382362D01*
G01X3100505Y385850D02*
X3100510Y384063D01*
G01X3100500Y383795D02*
X3100495Y385582D01*
G01X3092631Y385850D02*
X3092636Y384063D01*
G01X3092626Y383795D02*
X3092621Y385582D01*
G01X3101654D02*
X3101649Y383795D01*
G01X3101639Y384063D02*
X3101644Y385850D01*
G01X3101507Y383346D02*
Y382362D01*
G01X3100459Y393977D02*
X3101689D01*
G01X3096522D02*
X3097752D01*
G01X3092585D02*
X3093815D01*
G01X3088648D02*
X3089878D01*
G01X3100471Y393694D02*
X3101678D01*
G01X3096534D02*
X3097741D01*
G01X3092597D02*
X3093804D01*
G01X3088660D02*
X3089867D01*
G01X3089891Y393607D02*
X3088636D01*
G01X3093828D02*
X3092573D01*
G01X3101702D02*
X3100447D01*
G01X3097765D02*
X3096510D01*
G01X3100459Y392993D02*
X3101689D01*
G01X3096522D02*
X3097752D01*
G01X3092585D02*
X3093815D01*
G01X3088648D02*
X3089878D01*
G01X3089869Y392767D02*
X3088657D01*
G01X3093806D02*
X3092595D01*
G01X3101680D02*
X3100469D01*
G01X3097743D02*
X3096532D01*
G01X3100449Y392697D02*
X3101700D01*
G01X3096512D02*
X3097763D01*
G01X3092575D02*
X3093826D01*
G01X3088638D02*
X3089889D01*
G01X3089819Y391220D02*
X3088708D01*
G01X3097693D02*
X3096582D01*
G01Y390236D02*
X3097693D01*
G01X3088708D02*
X3089819D01*
G01X3096563Y389787D02*
X3097712D01*
G01X3088689D02*
X3089838D01*
G01X3089828Y389519D02*
X3088699D01*
G01X3097702D02*
X3096573D01*
G01X3089843Y388000D02*
X3088684D01*
G01X3097717D02*
X3096558D01*
G01X3096568Y387732D02*
X3097707D01*
G01X3088694D02*
X3089833D01*
G01X3100486Y387283D02*
X3101663D01*
G01X3096549D02*
X3097726D01*
G01X3092612D02*
X3093789D01*
G01X3088675D02*
X3089852D01*
G01Y386299D02*
X3088675D01*
G01X3093789D02*
X3092612D01*
G01X3101663D02*
X3100486D01*
G01X3097726D02*
X3096549D01*
G01X3093770Y385850D02*
X3092631D01*
G01X3101644D02*
X3100505D01*
G01X3100495Y385582D02*
X3101654D01*
G01X3092621D02*
X3093780D01*
G01X3097731Y392106D02*
X3097743Y392767D01*
G01X3097741Y393694D02*
X3097711Y392106D01*
G01X3093794D02*
X3093806Y392767D01*
G01X3093804Y393694D02*
X3093774Y392106D01*
G01X3089857D02*
X3089869Y392767D01*
G01X3089867Y393694D02*
X3089837Y392106D01*
G01X3100439D02*
X3100449Y392697D01*
G01X3100447Y393607D02*
X3100422Y392106D01*
G01X3096502D02*
X3096512Y392697D01*
G01X3096510Y393607D02*
X3096485Y392106D01*
G01X3092565D02*
X3092575Y392697D01*
G01X3092573Y393607D02*
X3092548Y392106D01*
G01X3088628D02*
X3088638Y392697D01*
G01X3088636Y393607D02*
X3088611Y392106D01*
G01X3096573Y389519D02*
X3096568Y387732D01*
G01X3096558Y388000D02*
X3096563Y389787D01*
G01X3088699Y389519D02*
X3088694Y387732D01*
G01X3088684Y388000D02*
X3088689Y389787D01*
G01X3100486Y387283D02*
Y386299D01*
G01X3097726Y387283D02*
Y386299D01*
G01X3097570Y391220D02*
Y390236D01*
G01X3096704Y391220D02*
Y390236D01*
G01X3096549Y386299D02*
Y387283D01*
G01X3093789Y386299D02*
Y387283D01*
G01X3092612D02*
Y386299D01*
G01X3089852Y387283D02*
Y386299D01*
G01X3089696Y391220D02*
Y390236D01*
G01X3088830Y391220D02*
Y390236D01*
G01X3088675Y386299D02*
Y387283D01*
G01X3097712Y389787D02*
X3097717Y388000D01*
G01X3097707Y387732D02*
X3097702Y389519D01*
G01X3089838Y389787D02*
X3089843Y388000D01*
G01X3089833Y387732D02*
X3089828Y389519D01*
G01X3097790Y392106D02*
X3097765Y393607D01*
G01X3097763Y392697D02*
X3097772Y392106D01*
G01X3093853D02*
X3093828Y393607D01*
G01X3093826Y392697D02*
X3093835Y392106D01*
G01X3089916D02*
X3089891Y393607D01*
G01X3089889Y392697D02*
X3089898Y392106D01*
G01X3100502D02*
X3100471Y393694D01*
G01X3100469Y392767D02*
X3100482Y392106D01*
G01X3096565D02*
X3096534Y393694D01*
G01X3096532Y392767D02*
X3096545Y392106D01*
G01X3092628D02*
X3092597Y393694D01*
G01X3092595Y392767D02*
X3092607Y392106D01*
G01X3088691D02*
X3088660Y393694D01*
G01X3088657Y392767D02*
X3088670Y392106D01*
G01X3089819Y401063D02*
X3088708D01*
G01X3097693D02*
X3096582D01*
G01X3089819Y400078D02*
X3088708D01*
G01X3097693D02*
X3096582D01*
G01X3089889Y398602D02*
X3088638D01*
G01X3093826D02*
X3092575D01*
G01X3097763D02*
X3096512D01*
G01X3101700D02*
X3100449D01*
G01X3096532Y398532D02*
X3097743D01*
G01X3100469D02*
X3101680D01*
G01X3092595D02*
X3093806D01*
G01X3088657D02*
X3089869D01*
G01X3089878Y398306D02*
X3088648D01*
G01X3093815D02*
X3092585D01*
G01X3097752D02*
X3096522D01*
G01X3101689D02*
X3100459D01*
G01X3096510Y397691D02*
X3097765D01*
G01X3100447D02*
X3101702D01*
G01X3092573D02*
X3093828D01*
G01X3088636D02*
X3089891D01*
G01X3089867Y397604D02*
X3088660D01*
G01X3093804D02*
X3092597D01*
G01X3097741D02*
X3096534D01*
G01X3101678D02*
X3100471D01*
G01X3089878Y397322D02*
X3088648D01*
G01X3093815D02*
X3092585D01*
G01X3097752D02*
X3096522D01*
G01X3101689D02*
X3100459D01*
G01X3100471Y397604D02*
X3100502Y399193D01*
G01X3100482D02*
X3100469Y398532D01*
G01X3096534Y397604D02*
X3096565Y399193D01*
G01X3096545D02*
X3096532Y398532D01*
G01X3092597Y397604D02*
X3092628Y399193D01*
G01X3092607D02*
X3092595Y398532D01*
G01X3088660Y397604D02*
X3088691Y399193D01*
G01X3088670D02*
X3088657Y398532D01*
G01X3097765Y397691D02*
X3097790Y399193D01*
G01X3097772D02*
X3097763Y398602D01*
G01X3093828Y397691D02*
X3093853Y399193D01*
G01X3093835D02*
X3093826Y398602D01*
G01X3089891Y397691D02*
X3089916Y399193D01*
G01X3089898D02*
X3089889Y398602D01*
G01X3097570Y401063D02*
Y400078D01*
G01X3096704D02*
Y401063D01*
G01X3089696D02*
Y400078D01*
G01X3088830D02*
Y401063D01*
G01X3100449Y398602D02*
X3100439Y399193D01*
G01X3100422D02*
X3100447Y397691D01*
G01X3096512Y398602D02*
X3096502Y399193D01*
G01X3096485D02*
X3096510Y397691D01*
G01X3092575Y398602D02*
X3092565Y399193D01*
G01X3092548D02*
X3092573Y397691D01*
G01X3088638Y398602D02*
X3088628Y399193D01*
G01X3088611D02*
X3088636Y397691D01*
G01X3097743Y398532D02*
X3097731Y399193D01*
G01X3097711D02*
X3097741Y397604D01*
G01X3093806Y398532D02*
X3093794Y399193D01*
G01X3093774D02*
X3093804Y397604D01*
G01X3089869Y398532D02*
X3089857Y399193D01*
G01X3089837D02*
X3089867Y397604D01*
G01X3101668Y392106D02*
X3101680Y392767D01*
G01X3101678Y393694D02*
X3101648Y392106D01*
G01X3101663Y386299D02*
Y387283D01*
G01X3101727Y392106D02*
X3101702Y393607D01*
G01X3101700Y392697D02*
X3101709Y392106D01*
G01X3101702Y397691D02*
X3101727Y399193D01*
G01X3101709D02*
X3101700Y398602D01*
G01X3101680Y398532D02*
X3101668Y399193D01*
G01X3101648D02*
X3101678Y397604D01*
G01X3093756Y408937D02*
X3092645D01*
G01X3101630D02*
X3100519D01*
G01X3093756Y407952D02*
X3092645D01*
G01X3101630D02*
X3100519D01*
G01X3100500Y407504D02*
X3101648D01*
G01X3092626D02*
X3093774D01*
G01X3093765Y407236D02*
X3092636D01*
G01X3101639D02*
X3100510D01*
G01X3093780Y405716D02*
X3092621D01*
G01X3101654D02*
X3100495D01*
G01X3100505Y405449D02*
X3101644D01*
G01X3092631D02*
X3093770D01*
G01X3089852Y405000D02*
X3088675D01*
G01X3093789D02*
X3092612D01*
G01X3097726D02*
X3096549D01*
G01X3101663D02*
X3100486D01*
G01X3089852Y404015D02*
X3088675D01*
G01X3093789D02*
X3092612D01*
G01X3097726D02*
X3096549D01*
G01X3101663D02*
X3100486D01*
G01X3089833Y403567D02*
X3088694D01*
G01X3097707D02*
X3096568D01*
G01X3096558Y403299D02*
X3097717D01*
G01X3088684D02*
X3089843D01*
G01X3096573Y401779D02*
X3097702D01*
G01X3088699D02*
X3089828D01*
G01X3089837Y401512D02*
X3088689D01*
G01X3097711D02*
X3096563D01*
G01X3100510Y407236D02*
X3100505Y405449D01*
G01X3100495Y405716D02*
X3100500Y407504D01*
G01X3097717Y403299D02*
X3097711Y401512D01*
G01X3097702Y401779D02*
X3097707Y403567D01*
G01X3092636Y407236D02*
X3092631Y405449D01*
G01X3092621Y405716D02*
X3092626Y407504D01*
G01X3089843Y403299D02*
X3089837Y401512D01*
G01X3089828Y401779D02*
X3089833Y403567D01*
G01X3100641Y407952D02*
Y408937D01*
G01X3100486Y405000D02*
Y404015D01*
G01X3100130Y415728D02*
Y410118D01*
G01X3097726Y405000D02*
Y404015D01*
G01X3096549D02*
Y405000D01*
G01X3095130Y415728D02*
Y410118D01*
G01X3093789Y404015D02*
Y405000D01*
G01X3093633Y408937D02*
Y407952D01*
G01X3092767D02*
Y408937D01*
G01X3092612Y405000D02*
Y404015D01*
G01X3089852Y405000D02*
Y404015D01*
G01X3088675D02*
Y405000D01*
G01X3096568Y403567D02*
X3096573Y401779D01*
G01X3096563Y401512D02*
X3096558Y403299D01*
G01X3093774Y407504D02*
X3093780Y405716D01*
G01X3093770Y405449D02*
X3093765Y407236D01*
G01X3088694Y403567D02*
X3088699Y401779D01*
G01X3088689Y401512D02*
X3088684Y403299D01*
G01X3096744Y416712D02*
G03Y444271I0J13780D01*
G01X3116035Y415728D02*
X3100130D01*
G01X3101663Y404015D02*
Y405000D01*
G01X3101507Y408937D02*
Y407952D01*
G01X3101648Y407504D02*
X3101654Y405716D01*
G01X3101644Y405449D02*
X3101639Y407236D01*
G01X3103633Y430492D02*
G03I-6889J0D01*
G01D02*
G03I-6889J0D01*
G01X3096744Y434429D02*
Y537312D01*
G01Y444271D02*
X3092807D01*
G01Y1094074D02*
X3090051D01*
G01X3096744D02*
X3093988D01*
G01X3100681D02*
X3097925D01*
G01X3100681Y1110610D02*
Y1094074D01*
G01X3097925D02*
Y1110610D01*
G01X3096744D02*
Y1094074D01*
G01X3093988D02*
Y1110610D01*
G01X3092807D02*
Y1094074D01*
G01X3090051D02*
Y1110610D01*
G01X3088870D02*
Y1094074D01*
G01X3104618D02*
X3101862D01*
G01D02*
Y1110610D01*
G01X3097925D02*
X3100681D01*
G01X3093988D02*
X3096744D01*
G01X3090051D02*
X3092807D01*
G01X3101862D02*
X3104618D01*
G01X3116603Y-999726D02*
Y-993952D01*
G01Y-995396D02*
X3117037Y-994674D01*
X3117686Y-994096D01*
X3118552Y-993952D01*
X3119310Y-994096D01*
X3119960Y-994674D01*
X3120285Y-995684D01*
Y-999726D01*
G01X3106535Y-1001892D02*
X3221154D01*
G01X3114171Y-980941D02*
Y-975167D01*
G01Y-976611D02*
X3114605Y-975889D01*
X3115254Y-975311D01*
X3116120Y-975167D01*
X3116878Y-975311D01*
X3117528Y-975889D01*
X3117853Y-976899D01*
Y-980941D01*
G01X3104103Y-983107D02*
X3210927D01*
G01X3115954Y-682988D02*
X3111382D01*
G01D02*
Y-652639D01*
G01X3115954Y-646413D02*
Y-682988D01*
G01X3106811Y-658086D02*
Y-651861D01*
G01X3111382Y-652639D02*
X3106811Y-658086D01*
G01Y-651861D02*
X3111382Y-646413D01*
G01D02*
X3115954D01*
G01X3111271Y86988D02*
G03X3112059Y86200I788J0D01*
G01X3110484D02*
G03X3111283Y85413I787J0D01*
G01X3114815Y88169D02*
G03X3115602Y88956I0J787D01*
G01X3117767Y85413D02*
G03X3116980Y86200I-787J0D01*
G01X3111271Y85551D02*
G03X3112059Y84763I788J0D01*
G01X3116586D02*
G03X3117374Y85551I0J788D01*
G01X3109696Y86200D02*
G03X3111271Y84626I1575J1D01*
G01X3116980Y85030D02*
Y84626D01*
G01X3115927Y132374D02*
Y88405D01*
G01X3115602Y90273D02*
Y88956D01*
G01X3111665Y85452D02*
Y179676D01*
G01X3111271Y177736D02*
Y85551D01*
G01X3110878Y179114D02*
Y86240D01*
G01X3110484Y86200D02*
Y178102D01*
G01X3109696Y86200D02*
Y178102D01*
G01X3110878Y86240D02*
X3111665Y85452D01*
G01X3172954Y88405D02*
X3115927D01*
G01X3109696Y88169D02*
X3114815D01*
G01X3110484Y87381D02*
X3109696D01*
G01Y86988D02*
X3110484D01*
G01X3109696Y86594D02*
X3110484D01*
G01X3112059Y86200D02*
X3134704D01*
G01X3110484D02*
X3109696D01*
G01X3117374Y85551D02*
X3111271D01*
G01X3177216Y85452D02*
X3111665D01*
G01X3109907Y85413D02*
X3178974D01*
G01X3116980Y85030D02*
X3111468D01*
G01X3116586Y84763D02*
X3112059D01*
G01X3111271Y84626D02*
X3177610D01*
G01X3120149Y88405D02*
G03X3119834Y87775I473J-630D01*
G01X3118374Y85413D02*
G03X3119150Y86064I0J788D01*
G01X3118374Y84626D02*
G03X3119925Y85927I0J1575D01*
G01X3120819Y86240D02*
X3120031Y85452D01*
G01X3118948Y86240D02*
X3118161Y85452D01*
G01X3119925Y85927D02*
X3121530Y95028D01*
G01X3120754Y95165D02*
X3119150Y86064D01*
G01X3119834Y84626D02*
Y88405D01*
G01X3119047Y85413D02*
Y84626D01*
G01X3118948Y103011D02*
Y86240D01*
G01X3118374Y85413D02*
Y84626D01*
G01X3117980Y85413D02*
Y84626D01*
G01X3117767Y85413D02*
Y84626D01*
G01X3117669Y90273D02*
Y85452D01*
G01X3117374Y90273D02*
Y85551D01*
G01X3117669Y86240D02*
X3171212D01*
G01X3169047Y85807D02*
X3119834D01*
G01X3116813Y101771D02*
G03I-1969J0D01*
G01X3113565Y99822D02*
X3112580Y98838D01*
G01X3117108D02*
Y118130D01*
G01X3116124Y123444D02*
Y99822D01*
G01X3113565Y123444D02*
Y99822D01*
G01X3112580Y98838D02*
Y118130D01*
G01X3111715Y96213D02*
Y90273D01*
G01X3117108Y98838D02*
X3116124Y99822D01*
G01D02*
X3113565D01*
G01X3117108Y98838D02*
X3112580D01*
G01X3110484Y97618D02*
X3109696D01*
G01X3110484Y96830D02*
X3109696D01*
G01X3117669Y96213D02*
X3111715D01*
G01X3109696Y96043D02*
X3111715D01*
G01X3117669Y90273D02*
X3111715D01*
G01X3117108Y105137D02*
X3116124Y104153D01*
G01X3115730Y108681D02*
Y100649D01*
G01X3113958D02*
Y108681D01*
G01X3113761Y100354D02*
Y103897D01*
G01X3111104Y105433D02*
Y117834D01*
G01X3113565Y104153D02*
X3112580Y105137D01*
G01X3118584Y105433D02*
X3111104D01*
G01X3117108Y105137D02*
X3119539D01*
G01X3112580D02*
X3110878D01*
G01X3113761Y103897D02*
X3115927D01*
G01X3115730Y103841D02*
X3113958D01*
G01X3115927Y102913D02*
X3113761D01*
G01X3115730Y102618D02*
X3113958D01*
G01Y101633D02*
X3115730D01*
G01Y100649D02*
X3113958D01*
G01X3115927Y100354D02*
X3113761D01*
G01X3120627Y99358D02*
X3119887Y99089D01*
G01X3120358Y100098D02*
X3119618Y99829D01*
G01X3117669Y105137D02*
Y96213D01*
G01X3117374D02*
Y117933D01*
G01X3121317Y97464D02*
X3120358Y100098D01*
G01X3119618Y99829D02*
X3120577Y97194D01*
G01X3119539Y105137D02*
Y118130D01*
G01X3118752D02*
Y105137D01*
G01X3118584Y117834D02*
Y105433D01*
G01X3118555Y132374D02*
Y104350D01*
G01X3118259Y131909D02*
Y103759D01*
G01X3170326Y104350D02*
X3118555D01*
G01X3129204Y103759D02*
X3118259D01*
G01X3120819Y103011D02*
X3118948D01*
G01X3116813Y111771D02*
G03I-1969J0D01*
G01X3115730Y112618D02*
Y110649D01*
G01Y122618D02*
Y114586D01*
G01X3113958Y112618D02*
Y110649D01*
G01Y122618D02*
Y114586D01*
G01X3113761Y112913D02*
Y110354D01*
G01X3115730Y116555D02*
X3113958D01*
G01X3115730Y116473D02*
X3113958D01*
G01X3115730Y114586D02*
X3113958D01*
G01X3115927Y112913D02*
X3113761D01*
G01X3115730Y112618D02*
X3113958D01*
G01X3115730Y110649D02*
X3113958D01*
G01X3115927Y110354D02*
X3113761D01*
G01X3111271Y108681D02*
X3117374D01*
G01X3113958Y106794D02*
X3115730D01*
G01Y106712D02*
X3113958D01*
G01Y105728D02*
X3115730D01*
G01X3112580Y118130D02*
X3113565Y119114D01*
G01X3117108D02*
Y124429D01*
G01X3113761Y119370D02*
Y122913D01*
G01X3112580Y124429D02*
Y119114D01*
G01X3116124D02*
X3117108Y118130D01*
G01X3115730Y121633D02*
X3113958D01*
G01Y120649D02*
X3115730D01*
G01X3115927Y120354D02*
X3113761D01*
G01X3115730Y119426D02*
X3113958D01*
G01X3115927Y119370D02*
X3113761D01*
G01X3113565Y119114D02*
X3110878D01*
G01X3117669D02*
X3116124D01*
G01X3117108Y118130D02*
X3171773D01*
G01X3112580D02*
X3110878D01*
G01X3117374Y117933D02*
X3111271D01*
G01X3118584Y117834D02*
X3111104D01*
G01X3115730Y117539D02*
X3113958D01*
G01X3117669Y119114D02*
Y118130D01*
G01X3116124Y123444D02*
X3117108Y124429D01*
G01X3116980Y131909D02*
Y132374D01*
G01X3115759Y137821D02*
Y132374D01*
G01X3114519Y140570D02*
Y132696D01*
G01X3114322Y131909D02*
Y177972D01*
G01X3112580Y124429D02*
X3113565Y123444D01*
G01X3110484Y132998D02*
X3109696D01*
G01X3110484Y132854D02*
X3109696D01*
G01X3115759Y132696D02*
X3114519D01*
G01X3115759Y132374D02*
X3121206D01*
G01X3109696Y132265D02*
X3110484D01*
G01Y132192D02*
X3109696D01*
G01Y132067D02*
X3110484D01*
G01X3174559Y131909D02*
X3114322D01*
G01X3109696Y131458D02*
X3110484D01*
G01X3109696Y127761D02*
X3110484D01*
G01X3109696Y126535D02*
X3110484D01*
G01Y125802D02*
X3109696D01*
G01X3112580Y124429D02*
X3117108D01*
G01X3116124Y123444D02*
X3113565D01*
G01X3115927Y122913D02*
X3113761D01*
G01X3115730Y122618D02*
X3113958D01*
G01X3112905Y136634D02*
G03I-3090J0D01*
G01X3116980Y137821D02*
Y177972D01*
G01X3115927Y152578D02*
Y137821D01*
G01X3119933Y138479D02*
X3116980D01*
G01X3110484Y137836D02*
X3109696D01*
G01X3121206Y137821D02*
X3115759D01*
G01X3109696Y135353D02*
X3110484D01*
G01X3109696Y134429D02*
X3110484D01*
G01X3115759Y133484D02*
X3114519D01*
G01X3131822Y136634D02*
G03I-6377J0D01*
G01X3118909Y136633D02*
X3125445Y130098D01*
G01X3129204Y128484D02*
X3118259D01*
G01X3125445Y143169D02*
X3118909Y136633D01*
G01X3119933Y137821D02*
Y138479D01*
G01X3119342D02*
Y137821D01*
G01X3119289D02*
Y138479D01*
G01X3119244D02*
Y137821D01*
G01X3119218Y138479D02*
Y137821D01*
G01X3119145D02*
Y148897D01*
G01X3119001Y137821D02*
Y138479D01*
G01X3118974D02*
Y137821D01*
G01X3118948Y138479D02*
Y137821D01*
G01X3117964Y138479D02*
Y137821D01*
G01X3117939D02*
Y138479D01*
G01X3117911D02*
Y137821D01*
G01X3117767D02*
Y148897D01*
G01X3117695Y137821D02*
Y138479D01*
G01X3117669D02*
Y137821D01*
G01X3117623Y138479D02*
Y137821D01*
G01X3117570Y138479D02*
Y137821D01*
G01X3117275Y140570D02*
Y137821D01*
G01X3114815Y143878D02*
G03X3115602Y144665I0J787D01*
G01Y150964D02*
Y144665D01*
G01X3112059Y177972D02*
Y149429D01*
G01D02*
X3110878D01*
G01X3109696Y143878D02*
X3114815D01*
G01X3110484Y143090D02*
X3109696D01*
G01Y142303D02*
X3110484D01*
G01Y141122D02*
X3109696D01*
G01X3114519Y140570D02*
X3174362D01*
G01X3109696Y140334D02*
X3110484D01*
G01Y138759D02*
X3109696D01*
G01X3114519Y138602D02*
X3174362D01*
G01X3115602Y150964D02*
G03X3114815Y151752I-787J1D01*
G01X3111665Y153523D02*
X3109696D01*
G01X3110484Y153326D02*
X3109696D01*
G01X3115927Y152578D02*
X3110878D01*
G01X3110484Y152539D02*
X3109696D01*
G01Y151752D02*
X3114815D01*
G01X3119145Y148897D02*
X3117767D01*
G01X3119145Y147519D02*
X3117767D01*
G01X3119145Y146535D02*
X3117767D01*
G01X3119145Y139463D02*
X3117767D01*
G01X3110484Y165292D02*
G03X3110878Y165974I-394J682D01*
G01Y164610D02*
G03X3110484Y163928I393J-682D01*
G01X3110878Y164610D02*
G03X3111665Y165974I-788J1364D01*
G01X3110484Y165292D02*
G03X3109696Y163928I787J-1364D01*
G01X3111665Y162224D02*
X3110878Y161437D01*
G01X3114519Y177185D02*
Y159862D01*
G01X3111615Y161200D02*
Y161004D01*
G01X3110484Y165763D02*
X3109696D01*
G01Y165199D02*
X3110484D01*
G01X3112059Y162224D02*
X3111665D01*
G01X3110878Y161200D02*
X3111665D01*
G01X3109696D02*
X3110484D01*
G01X3111615Y161004D02*
X3109696D01*
G01X3174362Y159862D02*
X3114519D01*
G01X3171901Y159665D02*
X3116980D01*
G01X3111665Y171240D02*
X3110878D01*
G01X3110484Y170818D02*
X3109696D01*
G01X3110484Y170228D02*
X3109696D01*
G01Y166331D02*
X3110484D01*
G01Y166094D02*
X3109696D01*
G01X3118850Y171193D02*
Y159862D01*
G01X3117275Y177185D02*
Y159862D01*
G01X3118850Y171193D02*
G03Y174043I1614J1425D01*
G01X3111271Y178889D02*
G03X3110484Y178102I0J-787D01*
G01X3111271Y179676D02*
G03X3109696Y178102I0J-1575D01*
G01X3111665Y177972D02*
X3110878Y177185D01*
G01X3110484Y171633D02*
X3111665Y175177D01*
G01X3110878D02*
X3109696Y171633D01*
G01X3111271Y177578D02*
X3111665Y177185D01*
G01X3110062Y179110D02*
X3110667Y178606D01*
G01X3111586Y174941D02*
X3110878Y175177D01*
G01X3177610Y179676D02*
X3111271D01*
G01X3111665Y179114D02*
X3110878D01*
G01X3111271Y178889D02*
X3177610D01*
G01X3117844Y178495D02*
X3111665D01*
G01X3110878Y178326D02*
X3111665D01*
G01X3109696Y178102D02*
X3110484D01*
G01X3111665Y177972D02*
X3177216D01*
G01X3111665Y177736D02*
X3110062D01*
G01X3110484Y177244D02*
X3109696D01*
G01X3177216Y177185D02*
X3111665D01*
G01X3110878Y175177D02*
X3111665D01*
G01X3110484Y174952D02*
X3109696D01*
G01X3110484Y174361D02*
X3109696D01*
G01X3110484Y171633D02*
X3109696D01*
G01X3117844Y178495D02*
G03X3118850Y177933I1006J619D01*
G01X3121645Y172618D02*
G03I-1181J0D01*
G01X3119972Y171929D02*
Y174463D01*
G01X3119937Y173398D02*
Y174527D01*
G01X3119874Y174959D02*
Y173831D01*
G01X3119775Y173307D02*
Y171929D01*
G01X3119711Y173586D02*
Y174715D01*
G01X3119677Y174847D02*
Y173650D01*
G01X3119578Y173307D02*
Y171929D01*
G01X3119283Y173307D02*
Y171929D01*
G01X3118850Y178889D02*
Y179676D01*
G01Y177185D02*
Y174043D01*
G01X3118791Y173307D02*
Y171929D01*
G01X3117844Y178889D02*
Y179676D01*
G01X3117717Y179331D02*
Y178774D01*
G01X3119937Y174527D02*
X3119711Y174715D01*
G01X3119937Y173398D02*
X3119711Y173586D01*
G01X3139322Y177933D02*
X3118850D01*
G01X3119874Y174959D02*
X3121055D01*
G01Y173831D02*
X3119874D01*
G01X3118791Y173307D02*
X3122137D01*
G01X3119972Y172178D02*
X3120956D01*
G01X3118791Y171929D02*
X3122137D01*
G01X3109528Y385582D02*
X3109523Y383795D01*
G01X3109513Y384063D02*
X3109518Y385850D01*
G01X3116389Y383346D02*
Y382362D01*
G01X3109382Y383346D02*
Y382362D01*
G01X3116253Y385850D02*
X3116258Y384063D01*
G01X3116248Y383795D02*
X3116243Y385582D01*
G01X3116258Y384063D02*
X3117387D01*
G01X3108384D02*
X3109513D01*
G01X3109523Y383795D02*
X3108374D01*
G01X3117397D02*
X3116248D01*
G01X3109504Y383346D02*
X3108393D01*
G01X3117378D02*
X3116267D01*
G01Y382362D02*
X3117378D01*
G01X3108393D02*
X3109504D01*
G01X3108515Y383346D02*
Y382362D01*
G01X3108379Y385850D02*
X3108384Y384063D01*
G01X3108374Y383795D02*
X3108369Y385582D01*
G01X3117402D02*
X3117397Y383795D01*
G01X3117387Y384063D02*
X3117392Y385850D01*
G01X3117256Y383346D02*
Y382362D01*
G01X3113479Y392106D02*
X3113491Y392767D01*
G01X3113489Y393694D02*
X3113459Y392106D01*
G01X3109542D02*
X3109554Y392767D01*
G01X3109552Y393694D02*
X3109522Y392106D01*
G01X3116187D02*
X3116197Y392697D01*
G01X3116195Y393607D02*
X3116170Y392106D01*
G01X3112250D02*
X3112260Y392697D01*
G01X3112258Y393607D02*
X3112233Y392106D01*
G01X3108313D02*
X3108323Y392697D01*
G01X3108321Y393607D02*
X3108296Y392106D01*
G01X3112321Y389519D02*
X3112316Y387732D01*
G01X3112306Y388000D02*
X3112311Y389787D01*
G01X3116234Y387283D02*
Y386299D01*
G01X3113474Y387283D02*
Y386299D01*
G01X3113319Y391220D02*
Y390236D01*
G01X3112452Y391220D02*
Y390236D01*
G01X3112297Y386299D02*
Y387283D01*
G01X3109537Y386299D02*
Y387283D01*
G01X3113460Y389787D02*
X3113465Y388000D01*
G01X3113455Y387732D02*
X3113450Y389519D01*
G01X3113538Y392106D02*
X3113513Y393607D01*
G01X3113511Y392697D02*
X3113520Y392106D01*
G01X3116250D02*
X3116219Y393694D01*
G01X3116217Y392767D02*
X3116230Y392106D01*
G01X3112313D02*
X3112282Y393694D01*
G01X3112280Y392767D02*
X3112293Y392106D01*
G01X3116207Y393977D02*
X3117437D01*
G01X3112270D02*
X3113500D01*
G01X3108333D02*
X3109563D01*
G01X3104396D02*
X3105626D01*
G01X3116219Y393694D02*
X3117426D01*
G01X3112282D02*
X3113489D01*
G01X3108345D02*
X3109552D01*
G01X3104408D02*
X3105615D01*
G01X3105639Y393607D02*
X3104384D01*
G01X3109576D02*
X3108321D01*
G01X3113513D02*
X3112258D01*
G01X3117450D02*
X3116195D01*
G01X3116207Y392993D02*
X3117437D01*
G01X3112270D02*
X3113500D01*
G01X3108333D02*
X3109563D01*
G01X3104396D02*
X3105626D01*
G01X3105617Y392767D02*
X3104406D01*
G01X3109554D02*
X3108343D01*
G01X3113491D02*
X3112280D01*
G01X3117428D02*
X3116217D01*
G01X3116197Y392697D02*
X3117448D01*
G01X3112260D02*
X3113511D01*
G01X3108323D02*
X3109574D01*
G01X3104386D02*
X3105637D01*
G01X3105567Y391220D02*
X3104456D01*
G01X3113441D02*
X3112330D01*
G01Y390236D02*
X3113441D01*
G01X3104456D02*
X3105567D01*
G01X3112311Y389787D02*
X3113460D01*
G01X3104437D02*
X3105586D01*
G01X3105576Y389519D02*
X3104447D01*
G01X3113450D02*
X3112321D01*
G01X3105591Y388000D02*
X3104432D01*
G01X3113465D02*
X3112306D01*
G01X3112316Y387732D02*
X3113455D01*
G01X3104442D02*
X3105581D01*
G01X3116234Y387283D02*
X3117411D01*
G01X3112297D02*
X3113474D01*
G01X3108360D02*
X3109537D01*
G01X3104423D02*
X3105600D01*
G01Y386299D02*
X3104423D01*
G01X3109537D02*
X3108360D01*
G01X3113474D02*
X3112297D01*
G01X3117411D02*
X3116234D01*
G01X3109518Y385850D02*
X3108379D01*
G01X3117392D02*
X3116253D01*
G01X3116243Y385582D02*
X3117402D01*
G01X3108369D02*
X3109528D01*
G01X3105605Y392106D02*
X3105617Y392767D01*
G01X3105615Y393694D02*
X3105585Y392106D01*
G01X3104376D02*
X3104386Y392697D01*
G01X3104384Y393607D02*
X3104359Y392106D01*
G01X3104447Y389519D02*
X3104442Y387732D01*
G01X3104432Y388000D02*
X3104437Y389787D01*
G01X3108360Y387283D02*
Y386299D01*
G01X3105600Y387283D02*
Y386299D01*
G01X3105445Y391220D02*
Y390236D01*
G01X3104578Y391220D02*
Y390236D01*
G01X3104423Y386299D02*
Y387283D01*
G01X3105586Y389787D02*
X3105591Y388000D01*
G01X3105581Y387732D02*
X3105576Y389519D01*
G01X3109601Y392106D02*
X3109576Y393607D01*
G01X3109574Y392697D02*
X3109583Y392106D01*
G01X3105664D02*
X3105639Y393607D01*
G01X3105637Y392697D02*
X3105646Y392106D01*
G01X3108376D02*
X3108345Y393694D01*
G01X3108343Y392767D02*
X3108356Y392106D01*
G01X3104439D02*
X3104408Y393694D01*
G01X3104406Y392767D02*
X3104419Y392106D01*
G01X3116219Y397604D02*
X3116250Y399193D01*
G01X3116230D02*
X3116217Y398532D01*
G01X3112282Y397604D02*
X3112313Y399193D01*
G01X3112293D02*
X3112280Y398532D01*
G01X3108345Y397604D02*
X3108376Y399193D01*
G01X3108356D02*
X3108343Y398532D01*
G01X3113513Y397691D02*
X3113538Y399193D01*
G01X3113520D02*
X3113511Y398602D01*
G01X3109576Y397691D02*
X3109601Y399193D01*
G01X3109583D02*
X3109574Y398602D01*
G01X3113319Y401063D02*
Y400078D01*
G01X3112452D02*
Y401063D01*
G01X3116197Y398602D02*
X3116187Y399193D01*
G01X3116170D02*
X3116195Y397691D01*
G01X3112260Y398602D02*
X3112250Y399193D01*
G01X3112233D02*
X3112258Y397691D01*
G01X3113491Y398532D02*
X3113479Y399193D01*
G01X3113459D02*
X3113489Y397604D01*
G01X3105567Y401063D02*
X3104456D01*
G01X3113441D02*
X3112330D01*
G01X3105567Y400078D02*
X3104456D01*
G01X3113441D02*
X3112330D01*
G01X3105637Y398602D02*
X3104386D01*
G01X3109574D02*
X3108323D01*
G01X3113511D02*
X3112260D01*
G01X3117448D02*
X3116197D01*
G01X3116217Y398532D02*
X3117428D01*
G01X3112280D02*
X3113491D01*
G01X3108343D02*
X3109554D01*
G01X3104406D02*
X3105617D01*
G01X3105626Y398306D02*
X3104396D01*
G01X3109563D02*
X3108333D01*
G01X3113500D02*
X3112270D01*
G01X3117437D02*
X3116207D01*
G01X3116195Y397691D02*
X3117450D01*
G01X3112258D02*
X3113513D01*
G01X3108321D02*
X3109576D01*
G01X3104384D02*
X3105639D01*
G01X3105615Y397604D02*
X3104408D01*
G01X3109552D02*
X3108345D01*
G01X3113489D02*
X3112282D01*
G01X3117426D02*
X3116219D01*
G01X3105626Y397322D02*
X3104396D01*
G01X3109563D02*
X3108333D01*
G01X3113500D02*
X3112270D01*
G01X3117437D02*
X3116207D01*
G01X3104408Y397604D02*
X3104439Y399193D01*
G01X3104419D02*
X3104406Y398532D01*
G01X3105639Y397691D02*
X3105664Y399193D01*
G01X3105646D02*
X3105637Y398602D01*
G01X3105445Y401063D02*
Y400078D01*
G01X3104578D02*
Y401063D01*
G01X3108323Y398602D02*
X3108313Y399193D01*
G01X3108296D02*
X3108321Y397691D01*
G01X3104386Y398602D02*
X3104376Y399193D01*
G01X3104359D02*
X3104384Y397691D01*
G01X3109554Y398532D02*
X3109542Y399193D01*
G01X3109522D02*
X3109552Y397604D01*
G01X3105617Y398532D02*
X3105605Y399193D01*
G01X3105585D02*
X3105615Y397604D01*
G01X3117416Y392106D02*
X3117428Y392767D01*
G01X3117426Y393694D02*
X3117396Y392106D01*
G01X3120124D02*
X3120134Y392697D01*
G01X3120132Y393607D02*
X3120107Y392106D01*
G01X3120195Y389519D02*
X3120190Y387732D01*
G01X3120180Y388000D02*
X3120185Y389787D01*
G01X3120326Y391220D02*
Y390236D01*
G01X3120171Y386299D02*
Y387283D01*
G01X3117411Y386299D02*
Y387283D01*
G01X3117475Y392106D02*
X3117450Y393607D01*
G01X3117448Y392697D02*
X3117457Y392106D01*
G01X3120187D02*
X3120156Y393694D01*
G01X3120154Y392767D02*
X3120167Y392106D01*
G01X3120145Y393977D02*
X3121374D01*
G01X3120156Y393694D02*
X3121363D01*
G01X3121387Y393607D02*
X3120132D01*
G01X3120145Y392993D02*
X3121374D01*
G01X3121365Y392767D02*
X3120154D01*
G01X3120134Y392697D02*
X3121385D01*
G01X3121315Y391220D02*
X3120204D01*
G01Y390236D02*
X3121315D01*
G01X3120185Y389787D02*
X3121334D01*
G01X3121324Y389519D02*
X3120195D01*
G01X3121339Y388000D02*
X3120180D01*
G01X3120190Y387732D02*
X3121329D01*
G01X3120171Y387283D02*
X3121348D01*
G01Y386299D02*
X3120171D01*
G01X3120156Y397604D02*
X3120187Y399193D01*
G01X3120167D02*
X3120154Y398532D01*
G01X3117450Y397691D02*
X3117475Y399193D01*
G01X3117457D02*
X3117448Y398602D01*
G01X3120326Y400078D02*
Y401063D01*
G01X3120134Y398602D02*
X3120124Y399193D01*
G01X3120107D02*
X3120132Y397691D01*
G01X3117428Y398532D02*
X3117416Y399193D01*
G01X3117396D02*
X3117426Y397604D01*
G01X3121315Y401063D02*
X3120204D01*
G01X3121315Y400078D02*
X3120204D01*
G01X3121385Y398602D02*
X3120134D01*
G01X3120154Y398532D02*
X3121365D01*
G01X3121374Y398306D02*
X3120145D01*
G01X3120132Y397691D02*
X3121387D01*
G01X3121363Y397604D02*
X3120156D01*
G01X3121374Y397322D02*
X3120145D01*
G01X3109504Y408937D02*
X3108393D01*
G01X3117378D02*
X3116267D01*
G01X3109504Y407952D02*
X3108393D01*
G01X3117378D02*
X3116267D01*
G01X3116248Y407504D02*
X3117396D01*
G01X3108374D02*
X3109522D01*
G01X3109513Y407236D02*
X3108384D01*
G01X3117387D02*
X3116258D01*
G01X3109528Y405716D02*
X3108369D01*
G01X3117402D02*
X3116243D01*
G01X3116253Y405449D02*
X3117392D01*
G01X3108379D02*
X3109518D01*
G01X3105600Y405000D02*
X3104423D01*
G01X3109537D02*
X3108360D01*
G01X3113474D02*
X3112297D01*
G01X3117411D02*
X3116234D01*
G01X3105600Y404015D02*
X3104423D01*
G01X3109537D02*
X3108360D01*
G01X3113474D02*
X3112297D01*
G01X3117411D02*
X3116234D01*
G01X3105581Y403567D02*
X3104442D01*
G01X3113455D02*
X3112316D01*
G01X3112306Y403299D02*
X3113465D01*
G01X3104432D02*
X3105591D01*
G01X3116258Y407236D02*
X3116253Y405449D01*
G01X3116243Y405716D02*
X3116248Y407504D01*
G01X3113465Y403299D02*
X3113459Y401512D01*
G01X3113450Y401779D02*
X3113455Y403567D01*
G01X3116389Y407952D02*
Y408937D01*
G01X3116234Y405000D02*
Y404015D01*
G01X3116035Y415728D02*
Y410118D01*
G01X3113474Y405000D02*
Y404015D01*
G01X3112297D02*
Y405000D01*
G01X3109537Y404015D02*
Y405000D01*
G01X3109382Y408937D02*
Y407952D01*
G01X3112316Y403567D02*
X3112321Y401779D01*
G01X3112311Y401512D02*
X3112306Y403299D01*
G01X3112321Y401779D02*
X3113450D01*
G01X3104447D02*
X3105576D01*
G01X3105585Y401512D02*
X3104437D01*
G01X3113459D02*
X3112311D01*
G01X3108384Y407236D02*
X3108379Y405449D01*
G01X3108369Y405716D02*
X3108374Y407504D01*
G01X3105591Y403299D02*
X3105585Y401512D01*
G01X3105576Y401779D02*
X3105581Y403567D01*
G01X3108515Y407952D02*
Y408937D01*
G01X3108360Y405000D02*
Y404015D01*
G01X3105600Y405000D02*
Y404015D01*
G01X3104423D02*
Y405000D01*
G01X3109522Y407504D02*
X3109528Y405716D01*
G01X3109518Y405449D02*
X3109513Y407236D01*
G01X3104442Y403567D02*
X3104447Y401779D01*
G01X3104437Y401512D02*
X3104432Y403299D01*
G01X3121348Y405000D02*
X3120171D01*
G01X3121348Y404015D02*
X3120171D01*
G01X3121329Y403567D02*
X3120190D01*
G01X3120180Y403299D02*
X3121339D01*
G01X3120171Y405000D02*
Y404015D01*
G01X3117411D02*
Y405000D01*
G01X3117256Y408937D02*
Y407952D01*
G01X3120190Y403567D02*
X3120195Y401779D01*
G01X3120185Y401512D02*
X3120180Y403299D01*
G01X3117396Y407504D02*
X3117402Y405716D01*
G01X3117392Y405449D02*
X3117387Y407236D01*
G01X3120195Y401779D02*
X3121324D01*
G01X3121333Y401512D02*
X3120185D01*
G01X3115700Y457815D02*
X3114224D01*
G01X3115700Y463343D02*
Y457815D01*
G01X3114224D02*
Y469626D01*
G01X3115700Y464851D02*
X3122590D01*
G01Y463343D02*
X3115700D01*
G01Y469626D02*
Y464851D01*
G01X3114224Y469626D02*
X3115700D01*
G01X3108555Y1094074D02*
X3105799D01*
G01X3112492D02*
X3109736D01*
G01X3116429D02*
X3113673D01*
G01X3116429Y1110610D02*
Y1094074D01*
G01X3113673D02*
Y1110610D01*
G01X3112492D02*
Y1094074D01*
G01X3109736D02*
Y1110610D01*
G01X3108555D02*
Y1094074D01*
G01X3105799D02*
Y1110610D01*
G01X3104618D02*
Y1094074D01*
G01X3120366D02*
X3117610D01*
G01X3120366Y1110610D02*
Y1094074D01*
G01X3117610D02*
Y1110610D01*
G01X3113673D02*
X3116429D01*
G01X3105799D02*
X3108555D01*
G01X3109736D02*
X3112492D01*
G01X3118497Y1122950D02*
X3116596D01*
G01Y1121519D02*
X3118497D01*
G01X3116596Y1120906D02*
X3118497D01*
G01Y1119373D02*
X3116596D01*
G01X3118397Y1118759D02*
X3115996D01*
G01X3116596Y1119373D02*
Y1120906D01*
G01Y1122950D02*
Y1121519D01*
G01X3115996Y1118759D02*
Y1123563D01*
G01X3117610Y1110610D02*
X3120366D01*
G01X3121547Y1114153D02*
X3119578Y1116122D01*
G01X3118397Y1123563D02*
X3118898Y1123461D01*
G01Y1118862D02*
X3118397Y1118759D01*
G01X3118798Y1122847D02*
X3118497Y1122950D01*
G01Y1120906D02*
X3118798Y1120804D01*
G01X3119098Y1121212D02*
X3119298Y1121110D01*
G01X3118898Y1123461D02*
X3119298Y1123154D01*
G01X3118998Y1122643D02*
X3118798Y1122847D01*
G01Y1120804D02*
X3118998Y1120599D01*
G01X3119298Y1123154D02*
X3119598Y1122745D01*
G01X3119298Y1121110D02*
X3119598Y1120701D01*
G01Y1122745D02*
X3119698Y1122439D01*
G01X3119098Y1122336D02*
X3118998Y1122643D01*
G01X3119598Y1120701D02*
X3119698Y1120394D01*
G01X3118998Y1120599D02*
X3119098Y1120293D01*
G01X3119698Y1120394D02*
Y1119883D01*
G01Y1122439D02*
Y1122030D01*
G01X3119098Y1122132D02*
Y1122336D01*
G01Y1120293D02*
Y1119986D01*
G01X3119698Y1119883D02*
X3119598Y1119577D01*
G01X3119098Y1119986D02*
X3118998Y1119679D01*
G01X3119698Y1122030D02*
X3119598Y1121723D01*
G01X3118998Y1121825D02*
X3119098Y1122132D01*
G01X3119598Y1119577D02*
X3119298Y1119168D01*
G01X3119598Y1121723D02*
X3119298Y1121315D01*
G01Y1119168D02*
X3118898Y1118862D01*
G01X3118998Y1119679D02*
X3118798Y1119475D01*
G01Y1121621D02*
X3118998Y1121825D01*
G01X3118798Y1119475D02*
X3118497Y1119373D01*
G01Y1121519D02*
X3118798Y1121621D01*
G01X3119298Y1121315D02*
X3119098Y1121212D01*
G01X3115996Y1123563D02*
X3118397D01*
G01X3127890Y-1837784D02*
Y-1856796D01*
G01X3129775Y-999726D02*
X3129992Y-997850D01*
X3130317Y-996262D01*
X3130750Y-994818D01*
X3131291Y-993230D01*
X3132157Y-991065D01*
X3127827D01*
G01X3138653Y-1000015D02*
X3138436Y-999870D01*
Y-999582D01*
X3138653Y-999437D01*
X3138870Y-999582D01*
Y-999870D01*
X3138653Y-1000015D01*
G01X3147314Y-991065D02*
X3146448Y-991354D01*
X3145798Y-992075D01*
X3145365Y-992941D01*
X3145040Y-994096D01*
X3144932Y-995396D01*
X3145040Y-996695D01*
X3145365Y-997850D01*
X3145798Y-998716D01*
X3146448Y-999437D01*
X3147314Y-999726D01*
X3148180Y-999437D01*
X3148830Y-998716D01*
X3149263Y-997850D01*
X3149588Y-996695D01*
X3149696Y-995396D01*
X3149588Y-994096D01*
X3149263Y-992941D01*
X3148830Y-992075D01*
X3148180Y-991354D01*
X3147314Y-991065D01*
G01X3155975D02*
X3155109Y-991354D01*
X3154459Y-992075D01*
X3154026Y-992941D01*
X3153701Y-994096D01*
X3153593Y-995396D01*
X3153701Y-996695D01*
X3154026Y-997850D01*
X3154459Y-998716D01*
X3155109Y-999437D01*
X3155975Y-999726D01*
X3156841Y-999437D01*
X3157491Y-998716D01*
X3157924Y-997850D01*
X3158249Y-996695D01*
X3158357Y-995396D01*
X3158249Y-994096D01*
X3157924Y-992941D01*
X3157491Y-992075D01*
X3156841Y-991354D01*
X3155975Y-991065D01*
G01X3125179Y-979209D02*
X3125829Y-980219D01*
X3126695Y-980797D01*
X3127669Y-980941D01*
X3128535Y-980797D01*
X3129402Y-980075D01*
X3129943Y-979209D01*
X3130051Y-978343D01*
X3129835Y-977332D01*
X3129077Y-976611D01*
X3128319Y-976322D01*
X3127344D01*
G01X3128319D02*
X3128968Y-975889D01*
X3129510Y-975167D01*
X3129726Y-974301D01*
X3129510Y-973435D01*
X3128968Y-972713D01*
X3127994Y-972280D01*
X3127020Y-972424D01*
X3126045Y-973002D01*
G01X3136222Y-981230D02*
X3136005Y-981085D01*
Y-980797D01*
X3136222Y-980652D01*
X3136439Y-980797D01*
Y-981085D01*
X3136222Y-981230D01*
G01X3142501Y-979642D02*
X3143151Y-980364D01*
X3143909Y-980797D01*
X3144883Y-980941D01*
X3145857Y-980652D01*
X3146615Y-980075D01*
X3147157Y-979065D01*
X3147265Y-977910D01*
X3147048Y-976755D01*
X3146507Y-976033D01*
X3145749Y-975456D01*
X3144991Y-975311D01*
X3144233Y-975456D01*
X3143259Y-976033D01*
X3143584Y-972280D01*
X3146507D01*
G01X3153544D02*
X3152678Y-972569D01*
X3152028Y-973290D01*
X3151595Y-974156D01*
X3151270Y-975311D01*
X3151162Y-976611D01*
X3151270Y-977910D01*
X3151595Y-979065D01*
X3152028Y-979931D01*
X3152678Y-980652D01*
X3153544Y-980941D01*
X3154410Y-980652D01*
X3155060Y-979931D01*
X3155493Y-979065D01*
X3155818Y-977910D01*
X3155926Y-976611D01*
X3155818Y-975311D01*
X3155493Y-974156D01*
X3155060Y-973290D01*
X3154410Y-972569D01*
X3153544Y-972280D01*
G01X3125860Y-682988D02*
X3122050D01*
G01X3125860Y-679097D02*
Y-682988D01*
G01X3122050D02*
Y-679097D01*
G01D02*
X3125860D01*
G01X3136527Y-679875D02*
X3140337Y-682210D01*
G01X3134242Y-676763D02*
X3136527Y-679875D01*
G01Y-672093D02*
X3137290Y-674428D01*
G01X3132718Y-672872D02*
X3134242Y-676763D01*
G01X3131956Y-667424D02*
X3132718Y-672872D01*
G01X3136527Y-669759D02*
Y-672093D01*
G01X3137290Y-667424D02*
X3136527Y-669759D01*
G01X3131956Y-661977D02*
Y-667424D01*
G01X3135766Y-663533D02*
Y-661977D01*
G01D02*
X3136527Y-657308D01*
G01X3132718Y-656529D02*
X3131956Y-661977D01*
G01X3140337Y-660420D02*
X3135766Y-663533D01*
G01X3136527Y-657308D02*
X3137290Y-654973D01*
G01X3136527Y-649526D02*
X3134242Y-652639D01*
G01D02*
X3132718Y-656529D01*
G01X3140337Y-647191D02*
X3136527Y-649526D01*
G01X3121006Y88996D02*
Y88927D01*
G01X3132039Y86830D02*
X3130661Y85452D01*
G01X3123230Y85846D02*
X3122836Y85452D01*
G01X3121006Y85846D02*
X3120612Y85452D01*
G01X3132039Y129153D02*
Y86830D01*
G01X3131448Y85413D02*
Y84626D01*
G01X3130661Y85413D02*
Y84626D01*
G01X3129874Y85413D02*
Y84626D01*
G01X3128397Y85452D02*
Y107106D01*
G01X3128289Y85767D02*
Y85452D01*
G01X3128210Y109074D02*
Y85846D01*
G01X3126714Y91752D02*
Y85452D01*
G01X3125986Y92145D02*
Y85846D01*
G01X3123565Y86567D02*
Y99064D01*
G01X3123230Y85846D02*
Y107106D01*
G01X3121006Y85846D02*
Y109074D01*
G01X3120819Y86240D02*
Y129153D01*
G01X3120622Y85413D02*
Y84626D01*
G01X3128604Y85452D02*
X3128210Y85846D01*
G01X3125986D02*
X3126380Y85452D01*
G01X3123230Y88996D02*
X3121006D01*
G01Y88923D02*
X3123230D01*
G01X3121006Y88338D02*
X3123565D01*
G01X3121006Y88011D02*
X3123230D01*
G01X3123565Y87846D02*
X3121006D01*
G01Y87815D02*
X3123230D01*
G01X3123565Y87452D02*
X3121006D01*
G01X3123565Y87354D02*
X3121006D01*
G01X3128397Y86830D02*
X3136468D01*
G01X3123565Y86567D02*
X3121006D01*
G01Y85846D02*
X3128210D01*
G01X3135385Y86594D02*
G03X3134598Y85807I0J-787D01*
G01X3136468Y85452D02*
Y92539D01*
G01X3134598Y85807D02*
Y84626D01*
G01X3133811Y85413D02*
Y84626D01*
G01X3153496Y86594D02*
X3135385D01*
G01X3131204Y95043D02*
X3131212Y94903D01*
G01X3133653D02*
X3133647Y95043D01*
G01D02*
X3133653Y94979D01*
G01X3129637Y94903D02*
X3129629Y95043D01*
G01X3131212Y94979D02*
X3131204Y95043D01*
G01X3129629D02*
X3129637Y94979D01*
G01X3127305Y94901D02*
G03Y93326I0J-787D01*
G01X3126714Y91752D02*
G03X3123565I-1574J0D01*
G01X3120754Y95165D02*
G03X3120577Y97194I-3877J684D01*
G01X3121530Y95028D02*
G03X3121317Y97464I-4653J820D01*
G01X3133653Y92484D02*
Y120985D01*
G01X3133220Y89980D02*
Y110059D01*
G01X3131567Y89980D02*
Y110059D01*
G01X3131212Y92484D02*
Y120985D01*
G01X3129637Y92484D02*
Y120985D01*
G01X3129204Y89980D02*
Y110059D01*
G01X3128289Y98670D02*
Y101713D01*
G01X3126320Y108287D02*
Y98641D01*
G01X3133300Y100655D02*
X3133647Y95043D01*
G01X3130720Y100655D02*
X3131204Y95043D01*
G01X3129204Y99966D02*
X3129629Y95043D01*
G01X3128289Y99064D02*
X3123565D01*
G01Y98670D02*
X3128289D01*
G01X3128210Y98641D02*
X3126320D01*
G01X3131212Y97483D02*
X3129637D01*
G01X3135228D02*
X3133653D01*
G01X3131212Y96989D02*
X3129637D01*
G01X3135228D02*
X3133653D01*
G01Y96778D02*
X3135228D01*
G01X3129637D02*
X3131212D01*
G01X3133647Y95043D02*
X3135228D01*
G01X3129629D02*
X3131212D01*
G01X3128210Y94901D02*
X3127305D01*
G01X3133653Y94838D02*
X3135228D01*
G01X3129637D02*
X3131212D01*
G01X3133653Y93862D02*
X3135228D01*
G01X3129637D02*
X3131212D01*
G01X3128210Y93326D02*
X3127305D01*
G01X3136468Y92539D02*
X3132039D01*
G01X3133653Y92484D02*
X3135228D01*
G01X3129637D02*
X3131212D01*
G01X3129204Y92342D02*
X3131567D01*
G01X3133220D02*
X3135582D01*
G01X3125986Y92145D02*
X3123230D01*
G01X3125986Y91752D02*
X3123230D01*
G01X3131567Y89980D02*
X3129204D01*
G01X3135582D02*
X3133220D01*
G01X3133300Y100655D02*
X3133291Y100861D01*
G01X3133264Y101446D02*
X3133291Y100861D01*
G01X3130707D02*
X3130720Y100655D01*
G01X3130228Y106120D02*
G03X3130279Y105329I246296J15483D01*
G01X3128654Y106120D02*
G03X3128704Y105329I250807J15457D01*
G01X3132947Y106120D02*
G03X3132983Y105330I348828J15500D01*
G01X3130720Y100655D02*
G03X3130669Y101020I-51395J-6995D01*
G01X3133300Y100655D02*
G03X3133263Y101020I-77747J-7697D01*
G01X3130707Y100861D02*
G03X3130669Y101446I-260547J-16631D01*
G01X3133264D02*
Y101020D01*
G01X3132983Y105736D02*
Y105329D01*
G01X3130669Y101020D02*
Y101446D01*
G01X3130279Y105329D02*
Y105755D01*
G01X3128704Y105736D02*
Y105329D01*
G01X3133100Y103759D02*
X3132983Y105736D01*
G01X3132663Y104350D02*
X3130902Y133484D01*
G01X3130508D02*
X3132269Y104350D01*
G01X3133220Y102114D02*
X3133264Y101446D01*
G01X3133220Y101688D02*
X3133264Y101020D01*
G01X3132983Y105329D02*
X3133085Y103759D01*
G01X3128866D02*
X3128704Y105736D01*
G01X3131182Y104350D02*
X3128717Y133484D01*
G01X3128322D02*
X3130787Y104350D01*
G01X3125959Y133484D02*
X3128425Y104350D01*
G01X3128030D02*
X3125564Y133484D01*
G01X3130669Y101446D02*
X3130279Y105755D01*
G01X3130669Y101020D02*
X3130279Y105329D01*
G01X3128704D02*
X3128846Y103759D01*
G01X3130279Y105329D02*
X3128704D01*
G01X3134558D02*
X3132983D01*
G01X3156842Y104547D02*
X3132039D01*
G01X3133220Y103759D02*
X3131567D01*
G01X3128289Y101713D02*
X3121006D01*
G01X3134839Y101446D02*
X3133264D01*
G01X3130669D02*
X3129204D01*
G01X3121006Y101319D02*
X3128289D01*
G01X3134839Y101020D02*
X3133264D01*
G01X3130669D02*
X3129204D01*
G01X3133291Y100861D02*
X3134865D01*
G01X3129204D02*
X3130707D01*
G01X3133300Y100655D02*
X3134875D01*
G01X3129204D02*
X3130720D01*
G01X3133265Y133484D02*
X3135026Y104350D01*
G01X3135420D02*
X3133659Y133484D01*
G01X3135228Y94979D02*
X3135222Y95043D01*
G01D02*
X3135228Y94903D01*
G01X3134974Y97894D02*
X3134975Y99167D01*
G01X3135582Y89980D02*
Y110059D01*
G01X3135228Y92484D02*
Y120985D01*
G01X3134875Y100655D02*
X3135222Y95043D01*
G01X3134865Y100861D02*
X3134839Y101446D01*
G01X3134865Y100861D02*
X3134875Y100655D01*
G01X3134522Y106120D02*
G03X3134558Y105329I342609J15197D01*
G01X3134875Y100655D02*
G03X3134839Y101020I-70967J-6815D01*
G01X3134741Y103189D02*
Y102820D01*
G01X3134839Y101020D02*
Y101446D01*
G01X3134558Y105329D02*
Y105755D01*
G01X3135451Y133484D02*
X3136508Y104350D01*
G01X3134841Y100656D02*
X3134840Y100684D01*
G01X3134839Y101446D02*
X3134558Y105755D01*
G01X3134839Y101020D02*
X3134558Y105329D01*
G01X3137236Y103759D02*
X3135582D01*
G01X3130228Y106120D02*
G03X3130279Y105755I48026J6524D01*
G01X3121793Y109074D02*
G03X3121006Y108287I0J-787D01*
G01X3126320D02*
G03X3125533Y109074I-787J0D01*
G01X3131164Y134960D02*
X3132947Y106120D01*
G01X3127743Y134960D02*
X3130228Y106120D01*
G01X3126168Y134960D02*
X3128654Y106120D01*
G01X3131567Y110059D02*
X3129204D01*
G01X3135582D02*
X3133220D01*
G01X3128210Y109074D02*
X3121006D01*
G01X3128397Y107106D02*
X3120819D01*
G01X3132947Y106120D02*
X3134522D01*
G01X3128654D02*
X3130228D01*
G01X3134558Y105755D02*
X3133220D01*
G01X3130279D02*
X3129204D01*
G01X3133850Y120859D02*
X3133653Y120491D01*
G01X3133850Y121353D02*
X3133653Y120985D01*
G01X3129834Y120859D02*
X3129637Y120491D01*
G01X3129834Y121353D02*
X3129637Y120985D01*
G01X3131015Y120859D02*
Y128520D01*
G01X3129834D02*
Y120859D01*
G01X3126724Y121279D02*
Y125216D01*
G01X3132739Y134960D02*
X3134522Y106120D01*
G01X3131212Y120985D02*
X3131015Y121353D01*
G01X3131212Y120491D02*
X3131015Y120859D01*
G01X3126724Y121279D02*
X3120819D01*
G01X3132039Y119311D02*
X3120819D01*
G01X3134522Y106120D02*
G03X3134558Y105755I66313J6356D01*
G01X3136902Y104350D02*
X3135845Y133484D01*
G01X3136160Y134960D02*
X3137241Y106120D01*
G01X3135031Y120859D02*
Y128520D01*
G01X3133850D02*
Y120859D01*
G01X3135228Y120985D02*
X3135031Y121353D01*
G01X3135228Y120491D02*
X3135031Y120859D01*
G01X3122995Y132548D02*
G03X3127895I2450J4086D01*
G01X3131980Y136633D02*
X3125445Y130098D01*
G01X3130031Y128761D02*
X3129834Y128026D01*
G01X3130031Y129255D02*
X3129834Y128520D01*
G01X3133220Y131909D02*
Y125216D01*
G01X3133122Y131909D02*
Y138479D01*
G01X3131567Y131909D02*
Y125216D01*
G01X3130819Y129255D02*
Y128761D01*
G01X3130031Y129255D02*
Y128761D01*
G01X3129204Y131909D02*
Y125216D01*
G01X3128122Y131909D02*
Y137421D01*
G01X3121206Y132374D02*
Y137821D01*
G01X3131015Y128520D02*
X3130819Y129255D01*
G01X3131015Y128026D02*
X3130819Y128761D01*
G01X3168063Y132696D02*
X3121206D01*
G01X3130031Y129255D02*
X3130819D01*
G01X3120819Y129153D02*
X3168063D01*
G01X3130819Y128761D02*
X3130031D01*
G01X3133220Y128484D02*
X3131567D01*
G01X3168063Y125216D02*
X3120819D01*
G01X3126724Y124232D02*
X3120819D01*
G01X3131153Y135203D02*
X3131164Y134960D01*
G01X3132739D02*
X3132728Y135203D01*
G01X3131153Y135061D02*
X3131164Y134960D01*
G01X3132739D02*
X3132728Y135061D01*
G01X3126153D02*
X3126168Y134960D01*
G01X3127743D02*
X3127728Y135061D01*
G01X3126153Y135203D02*
X3126168Y134960D01*
G01X3127743D02*
X3127728Y135203D01*
G01X3121359Y139083D02*
G03Y134183I4086J-2450D01*
G01X3129530D02*
G03Y139083I-4085J2450D01*
G01X3133279Y137421D02*
X3133908Y138208D01*
G01X3128279Y137421D02*
X3128908Y138208D01*
G01X3133515Y138479D02*
Y137101D01*
G01X3133463D02*
Y138479D01*
G01X3133417D02*
Y137101D01*
G01X3133391Y138479D02*
Y137101D01*
G01X3133319Y137322D02*
Y148897D01*
G01X3133279Y135846D02*
Y137421D01*
G01X3133174Y137101D02*
Y138479D01*
G01X3133148D02*
Y137101D01*
G01X3132728Y137322D02*
Y135061D01*
G01X3132334Y135944D02*
Y137322D01*
G01X3132137Y138479D02*
Y137101D01*
G01X3132112D02*
Y138479D01*
G01X3132085D02*
Y137101D01*
G01X3131941Y137322D02*
Y148897D01*
G01X3131868Y137101D02*
Y138479D01*
G01X3131842D02*
Y137101D01*
G01X3131796Y138479D02*
Y137101D01*
G01X3131744Y138479D02*
Y137101D01*
G01X3131547Y137322D02*
Y135944D01*
G01X3131153Y138479D02*
Y135061D01*
G01X3130759Y137421D02*
Y133484D01*
G01X3130602Y137421D02*
Y135846D01*
G01X3129973D02*
Y138208D01*
G01X3129972Y134665D02*
Y135846D01*
G01X3129382Y137322D02*
Y138479D01*
G01X3128909Y135846D02*
Y134665D01*
G01X3128908Y138208D02*
Y135846D01*
G01X3128791Y138479D02*
Y137101D01*
G01X3128738D02*
Y138479D01*
G01X3128693D02*
Y137101D01*
G01X3128667Y138479D02*
Y137101D01*
G01X3128594Y137322D02*
Y148897D01*
G01X3128450Y137101D02*
Y138479D01*
G01X3128423D02*
Y137101D01*
G01X3128397Y138479D02*
Y137101D01*
G01X3128279Y135846D02*
Y137421D01*
G01X3127728Y137322D02*
Y135061D01*
G01X3127413Y138479D02*
Y137101D01*
G01X3127387D02*
Y138479D01*
G01X3127360D02*
Y137101D01*
G01X3127334Y135944D02*
Y137322D01*
G01X3127216D02*
Y148897D01*
G01X3127144Y137101D02*
Y138479D01*
G01X3127118D02*
Y137101D01*
G01X3127072Y138479D02*
Y137101D01*
G01X3127019Y138479D02*
Y137101D01*
G01X3126547Y137322D02*
Y135944D01*
G01X3126429Y138479D02*
Y137322D01*
G01X3126153D02*
Y135061D01*
G01X3125759Y137421D02*
Y133484D01*
G01X3125602Y137421D02*
Y135846D01*
G01X3124973D02*
Y138208D01*
G01X3124972Y134665D02*
Y135846D01*
G01X3124952Y133484D02*
Y134665D01*
G01X3124657Y137322D02*
Y138479D01*
G01X3124480Y137322D02*
Y135944D01*
G01X3124067Y138479D02*
Y137101D01*
G01X3124014D02*
Y138479D01*
G01X3123968Y138602D02*
Y134665D01*
G01X3123943Y138479D02*
Y137101D01*
G01X3123870D02*
Y148897D01*
G01X3123726Y137101D02*
Y138479D01*
G01X3123699D02*
Y137101D01*
G01X3123673Y138479D02*
Y137101D01*
G01X3122689Y138479D02*
Y137101D01*
G01X3122663D02*
Y138479D01*
G01X3122636D02*
Y137101D01*
G01X3122492D02*
Y148897D01*
G01X3122419Y137101D02*
Y138479D01*
G01X3122393D02*
Y137101D01*
G01X3122348Y138479D02*
Y137101D01*
G01X3122295Y138479D02*
Y137101D01*
G01X3121704Y138479D02*
Y137101D01*
G01X3129973Y138208D02*
X3130602Y137421D01*
G01X3124973Y138208D02*
X3125602Y137421D01*
G01X3125445Y143169D02*
X3131980Y136633D01*
G01X3124657Y138479D02*
X3121704D01*
G01X3129382D02*
X3126429D01*
G01X3134106D02*
X3131153D01*
G01X3129973Y138208D02*
X3133908D01*
G01X3124973D02*
X3128908D01*
G01X3130602Y137421D02*
X3133279D01*
G01X3125602D02*
X3128279D01*
G01X3164480Y137322D02*
X3124480D01*
G01X3121704Y137101D02*
X3124480D01*
G01X3128791D02*
X3127019D01*
G01X3133515D02*
X3131744D01*
G01X3164480Y135944D02*
X3124480D01*
G01X3128903Y135846D02*
X3124978D01*
G01X3133903D02*
X3129978D01*
G01X3131164Y134960D02*
X3132739D01*
G01X3126168D02*
X3127743D01*
G01X3164913Y134665D02*
X3123968D01*
G01X3130902Y133484D02*
X3128322D01*
G01X3125959D02*
X3124952D01*
G01X3135845D02*
X3133265D01*
G01X3134047Y128761D02*
X3133850Y128026D01*
G01X3134047Y129255D02*
X3133850Y128520D01*
G01X3135582Y131909D02*
Y125216D01*
G01X3134834Y129255D02*
Y128761D01*
G01X3134047Y129255D02*
Y128761D01*
G01X3135031Y128520D02*
X3134834Y129255D01*
G01X3135031Y128026D02*
X3134834Y128761D01*
G01X3134047Y129255D02*
X3134834D01*
G01Y128761D02*
X3134047D01*
G01X3137236Y128484D02*
X3135582D01*
G01X3136153Y135203D02*
X3136160Y134960D01*
G01X3136153Y135061D02*
X3136160Y134960D01*
G01X3136809Y138479D02*
Y137101D01*
G01X3136665Y137322D02*
Y148897D01*
G01X3136593Y137101D02*
Y138479D01*
G01X3136567D02*
Y137101D01*
G01X3136547Y137322D02*
Y135944D01*
G01X3136521Y138479D02*
Y137101D01*
G01X3136468Y138479D02*
Y137101D01*
G01X3136153Y137322D02*
Y135061D01*
G01X3135878Y138479D02*
Y137322D01*
G01X3135759Y137421D02*
Y133484D01*
G01X3135602Y137421D02*
Y135846D01*
G01X3134973D02*
Y138208D01*
G01X3134972Y134665D02*
Y135846D01*
G01X3134106Y137322D02*
Y138479D01*
G01X3133909Y135846D02*
Y134665D01*
G01X3133908Y138208D02*
Y135846D01*
G01X3134973Y138208D02*
X3135602Y137421D01*
G01X3138830Y138479D02*
X3135878D01*
G01X3134973Y138208D02*
X3138908D01*
G01X3135602Y137421D02*
X3138279D01*
G01X3138240Y137101D02*
X3136468D01*
G01X3138903Y135846D02*
X3134978D01*
G01X3136160Y134960D02*
X3137735D01*
G01X3127895Y140719D02*
G03X3122995I-2450J-4085D01*
G01X3123870Y148897D02*
X3122492D01*
G01X3128594D02*
X3127216D01*
G01X3133319D02*
X3131941D01*
G01X3123870Y147519D02*
X3122492D01*
G01X3128594D02*
X3127216D01*
G01X3133319D02*
X3131941D01*
G01X3123870Y146535D02*
X3122492D01*
G01X3128594D02*
X3127216D01*
G01X3133319D02*
X3131941D01*
G01X3123870Y139463D02*
X3122492D01*
G01X3128594D02*
X3127216D01*
G01X3133319D02*
X3131941D01*
G01X3138043Y148897D02*
X3136665D01*
G01X3138043Y147519D02*
X3136665D01*
G01X3138043Y146535D02*
X3136665D01*
G01X3138043Y139463D02*
X3136665D01*
G01X3133633Y162618D02*
G03I-1181J0D01*
G01X3125641D02*
G03I-1181J0D01*
G01X3134606D02*
G03I-2154J0D01*
G01X3126613D02*
G03I-2153J0D01*
G01X3133319Y171304D02*
Y161929D01*
G01X3131547D02*
Y171304D01*
G01X3125326D02*
Y161929D01*
G01X3123555D02*
Y171304D01*
G01X3131547Y164291D02*
X3133319D01*
G01X3123555D02*
X3125326D01*
G01Y163307D02*
X3123555D01*
G01X3133319D02*
X3131547D01*
G01X3125326Y161929D02*
X3123555D01*
G01X3133319D02*
X3131547D01*
G01X3130609Y172618D02*
G03I-2153J0D01*
G01X3133614Y171304D02*
Y169926D01*
G01X3133220Y171304D02*
Y169926D01*
G01X3132925Y171304D02*
Y169926D01*
G01X3131941Y171304D02*
Y169926D01*
G01X3131645D02*
Y171304D01*
G01X3131252Y169926D02*
Y171304D01*
G01X3130759Y169926D02*
Y171304D01*
G01X3126114D02*
Y169926D01*
G01X3125622Y171304D02*
Y169926D01*
G01X3125228Y171304D02*
Y169926D01*
G01X3124933Y171304D02*
Y169926D01*
G01X3123948Y171304D02*
Y169926D01*
G01X3123653D02*
Y171304D01*
G01X3123259Y169926D02*
Y171304D01*
G01X3122767Y169926D02*
Y171304D01*
G01X3126114D02*
X3122767D01*
G01X3134106D02*
X3130759D01*
G01X3126114Y169926D02*
X3122767D01*
G01X3134106D02*
X3130759D01*
G01X3131547Y168941D02*
X3133319D01*
G01X3123555D02*
X3125326D01*
G01X3138602Y172618D02*
G03I-2153J0D01*
G01X3134106Y171304D02*
Y169926D01*
G01X3129637Y172618D02*
G03I-1181J0D01*
G01X3129209Y173586D02*
X3128983Y173398D01*
G01X3129209Y174715D02*
X3128983Y174527D01*
G01X3121217Y173586D02*
X3120991Y173398D01*
G01X3121217Y174715D02*
X3120991Y174527D01*
G01X3130130Y171929D02*
Y173307D01*
G01X3129637D02*
Y171929D01*
G01X3129342Y173307D02*
Y171929D01*
G01X3129244Y174847D02*
Y173650D01*
G01X3129209Y174715D02*
Y173586D01*
G01X3129145Y171929D02*
Y173307D01*
G01X3129047Y173831D02*
Y174959D01*
G01X3128983Y174527D02*
Y173398D01*
G01X3128948Y174463D02*
Y171929D01*
G01X3127964D02*
Y174463D01*
G01X3127930Y173398D02*
Y174527D01*
G01X3127866Y174959D02*
Y173831D01*
G01X3127767Y173307D02*
Y171929D01*
G01X3127704Y173586D02*
Y174715D01*
G01X3127669Y174847D02*
Y173650D01*
G01X3127570Y173307D02*
Y171929D01*
G01X3127275Y173307D02*
Y171929D01*
G01X3126783Y173307D02*
Y171929D01*
G01X3122137D02*
Y173307D01*
G01X3121645D02*
Y171929D01*
G01X3121350Y173307D02*
Y171929D01*
G01X3121252Y174847D02*
Y173650D01*
G01X3121217Y174715D02*
Y173586D01*
G01X3121153Y171929D02*
Y173307D01*
G01X3121055Y173831D02*
Y174959D01*
G01X3120991Y174527D02*
Y173398D01*
G01X3120956Y174463D02*
Y171929D01*
G01X3127930Y174527D02*
X3127704Y174715D01*
G01X3127930Y173398D02*
X3127704Y173586D01*
G01X3127866Y174959D02*
X3129047D01*
G01Y173831D02*
X3127866D01*
G01X3126783Y173307D02*
X3130130D01*
G01X3127964Y172178D02*
X3128948D01*
G01X3126783Y171929D02*
X3130130D01*
G01X3137630Y172618D02*
G03I-1181J0D01*
G01X3135956Y171929D02*
Y174463D01*
G01X3135922Y173398D02*
Y174527D01*
G01X3135858Y174959D02*
Y173831D01*
G01X3135759Y173307D02*
Y171929D01*
G01X3135696Y173586D02*
Y174715D01*
G01X3135661Y174847D02*
Y173650D01*
G01X3135563Y173307D02*
Y171929D01*
G01X3135267Y173307D02*
Y171929D01*
G01X3134775Y173307D02*
Y171929D01*
G01X3135922Y174527D02*
X3135696Y174715D01*
G01X3135922Y173398D02*
X3135696Y173586D01*
G01X3135858Y174959D02*
X3137039D01*
G01Y173831D02*
X3135858D01*
G01X3134775Y173307D02*
X3138122D01*
G01X3135956Y172178D02*
X3136941D01*
G01X3134775Y171929D02*
X3138122D01*
G01X3133150Y385582D02*
X3133145Y383795D01*
G01X3133135Y384063D02*
X3133140Y385850D01*
G01X3125276Y385582D02*
X3125271Y383795D01*
G01X3125261Y384063D02*
X3125266Y385850D01*
G01X3133004Y383346D02*
Y382362D01*
G01X3132137Y383346D02*
Y382362D01*
G01X3125130Y383346D02*
Y382362D01*
G01X3124263Y383346D02*
Y382362D01*
G01X3132001Y385850D02*
X3132006Y384063D01*
G01X3131996Y383795D02*
X3131991Y385582D01*
G01X3124127Y385850D02*
X3124132Y384063D01*
G01X3124122Y383795D02*
X3124117Y385582D01*
G01X3132006Y384063D02*
X3133135D01*
G01X3124132D02*
X3125261D01*
G01X3125271Y383795D02*
X3124122D01*
G01X3133145D02*
X3131996D01*
G01X3125252Y383346D02*
X3124141D01*
G01X3133126D02*
X3132015D01*
G01Y382362D02*
X3133126D01*
G01X3124141D02*
X3125252D01*
G01X3133164Y392106D02*
X3133176Y392767D01*
G01X3133174Y393694D02*
X3133144Y392106D01*
G01X3129227D02*
X3129239Y392767D01*
G01X3129237Y393694D02*
X3129207Y392106D01*
G01X3125290D02*
X3125302Y392767D01*
G01X3125300Y393694D02*
X3125270Y392106D01*
G01X3121353D02*
X3121365Y392767D01*
G01X3121363Y393694D02*
X3121333Y392106D01*
G01X3131935D02*
X3131945Y392697D01*
G01X3131943Y393607D02*
X3131918Y392106D01*
G01X3127998D02*
X3128008Y392697D01*
G01X3128006Y393607D02*
X3127981Y392106D01*
G01X3124061D02*
X3124071Y392697D01*
G01X3124069Y393607D02*
X3124044Y392106D01*
G01X3128069Y389519D02*
X3128064Y387732D01*
G01X3128054Y388000D02*
X3128059Y389787D01*
G01X3133159Y386299D02*
Y387283D01*
G01X3131982D02*
Y386299D01*
G01X3129222Y387283D02*
Y386299D01*
G01X3129067Y391220D02*
Y390236D01*
G01X3128200Y391220D02*
Y390236D01*
G01X3128045Y386299D02*
Y387283D01*
G01X3125285Y386299D02*
Y387283D01*
G01X3124108D02*
Y386299D01*
G01X3121348Y387283D02*
Y386299D01*
G01X3121193Y391220D02*
Y390236D01*
G01X3129208Y389787D02*
X3129213Y388000D01*
G01X3129203Y387732D02*
X3129198Y389519D01*
G01X3121334Y389787D02*
X3121339Y388000D01*
G01X3121329Y387732D02*
X3121324Y389519D01*
G01X3133223Y392106D02*
X3133198Y393607D01*
G01X3133196Y392697D02*
X3133206Y392106D01*
G01X3129286D02*
X3129261Y393607D01*
G01X3129259Y392697D02*
X3129269Y392106D01*
G01X3125349D02*
X3125324Y393607D01*
G01X3125322Y392697D02*
X3125332Y392106D01*
G01X3121412D02*
X3121387Y393607D01*
G01X3121385Y392697D02*
X3121395Y392106D01*
G01X3131998D02*
X3131967Y393694D01*
G01X3131965Y392767D02*
X3131978Y392106D01*
G01X3128061D02*
X3128030Y393694D01*
G01X3128028Y392767D02*
X3128041Y392106D01*
G01X3124124D02*
X3124093Y393694D01*
G01X3124091Y392767D02*
X3124104Y392106D01*
G01X3131956Y393977D02*
X3133185D01*
G01X3128019D02*
X3129248D01*
G01X3124082D02*
X3125311D01*
G01X3131967Y393694D02*
X3133174D01*
G01X3128030D02*
X3129237D01*
G01X3124093D02*
X3125300D01*
G01X3125324Y393607D02*
X3124069D01*
G01X3129261D02*
X3128006D01*
G01X3133198D02*
X3131943D01*
G01X3131956Y392993D02*
X3133185D01*
G01X3128019D02*
X3129248D01*
G01X3124082D02*
X3125311D01*
G01X3125302Y392767D02*
X3124091D01*
G01X3129239D02*
X3128028D01*
G01X3133176D02*
X3131965D01*
G01X3131945Y392697D02*
X3133196D01*
G01X3128008D02*
X3129259D01*
G01X3124071D02*
X3125322D01*
G01X3129189Y391220D02*
X3128078D01*
G01Y390236D02*
X3129189D01*
G01X3128059Y389787D02*
X3129208D01*
G01X3129198Y389519D02*
X3128069D01*
G01X3129213Y388000D02*
X3128054D01*
G01X3128064Y387732D02*
X3129203D01*
G01X3131982Y387283D02*
X3133159D01*
G01X3128045D02*
X3129222D01*
G01X3124108D02*
X3125285D01*
G01Y386299D02*
X3124108D01*
G01X3129222D02*
X3128045D01*
G01X3133159D02*
X3131982D01*
G01X3125266Y385850D02*
X3124127D01*
G01X3133140D02*
X3132001D01*
G01X3131991Y385582D02*
X3133150D01*
G01X3124117D02*
X3125276D01*
G01X3131967Y397604D02*
X3131998Y399193D01*
G01X3131978D02*
X3131965Y398532D01*
G01X3128030Y397604D02*
X3128061Y399193D01*
G01X3128041D02*
X3128028Y398532D01*
G01X3124093Y397604D02*
X3124124Y399193D01*
G01X3124104D02*
X3124091Y398532D01*
G01X3133198Y397691D02*
X3133223Y399193D01*
G01X3133206D02*
X3133196Y398602D01*
G01X3129261Y397691D02*
X3129286Y399193D01*
G01X3129269D02*
X3129259Y398602D01*
G01X3125324Y397691D02*
X3125349Y399193D01*
G01X3125332D02*
X3125322Y398602D01*
G01X3121387Y397691D02*
X3121412Y399193D01*
G01X3121395D02*
X3121385Y398602D01*
G01X3129067Y401063D02*
Y400078D01*
G01X3128200D02*
Y401063D01*
G01X3121193D02*
Y400078D01*
G01X3131945Y398602D02*
X3131935Y399193D01*
G01X3131918D02*
X3131943Y397691D01*
G01X3128008Y398602D02*
X3127998Y399193D01*
G01X3127981D02*
X3128006Y397691D01*
G01X3124071Y398602D02*
X3124061Y399193D01*
G01X3124044D02*
X3124069Y397691D01*
G01X3133176Y398532D02*
X3133164Y399193D01*
G01X3133144D02*
X3133174Y397604D01*
G01X3129239Y398532D02*
X3129227Y399193D01*
G01X3129207D02*
X3129237Y397604D01*
G01X3125302Y398532D02*
X3125290Y399193D01*
G01X3125270D02*
X3125300Y397604D01*
G01X3121365Y398532D02*
X3121353Y399193D01*
G01X3121333D02*
X3121363Y397604D01*
G01X3129189Y401063D02*
X3128078D01*
G01X3129189Y400078D02*
X3128078D01*
G01X3125322Y398602D02*
X3124071D01*
G01X3129259D02*
X3128008D01*
G01X3133196D02*
X3131945D01*
G01X3131965Y398532D02*
X3133176D01*
G01X3128028D02*
X3129239D01*
G01X3124091D02*
X3125302D01*
G01X3125311Y398306D02*
X3124082D01*
G01X3129248D02*
X3128019D01*
G01X3133185D02*
X3131956D01*
G01X3131943Y397691D02*
X3133198D01*
G01X3128006D02*
X3129261D01*
G01X3124069D02*
X3125324D01*
G01X3125300Y397604D02*
X3124093D01*
G01X3129237D02*
X3128030D01*
G01X3133174D02*
X3131967D01*
G01X3125311Y397322D02*
X3124082D01*
G01X3129248D02*
X3128019D01*
G01X3133185D02*
X3131956D01*
G01X3135872Y392106D02*
X3135882Y392697D01*
G01X3135880Y393607D02*
X3135855Y392106D01*
G01X3135943Y389519D02*
X3135938Y387732D01*
G01X3135928Y388000D02*
X3135933Y389787D01*
G01X3136074Y391220D02*
Y390236D01*
G01X3135919Y386299D02*
Y387283D01*
G01X3135935Y392106D02*
X3135904Y393694D01*
G01X3135902Y392767D02*
X3135915Y392106D01*
G01X3135893Y393977D02*
X3137122D01*
G01X3135904Y393694D02*
X3137111D01*
G01X3137135Y393607D02*
X3135880D01*
G01X3135893Y392993D02*
X3137122D01*
G01X3137113Y392767D02*
X3135902D01*
G01X3135882Y392697D02*
X3137133D01*
G01X3137063Y391220D02*
X3135952D01*
G01Y390236D02*
X3137063D01*
G01X3135933Y389787D02*
X3137082D01*
G01X3137072Y389519D02*
X3135943D01*
G01X3137087Y388000D02*
X3135928D01*
G01X3135938Y387732D02*
X3137077D01*
G01X3135919Y387283D02*
X3137096D01*
G01Y386299D02*
X3135919D01*
G01X3135904Y397604D02*
X3135935Y399193D01*
G01X3135915D02*
X3135902Y398532D01*
G01X3136074Y400078D02*
Y401063D01*
G01X3135882Y398602D02*
X3135872Y399193D01*
G01X3135855D02*
X3135880Y397691D01*
G01X3137063Y401063D02*
X3135952D01*
G01X3137063Y400078D02*
X3135952D01*
G01X3137133Y398602D02*
X3135882D01*
G01X3135902Y398532D02*
X3137113D01*
G01X3137122Y398306D02*
X3135893D01*
G01X3135880Y397691D02*
X3137135D01*
G01X3137111Y397604D02*
X3135904D01*
G01X3137122Y397322D02*
X3135893D01*
G01X3125252Y408937D02*
X3124141D01*
G01X3133126D02*
X3132015D01*
G01X3125252Y407952D02*
X3124141D01*
G01X3133126D02*
X3132015D01*
G01X3131996Y407504D02*
X3133145D01*
G01X3124122D02*
X3125270D01*
G01X3125261Y407236D02*
X3124132D01*
G01X3133135D02*
X3132006D01*
G01X3125276Y405716D02*
X3124117D01*
G01X3133150D02*
X3131991D01*
G01X3132001Y405449D02*
X3133140D01*
G01X3124127D02*
X3125266D01*
G01X3125285Y405000D02*
X3124108D01*
G01X3129222D02*
X3128045D01*
G01X3133159D02*
X3131982D01*
G01X3125285Y404015D02*
X3124108D01*
G01X3129222D02*
X3128045D01*
G01X3133159D02*
X3131982D01*
G01X3129203Y403567D02*
X3128064D01*
G01X3128054Y403299D02*
X3129213D01*
G01X3132006Y407236D02*
X3132001Y405449D01*
G01X3131991Y405716D02*
X3131996Y407504D01*
G01X3129213Y403299D02*
X3129207Y401512D01*
G01X3129198Y401779D02*
X3129203Y403567D01*
G01X3124132Y407236D02*
X3124127Y405449D01*
G01X3124117Y405716D02*
X3124122Y407504D01*
G01X3121339Y403299D02*
X3121333Y401512D01*
G01X3121324Y401779D02*
X3121329Y403567D01*
G01X3133159Y404015D02*
Y405000D01*
G01X3133004Y408937D02*
Y407952D01*
G01X3132137D02*
Y408937D01*
G01X3131982Y405000D02*
Y404015D01*
G01X3129222Y405000D02*
Y404015D01*
G01X3128045D02*
Y405000D01*
G01X3125285Y404015D02*
Y405000D01*
G01X3125130Y408937D02*
Y407952D01*
G01X3124263D02*
Y408937D01*
G01X3124108Y405000D02*
Y404015D01*
G01X3121348D02*
Y405000D01*
G01X3121035Y415728D02*
Y410118D01*
G01X3133145Y407504D02*
X3133150Y405716D01*
G01X3133140Y405449D02*
X3133135Y407236D01*
G01X3128064Y403567D02*
X3128069Y401779D01*
G01X3128059Y401512D02*
X3128054Y403299D01*
G01X3125270Y407504D02*
X3125276Y405716D01*
G01X3125266Y405449D02*
X3125261Y407236D01*
G01X3128069Y401779D02*
X3129198D01*
G01X3129207Y401512D02*
X3128059D01*
G01X3136941Y415728D02*
X3121035D01*
G01X3137096Y405000D02*
X3135919D01*
G01X3137096Y404015D02*
X3135919D01*
G01X3137077Y403567D02*
X3135938D01*
G01X3135928Y403299D02*
X3137087D01*
G01X3135919Y404015D02*
Y405000D01*
G01X3135938Y403567D02*
X3135943Y401779D01*
G01X3135933Y401512D02*
X3135928Y403299D01*
G01X3135943Y401779D02*
X3137072D01*
G01X3137082Y401512D02*
X3135933D01*
G01X3124067Y457815D02*
X3122590D01*
G01X3134893D02*
X3133417D01*
G01D02*
Y467615D01*
G01X3124067Y469626D02*
Y457815D01*
G01X3122590D02*
Y463343D01*
G01X3126035Y465856D02*
X3129972D01*
G01Y464851D02*
X3126035D01*
G01X3133417Y467615D02*
X3131941Y465856D01*
G01X3126035Y462841D02*
X3129972D01*
G01Y461835D02*
X3126035D01*
G01X3131941Y465856D02*
Y467867D01*
G01X3129972Y462841D02*
Y461835D01*
G01Y465856D02*
Y464851D01*
G01X3126035Y461835D02*
Y462841D01*
G01Y464851D02*
Y465856D01*
G01X3122590Y464851D02*
Y469626D01*
G01X3134893D02*
Y457815D01*
G01X3133417Y469626D02*
X3134893D01*
G01X3122590D02*
X3124067D01*
G01X3131941Y467867D02*
X3133417Y469626D01*
G01X3121547Y1084626D02*
G03X3125484Y1080689I3937J0D01*
G01X3237689D02*
X3125484D01*
G01X3121547Y1084626D02*
Y1114153D01*
G01X3121700Y1118759D02*
X3121099D01*
G01X3121700Y1123563D02*
Y1118759D01*
G01X3121099D02*
Y1122745D01*
G01X3120499Y1122030D02*
Y1122847D01*
G01X3121099Y1122745D02*
X3120499Y1122030D01*
G01Y1122847D02*
X3121099Y1123563D01*
G01D02*
X3121700D01*
G01X3127890Y1453929D02*
Y1434916D01*
G01X3140337Y-682210D02*
X3144147Y-682988D01*
G01D02*
X3147957D01*
G01D02*
X3151767Y-682210D01*
G01X3141100Y-678319D02*
X3143385Y-679097D01*
G01D02*
X3148719D01*
G01X3138813Y-676763D02*
X3141100Y-678319D01*
G01X3137290Y-674428D02*
X3138813Y-676763D01*
G01Y-665868D02*
X3137290Y-667424D01*
G01X3141100Y-664311D02*
X3138813Y-665868D01*
G01X3151767Y-682210D02*
X3155577Y-679875D01*
G01X3151005Y-678319D02*
X3153291Y-676763D01*
G01X3148719Y-679097D02*
X3151005Y-678319D01*
G01X3148719Y-663533D02*
X3143385D01*
G01D02*
X3141100Y-664311D01*
G01X3143385Y-650304D02*
X3147957D01*
G01Y-659642D02*
X3144147D01*
G01D02*
X3140337Y-660420D01*
G01X3137290Y-654973D02*
X3138813Y-652639D01*
G01X3141100Y-651082D02*
X3143385Y-650304D01*
G01X3138813Y-652639D02*
X3141100Y-651082D01*
G01X3153291Y-665868D02*
X3151005Y-664311D01*
G01X3155577Y-662755D02*
X3151767Y-660420D01*
G01X3151005Y-664311D02*
X3148719Y-663533D01*
G01X3151767Y-660420D02*
X3147957Y-659642D01*
G01X3150243Y-651082D02*
X3152529Y-652639D01*
G01X3147957Y-650304D02*
X3150243Y-651082D01*
G01X3152529Y-652639D02*
X3154053Y-654973D01*
G01X3147195Y-646413D02*
X3144147D01*
G01D02*
X3140337Y-647191D01*
G01X3151005D02*
X3147195Y-646413D01*
G01X3154815Y-649526D02*
X3151005Y-647191D01*
G01X3152413Y85452D02*
Y92539D01*
G01Y86830D02*
X3160484D01*
G01X3149716Y94903D02*
X3149720Y95043D01*
G01D02*
X3149716Y94979D01*
G01X3145700Y94903D02*
X3145702Y95043D01*
G01X3147275Y94979D02*
X3147276Y95043D01*
G01X3145702D02*
X3145700Y94979D01*
G01X3147276Y95043D02*
X3147275Y94903D01*
G01X3141685D02*
X3141683Y95043D01*
G01X3143259Y94979D02*
X3143258Y95043D01*
G01X3141683D02*
X3141685Y94979D01*
G01X3143258Y95043D02*
X3143259Y94903D01*
G01X3137669D02*
X3137665Y95043D01*
G01X3139244Y94979D02*
X3139240Y95043D01*
G01X3137665D02*
X3137669Y94979D01*
G01X3139240Y95043D02*
X3139244Y94903D01*
G01X3149919Y100655D02*
X3149720Y95043D01*
G01X3147339Y100655D02*
X3147276Y95043D01*
G01X3145765Y100655D02*
X3145702Y95043D01*
G01X3149716Y92484D02*
Y120985D01*
G01X3149283Y89980D02*
Y110059D01*
G01X3147630Y89980D02*
Y110059D01*
G01X3147275Y120985D02*
Y92484D01*
G01X3145700D02*
Y120985D01*
G01X3145267Y89980D02*
Y110059D01*
G01X3143614Y89980D02*
Y110059D01*
G01X3143259Y120985D02*
Y92484D01*
G01X3141685D02*
Y120985D01*
G01X3141252Y89980D02*
Y110059D01*
G01X3139598Y89980D02*
Y110059D01*
G01X3139244Y120985D02*
Y92484D01*
G01X3137669D02*
Y120985D01*
G01X3137236Y89980D02*
Y110059D01*
G01X3143184Y100655D02*
X3143258Y95043D01*
G01X3141609Y100655D02*
X3141683Y95043D01*
G01X3139030Y100655D02*
X3139240Y95043D01*
G01X3137455Y100655D02*
X3137665Y95043D01*
G01X3139244Y97483D02*
X3137669D01*
G01X3143259D02*
X3141685D01*
G01X3147275D02*
X3145700D01*
G01X3151291D02*
X3149716D01*
G01X3139244Y96989D02*
X3137669D01*
G01X3143259D02*
X3141685D01*
G01X3147275D02*
X3145700D01*
G01X3151291D02*
X3149716D01*
G01Y96778D02*
X3151291D01*
G01X3145700D02*
X3147275D01*
G01X3141685D02*
X3143259D01*
G01X3137669D02*
X3139244D01*
G01X3149716Y95043D02*
X3151295D01*
G01X3145700D02*
X3147276D01*
G01X3141683D02*
X3143259D01*
G01X3137665D02*
X3139244D01*
G01X3149716Y94838D02*
X3151291D01*
G01X3145700D02*
X3147275D01*
G01X3141685D02*
X3143259D01*
G01X3137669D02*
X3139244D01*
G01X3149716Y93862D02*
X3151291D01*
G01X3145700D02*
X3147275D01*
G01X3141685D02*
X3143259D01*
G01X3137669D02*
X3139244D01*
G01X3149716Y92484D02*
X3151291D01*
G01X3145700D02*
X3147275D01*
G01X3141685D02*
X3143259D01*
G01X3137669D02*
X3139244D01*
G01X3149283Y92342D02*
X3151645D01*
G01X3145267D02*
X3147630D01*
G01X3141252D02*
X3143614D01*
G01X3137236D02*
X3139598D01*
G01Y89980D02*
X3137236D01*
G01X3143614D02*
X3141252D01*
G01X3147630D02*
X3145267D01*
G01X3151645D02*
X3149283D01*
G01X3149919Y100655D02*
X3149925Y100861D01*
G01X3149940Y101446D02*
X3149925Y100861D01*
G01X3145765Y100655D02*
X3145766Y100861D01*
G01X3145771Y101446D02*
X3145766Y100861D01*
G01X3147341D02*
X3147346Y101446D01*
G01X3145822Y105329D02*
X3145828Y106120D01*
G01X3147403D02*
X3147396Y105329D01*
G01X3145771Y101020D02*
X3145765Y100655D01*
G01X3147339D02*
X3147346Y101020D01*
G01X3147341Y100861D02*
X3147339Y100655D01*
G01X3141609D02*
X3141607Y100861D01*
G01X3141602Y101446D02*
X3141607Y100861D01*
G01X3143182D02*
X3143177Y101446D01*
G01X3141543Y105329D02*
X3141535Y106120D01*
G01X3143109D02*
X3143117Y105329D01*
G01X3141602Y101020D02*
X3141609Y100655D01*
G01X3143184D02*
X3143177Y101020D01*
G01X3143182Y100861D02*
X3143184Y100655D01*
G01X3137455D02*
X3137449Y100861D01*
G01X3137433Y101446D02*
X3137449Y100861D01*
G01X3139024D02*
X3139007Y101446D01*
G01X3137263Y105329D02*
X3137241Y106120D01*
G01X3138816D02*
X3138838Y105329D01*
G01X3139024Y100861D02*
X3139030Y100655D01*
G01X3149941Y101020D02*
G03X3149920Y100655I134357J-7913D01*
G01X3139030D02*
G03X3139007Y101020I-116269J-7143D01*
G01X3137455Y100655D02*
G03X3137433Y101020I-127448J-7499D01*
G01X3150101Y105329D02*
X3149940Y101020D01*
G01X3150101Y105755D02*
X3149940Y101446D01*
G01X3150674Y133484D02*
X3149617Y104350D01*
G01X3149223D02*
X3150280Y133484D01*
G01X3148487D02*
X3148135Y104350D01*
G01X3148093Y133484D02*
X3147741Y104350D01*
G01X3145731Y133484D02*
X3145379Y104350D01*
G01X3145337Y133484D02*
X3144985Y104350D01*
G01X3147346Y101020D02*
X3147396Y105329D01*
G01X3147346Y101446D02*
X3147396Y105755D01*
G01X3145822Y105329D02*
X3145771Y101020D01*
G01X3145822Y105755D02*
X3145771Y101446D01*
G01X3149940D02*
Y101020D01*
G01X3147396Y105329D02*
Y105755D01*
G01X3147346Y101020D02*
Y101446D01*
G01X3145822Y105755D02*
Y105329D01*
G01X3145771Y101446D02*
Y101020D01*
G01X3143177D02*
Y101446D01*
G01X3143117Y105329D02*
Y105755D01*
G01X3141602Y101446D02*
Y101020D01*
G01X3141543Y105755D02*
Y105329D01*
G01X3139007Y101020D02*
Y101446D01*
G01X3138838Y105329D02*
Y105755D01*
G01X3137433Y101446D02*
Y101020D01*
G01X3137263Y105755D02*
Y105329D01*
G01X3143544Y133484D02*
X3143896Y104350D01*
G01X3143150Y133484D02*
X3143502Y104350D01*
G01X3141140D02*
X3140788Y133484D01*
G01X3140395D02*
X3140746Y104350D01*
G01X3143177Y101446D02*
X3143117Y105755D01*
G01X3143177Y101020D02*
X3143117Y105329D01*
G01X3141543Y105755D02*
X3141602Y101446D01*
G01X3141543Y105329D02*
X3141602Y101020D01*
G01X3139658Y104350D02*
X3138602Y133484D01*
G01X3138207D02*
X3139264Y104350D01*
G01X3139007Y101446D02*
X3138838Y105755D01*
G01X3139007Y101020D02*
X3138838Y105329D01*
G01X3137263Y105755D02*
X3137433Y101446D01*
G01X3137263Y105329D02*
X3137433Y101020D01*
G01X3138838Y105329D02*
X3137263D01*
G01X3143117D02*
X3141543D01*
G01X3147396D02*
X3145822D01*
G01X3141252Y103759D02*
X3139598D01*
G01X3145267D02*
X3143614D01*
G01X3149283D02*
X3147630D01*
G01X3139007Y101446D02*
X3137433D01*
G01X3143177D02*
X3141602D01*
G01X3147346D02*
X3145771D01*
G01X3151515D02*
X3149940D01*
G01X3139007Y101020D02*
X3137433D01*
G01X3143177D02*
X3141602D01*
G01X3147346D02*
X3145771D01*
G01X3151515D02*
X3149940D01*
G01X3149925Y100861D02*
X3151500D01*
G01X3145766D02*
X3147341D01*
G01X3141607D02*
X3143182D01*
G01X3137449D02*
X3139024D01*
G01X3149919Y100655D02*
X3151494D01*
G01X3145765D02*
X3147339D01*
G01X3141609D02*
X3143184D01*
G01X3137455D02*
X3139030D01*
G01X3151291Y94979D02*
X3151295Y95043D01*
G01D02*
X3151291Y94903D01*
G01X3151494Y100655D02*
X3151295Y95043D01*
G01X3151645Y89980D02*
Y110059D01*
G01X3151291Y120985D02*
Y92484D01*
G01X3156842Y92539D02*
X3152413D01*
G01X3151500Y100861D02*
X3151515Y101446D01*
G01X3150101Y105329D02*
X3150122Y106120D01*
G01X3151697D02*
X3151676Y105329D01*
G01X3151500Y100861D02*
X3151494Y100655D01*
G01X3151515Y101020D02*
G03X3151494Y100655I122589J-7236D01*
G01X3151515Y101020D02*
X3151676Y105329D01*
G01X3151515Y101446D02*
X3151645Y104934D01*
G01X3153430Y133484D02*
X3152374Y104350D01*
G01X3153036Y133484D02*
X3151980Y104350D01*
G01X3151645Y104829D02*
X3151676Y105736D01*
G01Y105329D02*
Y105736D01*
G01X3151515Y101020D02*
Y101446D01*
G01X3150101Y105755D02*
Y105329D01*
G01X3151676D02*
X3150101D01*
G01X3153299Y103759D02*
X3151645D01*
G01X3147403Y106120D02*
X3147396Y105755D01*
G01X3145822D02*
X3145828Y106120D01*
G01X3143109D02*
X3143117Y105755D01*
G01X3141543D02*
X3141535Y106120D01*
G01X3138816D02*
G03X3138837Y105755I108678J6070D01*
G01X3137241Y106120D02*
G03X3137263Y105755I137881J8127D01*
G01X3147726Y134960D02*
X3147403Y106120D01*
G01X3146151Y134960D02*
X3145828Y106120D01*
G01X3142730Y134960D02*
X3143109Y106120D01*
G01X3141156Y134960D02*
X3141535Y106120D01*
G01X3137735Y134960D02*
X3138816Y106120D01*
G01X3139598Y110059D02*
X3137236D01*
G01X3143614D02*
X3141252D01*
G01X3147630D02*
X3145267D01*
G01X3151645D02*
X3149283D01*
G01X3145828Y106120D02*
X3147403D01*
G01X3141535D02*
X3143109D01*
G01X3137241D02*
X3138816D01*
G01X3138838Y105755D02*
X3137263D01*
G01X3143117D02*
X3141543D01*
G01X3147396D02*
X3145822D01*
G01X3149913Y120859D02*
X3149716Y120491D01*
G01X3149913Y121353D02*
X3149716Y120985D01*
G01X3145897Y120859D02*
X3145700Y120491D01*
G01X3145897Y121353D02*
X3145700Y120985D01*
G01X3141882Y120859D02*
X3141685Y120491D01*
G01X3141882Y121353D02*
X3141685Y120985D01*
G01X3137866Y120859D02*
X3137669Y120491D01*
G01X3137866Y121353D02*
X3137669Y120985D01*
G01X3149913Y128520D02*
Y120859D01*
G01X3147078D02*
Y128520D01*
G01X3145897D02*
Y120859D01*
G01X3143063D02*
Y128520D01*
G01X3141882D02*
Y120859D01*
G01X3139047D02*
Y128520D01*
G01X3137866D02*
Y120859D01*
G01X3147275Y120985D02*
X3147078Y121353D01*
G01X3147275Y120491D02*
X3147078Y120859D01*
G01X3143259Y120985D02*
X3143063Y121353D01*
G01X3143259Y120491D02*
X3143063Y120859D01*
G01X3139244Y120985D02*
X3139047Y121353D01*
G01X3139244Y120491D02*
X3139047Y120859D01*
G01X3151697Y106120D02*
G03X3151676Y105736I69602J-3999D01*
G01X3150101Y105755D02*
G03X3150122Y106120I-145358J8546D01*
G01X3152722Y134960D02*
X3151697Y106120D01*
G01X3151147Y134960D02*
X3150122Y106120D01*
G01D02*
X3151697D01*
G01X3151645Y105755D02*
X3150101D01*
G01X3151094Y120859D02*
Y128520D01*
G01X3151291Y120985D02*
X3151094Y121353D01*
G01X3151291Y120491D02*
X3151094Y120859D01*
G01X3150110Y128761D02*
X3149913Y128026D01*
G01X3150110Y129255D02*
X3149913Y128520D01*
G01X3146094Y128761D02*
X3145897Y128026D01*
G01X3146094Y129255D02*
X3145897Y128520D01*
G01X3142078Y128761D02*
X3141882Y128026D01*
G01X3142078Y129255D02*
X3141882Y128520D01*
G01X3138063Y128761D02*
X3137866Y128026D01*
G01X3138063Y129255D02*
X3137866Y128520D01*
G01X3149283Y131909D02*
Y125216D01*
G01X3147630Y131909D02*
Y125216D01*
G01X3146882Y129255D02*
Y128761D01*
G01X3146094Y129255D02*
Y128761D01*
G01X3145759Y137421D02*
Y131909D01*
G01X3145267D02*
Y125216D01*
G01X3143614Y131909D02*
Y125216D01*
G01X3143122Y131909D02*
Y137421D01*
G01X3142866Y129255D02*
Y128761D01*
G01X3142078Y129255D02*
Y128761D01*
G01X3141252Y131909D02*
Y125216D01*
G01X3139598Y131909D02*
Y125216D01*
G01X3138850Y129255D02*
Y128761D01*
G01X3138122Y131909D02*
Y137421D01*
G01X3138063Y129255D02*
Y128761D01*
G01X3137236Y131909D02*
Y125216D01*
G01X3147078Y128520D02*
X3146882Y129255D01*
G01X3147078Y128026D02*
X3146882Y128761D01*
G01X3143063Y128520D02*
X3142866Y129255D01*
G01X3143063Y128026D02*
X3142866Y128761D01*
G01X3139047Y128520D02*
X3138850Y129255D01*
G01X3139047Y128026D02*
X3138850Y128761D01*
G01X3146094Y129255D02*
X3146882D01*
G01X3142078D02*
X3142866D01*
G01X3138063D02*
X3138850D01*
G01Y128761D02*
X3138063D01*
G01X3142866D02*
X3142078D01*
G01X3146882D02*
X3146094D01*
G01X3141252Y128484D02*
X3139598D01*
G01X3145267D02*
X3143614D01*
G01X3149283D02*
X3147630D01*
G01X3146153Y135203D02*
X3146151Y134960D01*
G01X3147726D02*
X3147728Y135203D01*
G01X3141153D02*
X3141156Y134960D01*
G01X3142730D02*
X3142728Y135203D01*
G01X3137735Y134960D02*
X3137728Y135203D01*
G01X3137735Y134960D02*
X3137728Y135061D01*
G01X3141153D02*
X3141156Y134960D01*
G01X3142730D02*
X3142728Y135061D01*
G01X3146153D02*
X3146151Y134960D01*
G01X3147726D02*
X3147728Y135061D01*
G01X3148279Y137421D02*
X3148908Y138208D01*
G01X3143279Y137421D02*
X3143908Y138208D01*
G01X3138279Y137421D02*
X3138908Y138208D01*
G01X3150051Y138479D02*
Y137322D01*
G01X3149973Y135846D02*
Y138208D01*
G01X3149972Y134665D02*
Y135846D01*
G01X3148909D02*
Y134665D01*
G01X3148908Y138208D02*
Y135846D01*
G01X3148279D02*
Y138479D01*
G01X3148122Y133484D02*
Y137421D01*
G01X3147728Y137322D02*
Y135061D01*
G01X3147689Y138479D02*
Y137101D01*
G01X3147636D02*
Y138479D01*
G01X3147590D02*
Y137101D01*
G01X3147565Y138479D02*
Y137101D01*
G01X3147492Y137322D02*
Y148897D01*
G01X3147433Y135944D02*
Y137101D01*
G01X3147348D02*
Y138479D01*
G01X3147334Y135944D02*
Y137322D01*
G01X3147321Y138479D02*
Y137101D01*
G01X3147295Y138479D02*
Y137101D01*
G01X3146547Y137322D02*
Y135944D01*
G01X3146311Y138479D02*
Y137101D01*
G01X3146285D02*
Y138479D01*
G01X3146258D02*
Y137101D01*
G01X3146153Y137322D02*
Y135061D01*
G01X3146114Y137322D02*
Y148897D01*
G01X3146041Y137101D02*
Y138479D01*
G01X3146015D02*
Y137101D01*
G01X3145970Y138479D02*
Y137101D01*
G01X3145917Y138479D02*
Y137101D01*
G01X3145602Y137421D02*
Y135846D01*
G01X3145326Y138479D02*
Y137101D01*
G01X3144973Y135846D02*
Y138208D01*
G01X3144972Y134665D02*
Y135846D01*
G01X3143909D02*
Y134665D01*
G01X3143908Y138208D02*
Y135846D01*
G01X3143555Y137101D02*
Y138479D01*
G01X3143279Y135846D02*
Y137421D01*
G01X3142964Y138479D02*
Y137101D01*
G01X3142911D02*
Y138479D01*
G01X3142866D02*
Y137101D01*
G01X3142840Y138479D02*
Y137101D01*
G01X3142767Y137322D02*
Y148897D01*
G01X3142728Y137322D02*
Y135061D01*
G01X3142623Y137101D02*
Y138479D01*
G01X3142596D02*
Y137101D01*
G01X3142570Y138479D02*
Y137101D01*
G01X3142334Y135944D02*
Y137322D01*
G01X3141586Y138479D02*
Y137101D01*
G01X3141561D02*
Y138479D01*
G01X3141547Y137322D02*
Y135944D01*
G01X3141533Y138479D02*
Y137101D01*
G01X3141527Y135944D02*
Y137101D01*
G01X3141389Y137322D02*
Y148897D01*
G01X3141317Y137101D02*
Y138479D01*
G01X3141291D02*
Y137101D01*
G01X3141245Y138479D02*
Y137101D01*
G01X3141193Y138479D02*
Y137101D01*
G01X3141153Y137322D02*
Y135061D01*
G01X3140759Y137421D02*
Y133484D01*
G01X3140602Y138479D02*
Y135846D01*
G01X3139973D02*
Y138208D01*
G01X3139972Y134665D02*
Y135846D01*
G01X3138909D02*
Y134665D01*
G01X3138908Y138208D02*
Y135846D01*
G01X3138830Y137322D02*
Y138479D01*
G01X3138279Y135846D02*
Y137421D01*
G01X3138240Y138479D02*
Y137101D01*
G01X3138187D02*
Y138479D01*
G01X3138141D02*
Y137101D01*
G01X3138116Y138479D02*
Y137101D01*
G01X3138043Y137322D02*
Y148897D01*
G01X3137899Y137101D02*
Y138479D01*
G01X3137872D02*
Y137101D01*
G01X3137846Y138479D02*
Y137101D01*
G01X3137728Y137322D02*
Y135061D01*
G01X3137334Y135944D02*
Y137322D01*
G01X3136862Y138479D02*
Y137101D01*
G01X3136836D02*
Y138479D01*
G01X3150602Y137421D02*
X3149973Y138208D01*
G01X3144973D02*
X3145602Y137421D01*
G01X3139973Y138208D02*
X3140602Y137421D01*
G01X3143555Y138479D02*
X3140602D01*
G01X3148279D02*
X3145326D01*
G01X3153004D02*
X3150051D01*
G01X3149973Y138208D02*
X3153908D01*
G01X3144973D02*
X3148908D01*
G01X3139973D02*
X3143908D01*
G01X3145602Y137421D02*
X3148279D01*
G01X3140602D02*
X3143279D01*
G01X3143555Y137101D02*
X3141193D01*
G01X3147689D02*
X3145326D01*
G01X3143903Y135846D02*
X3139978D01*
G01X3148903D02*
X3144978D01*
G01X3153903D02*
X3149978D01*
G01X3146151Y134960D02*
X3147726D01*
G01X3141156D02*
X3142730D01*
G01X3140788Y133484D02*
X3138207D01*
G01X3145731D02*
X3143150D01*
G01X3150674D02*
X3148093D01*
G01X3151645Y131909D02*
Y125216D01*
G01X3150897Y129255D02*
Y128761D01*
G01X3150759Y131909D02*
Y137421D01*
G01X3150110Y129255D02*
Y128761D01*
G01X3151094Y128520D02*
X3150897Y129255D01*
G01X3151094Y128026D02*
X3150897Y128761D01*
G01X3150110Y129255D02*
X3150897D01*
G01Y128761D02*
X3150110D01*
G01X3153299Y128484D02*
X3151645D01*
G01X3151153Y135203D02*
X3151147Y134960D01*
G01X3152722D02*
X3152728Y135203D01*
G01X3151153Y135061D02*
X3151147Y134960D01*
G01X3152722D02*
X3152728Y135061D01*
G01X3153122Y133484D02*
Y137421D01*
G01X3153004Y137322D02*
Y138479D01*
G01X3152728Y135061D02*
Y137322D01*
G01X3152413Y138479D02*
Y137101D01*
G01X3152360D02*
Y138479D01*
G01X3152334Y135944D02*
Y137322D01*
G01X3152315Y138479D02*
Y137101D01*
G01X3152289Y138479D02*
Y137101D01*
G01X3152216Y137322D02*
Y148897D01*
G01X3152072Y137101D02*
Y138479D01*
G01X3152045D02*
Y137101D01*
G01X3152019Y138479D02*
Y137101D01*
G01X3151547Y137322D02*
Y135944D01*
G01X3151153Y135061D02*
Y137322D01*
G01X3151035Y138479D02*
Y137101D01*
G01X3151009D02*
Y138479D01*
G01X3150982D02*
Y137101D01*
G01X3150838Y137322D02*
Y148897D01*
G01X3150766Y137101D02*
Y138479D01*
G01X3150740D02*
Y137101D01*
G01X3150694Y138479D02*
Y137101D01*
G01X3150641Y138479D02*
Y137101D01*
G01X3150602Y137421D02*
Y135846D01*
G01X3153279Y137421D02*
X3150602D01*
G01X3152413Y137101D02*
X3150641D01*
G01X3151147Y134960D02*
X3152722D01*
G01X3155617Y133484D02*
X3153036D01*
G01X3142767Y148897D02*
X3141389D01*
G01X3147492D02*
X3146114D01*
G01X3142767Y147519D02*
X3141389D01*
G01X3147492D02*
X3146114D01*
G01X3142767Y146535D02*
X3141389D01*
G01X3147492D02*
X3146114D01*
G01X3142767Y139463D02*
X3141389D01*
G01X3147492D02*
X3146114D01*
G01X3152216Y148897D02*
X3150838D01*
G01X3152216Y147519D02*
X3150838D01*
G01X3152216Y146535D02*
X3150838D01*
G01X3152216Y139463D02*
X3150838D01*
G01X3149618Y162618D02*
G03I-1181J0D01*
G01X3150590D02*
G03I-2153J0D01*
G01X3141626D02*
G03I-1181J0D01*
G01X3142598D02*
G03I-2153J0D01*
G01X3149303Y171304D02*
Y161929D01*
G01X3147531D02*
Y171304D01*
G01X3141311D02*
Y161929D01*
G01X3139539D02*
Y171304D01*
G01X3147531Y164291D02*
X3149303D01*
G01X3139539D02*
X3141311D01*
G01Y163307D02*
X3139539D01*
G01X3149303D02*
X3147531D01*
G01X3141311Y161929D02*
X3139539D01*
G01X3149303D02*
X3147531D01*
G01X3149598Y171304D02*
Y169926D01*
G01X3149204Y171304D02*
Y169926D01*
G01X3148909Y171304D02*
Y169926D01*
G01X3147925Y171304D02*
Y169926D01*
G01X3147630D02*
Y171304D01*
G01X3147236Y169926D02*
Y171304D01*
G01X3146744Y169926D02*
Y171304D01*
G01X3142098D02*
Y169926D01*
G01X3141606Y171304D02*
Y169926D01*
G01X3141212Y171304D02*
Y169926D01*
G01X3140917Y171304D02*
Y169926D01*
G01X3139933Y171304D02*
Y169926D01*
G01X3139637D02*
Y171304D01*
G01X3139244Y169926D02*
Y171304D01*
G01X3138752Y169926D02*
Y171304D01*
G01X3142098D02*
X3138752D01*
G01X3150090D02*
X3146744D01*
G01X3142098Y169926D02*
X3138752D01*
G01X3150090D02*
X3146744D01*
G01X3147531Y168941D02*
X3149303D01*
G01X3139539D02*
X3141311D01*
G01X3154586Y172618D02*
G03I-2153J0D01*
G01X3150090Y171304D02*
Y169926D01*
G01X3147196Y182205D02*
G03X3146409Y182992I-787J0D01*
G01X3148552Y178495D02*
G03X3149559Y177933I1006J619D01*
G01X3142472Y182992D02*
G03X3141685Y182205I0J-787D01*
G01X3139322Y177933D02*
G03X3140329Y178495I1J1181D01*
G01X3137201Y173586D02*
X3136975Y173398D01*
G01X3137201Y174715D02*
X3136975Y174527D01*
G01X3148359Y179889D02*
X3150201Y182672D01*
G01X3148359Y180571D02*
X3150201Y183354D01*
G01X3149559Y178889D02*
Y179676D01*
G01X3148552Y178889D02*
Y179676D01*
G01X3148426Y179331D02*
Y178774D01*
G01X3148359Y180571D02*
Y179889D01*
G01X3147612Y179676D02*
Y180301D01*
G01X3146409Y181811D02*
Y183780D01*
G01Y175610D02*
Y176397D01*
G01X3145819Y180301D02*
Y179676D01*
G01Y178889D02*
Y175610D01*
G01X3145228D02*
Y176397D01*
G01X3143653D02*
Y175610D01*
G01X3143063Y180301D02*
Y179676D01*
G01Y178889D02*
Y175610D01*
G01X3142472Y176397D02*
Y175610D01*
G01Y183780D02*
Y181811D01*
G01X3141269Y180301D02*
Y179676D01*
G01X3140522Y179889D02*
Y180571D01*
G01X3140456Y178774D02*
Y179331D01*
G01X3140329Y179676D02*
Y178889D01*
G01X3139322Y179676D02*
Y178889D01*
G01X3138122Y171929D02*
Y173307D01*
G01X3137630D02*
Y171929D01*
G01X3137334Y173307D02*
Y171929D01*
G01X3137236Y174847D02*
Y173650D01*
G01X3137201Y174715D02*
Y173586D01*
G01X3137137Y171929D02*
Y173307D01*
G01X3137039Y173831D02*
Y174959D01*
G01X3136975Y174527D02*
Y173398D01*
G01X3136941Y174463D02*
Y171929D01*
G01X3138681Y183354D02*
X3140522Y180571D01*
G01X3138681Y182672D02*
X3140522Y179889D01*
G01X3146409Y182205D02*
X3142472D01*
G01X3146409Y181811D02*
X3142472D01*
G01X3145819Y180301D02*
X3147612D01*
G01X3141269D02*
X3143063D01*
G01X3148552Y178495D02*
X3140329D01*
G01X3143063Y178234D02*
X3145819D01*
G01X3170228Y177933D02*
X3149559D01*
G01X3146409Y176397D02*
X3142472D01*
G01Y175610D02*
X3146409D01*
G01X3147695Y183114D02*
G03X3146409Y183780I-1286J-909D01*
G01X3142472D02*
G03X3141186Y183114I0J-1575D01*
G01X3149453Y183871D02*
Y183189D01*
G01X3139428D02*
Y183871D01*
G01X3138681Y183354D02*
Y182672D01*
G01X3138641Y182795D02*
Y183477D01*
G01X3139428Y183871D02*
X3149453D01*
G01X3146409Y183780D02*
X3142472D01*
G01Y183569D02*
X3146409D01*
G01X3149453Y183189D02*
X3139428D01*
G01X3146409Y182992D02*
X3142472D01*
G01Y182598D02*
X3146409D01*
G01X3153614Y172618D02*
G03I-1181J0D01*
G01X3153185Y173586D02*
X3152959Y173398D01*
G01X3153185Y174715D02*
X3152959Y174527D01*
G01X3153220Y174847D02*
Y173650D01*
G01X3153185Y174715D02*
Y173586D01*
G01X3153122Y171929D02*
Y173307D01*
G01X3153023Y173831D02*
Y174959D01*
G01X3152959Y174527D02*
Y173398D01*
G01X3152925Y174463D02*
Y171929D01*
G01X3151941D02*
Y174463D01*
G01X3151906Y173398D02*
Y174527D01*
G01X3151842Y174959D02*
Y173831D01*
G01X3151744Y173307D02*
Y171929D01*
G01X3151680Y173586D02*
Y174715D01*
G01X3151645Y174847D02*
Y173650D01*
G01X3151547Y173307D02*
Y171929D01*
G01X3151252Y173307D02*
Y171929D01*
G01X3150759Y173307D02*
Y171929D01*
G01X3151906Y174527D02*
X3151680Y174715D01*
G01X3151906Y173398D02*
X3151680Y173586D01*
G01X3151842Y174959D02*
X3153023D01*
G01Y173831D02*
X3151842D01*
G01X3150759Y173307D02*
X3154106D01*
G01X3151941Y172178D02*
X3152925D01*
G01X3150759Y171929D02*
X3154106D01*
G01X3150241Y182795D02*
Y183477D01*
G01X3150201Y182672D02*
Y183354D01*
G01X3148898Y385582D02*
X3148893Y383795D01*
G01X3148883Y384063D02*
X3148888Y385850D01*
G01X3141024Y385582D02*
X3141019Y383795D01*
G01X3141009Y384063D02*
X3141014Y385850D01*
G01X3148752Y383346D02*
Y382362D01*
G01X3147885Y383346D02*
Y382362D01*
G01X3140878Y383346D02*
Y382362D01*
G01X3140011Y383346D02*
Y382362D01*
G01X3147749Y385850D02*
X3147754Y384063D01*
G01X3147745Y383795D02*
X3147739Y385582D01*
G01X3139875Y385850D02*
X3139880Y384063D01*
G01X3139870Y383795D02*
X3139865Y385582D01*
G01X3147754Y384063D02*
X3148883D01*
G01X3139880D02*
X3141009D01*
G01X3141019Y383795D02*
X3139870D01*
G01X3148893D02*
X3147745D01*
G01X3141000Y383346D02*
X3139889D01*
G01X3148874D02*
X3147763D01*
G01Y382362D02*
X3148874D01*
G01X3139889D02*
X3141000D01*
G01X3148912Y392106D02*
X3148924Y392767D01*
G01X3148922Y393694D02*
X3148892Y392106D01*
G01X3144975D02*
X3144987Y392767D01*
G01X3144985Y393694D02*
X3144955Y392106D01*
G01X3141038D02*
X3141050Y392767D01*
G01X3141048Y393694D02*
X3141018Y392106D01*
G01X3137101D02*
X3137113Y392767D01*
G01X3137111Y393694D02*
X3137081Y392106D01*
G01X3147683D02*
X3147693Y392697D01*
G01X3147691Y393607D02*
X3147666Y392106D01*
G01X3143746D02*
X3143756Y392697D01*
G01X3143754Y393607D02*
X3143729Y392106D01*
G01X3139809D02*
X3139819Y392697D01*
G01X3139817Y393607D02*
X3139792Y392106D01*
G01X3143817Y389519D02*
X3143812Y387732D01*
G01X3143802Y388000D02*
X3143807Y389787D01*
G01X3148907Y386299D02*
Y387283D01*
G01X3147730D02*
Y386299D01*
G01X3144970Y387283D02*
Y386299D01*
G01X3144815Y391220D02*
Y390236D01*
G01X3143948Y391220D02*
Y390236D01*
G01X3143793Y386299D02*
Y387283D01*
G01X3141033Y386299D02*
Y387283D01*
G01X3139856D02*
Y386299D01*
G01X3137096Y387283D02*
Y386299D01*
G01X3136941Y391220D02*
Y390236D01*
G01X3144956Y389787D02*
X3144961Y388000D01*
G01X3144951Y387732D02*
X3144946Y389519D01*
G01X3137082Y389787D02*
X3137087Y388000D01*
G01X3137077Y387732D02*
X3137072Y389519D01*
G01X3148971Y392106D02*
X3148946Y393607D01*
G01X3148944Y392697D02*
X3148954Y392106D01*
G01X3145034D02*
X3145009Y393607D01*
G01X3145007Y392697D02*
X3145017Y392106D01*
G01X3141097D02*
X3141072Y393607D01*
G01X3141070Y392697D02*
X3141080Y392106D01*
G01X3137160D02*
X3137135Y393607D01*
G01X3137133Y392697D02*
X3137143Y392106D01*
G01X3147746D02*
X3147715Y393694D01*
G01X3147713Y392767D02*
X3147726Y392106D01*
G01X3143809D02*
X3143778Y393694D01*
G01X3143776Y392767D02*
X3143789Y392106D01*
G01X3139872D02*
X3139841Y393694D01*
G01X3139839Y392767D02*
X3139852Y392106D01*
G01X3147704Y393977D02*
X3148933D01*
G01X3143767D02*
X3144996D01*
G01X3139830D02*
X3141059D01*
G01X3147715Y393694D02*
X3148922D01*
G01X3143778D02*
X3144985D01*
G01X3139841D02*
X3141048D01*
G01X3141072Y393607D02*
X3139817D01*
G01X3145009D02*
X3143754D01*
G01X3148946D02*
X3147691D01*
G01X3147704Y392993D02*
X3148933D01*
G01X3143767D02*
X3144996D01*
G01X3139830D02*
X3141059D01*
G01X3141050Y392767D02*
X3139839D01*
G01X3144987D02*
X3143776D01*
G01X3148924D02*
X3147713D01*
G01X3147693Y392697D02*
X3148944D01*
G01X3143756D02*
X3145007D01*
G01X3139819D02*
X3141070D01*
G01X3144937Y391220D02*
X3143826D01*
G01Y390236D02*
X3144937D01*
G01X3143807Y389787D02*
X3144956D01*
G01X3144946Y389519D02*
X3143817D01*
G01X3144961Y388000D02*
X3143802D01*
G01X3143812Y387732D02*
X3144951D01*
G01X3147730Y387283D02*
X3148907D01*
G01X3143793D02*
X3144970D01*
G01X3139856D02*
X3141033D01*
G01Y386299D02*
X3139856D01*
G01X3144970D02*
X3143793D01*
G01X3148907D02*
X3147730D01*
G01X3141014Y385850D02*
X3139875D01*
G01X3148888D02*
X3147749D01*
G01X3147739Y385582D02*
X3148898D01*
G01X3139865D02*
X3141024D01*
G01X3147715Y397604D02*
X3147746Y399193D01*
G01X3147726D02*
X3147713Y398532D01*
G01X3143778Y397604D02*
X3143809Y399193D01*
G01X3143789D02*
X3143776Y398532D01*
G01X3139841Y397604D02*
X3139872Y399193D01*
G01X3139852D02*
X3139839Y398532D01*
G01X3148946Y397691D02*
X3148971Y399193D01*
G01X3148954D02*
X3148944Y398602D01*
G01X3145009Y397691D02*
X3145034Y399193D01*
G01X3145017D02*
X3145007Y398602D01*
G01X3141072Y397691D02*
X3141097Y399193D01*
G01X3141080D02*
X3141070Y398602D01*
G01X3137135Y397691D02*
X3137160Y399193D01*
G01X3137143D02*
X3137133Y398602D01*
G01X3144815Y401063D02*
Y400078D01*
G01X3143948D02*
Y401063D01*
G01X3136941D02*
Y400078D01*
G01X3147693Y398602D02*
X3147683Y399193D01*
G01X3147666D02*
X3147691Y397691D01*
G01X3143756Y398602D02*
X3143746Y399193D01*
G01X3143729D02*
X3143754Y397691D01*
G01X3139819Y398602D02*
X3139809Y399193D01*
G01X3139792D02*
X3139817Y397691D01*
G01X3148924Y398532D02*
X3148912Y399193D01*
G01X3148892D02*
X3148922Y397604D01*
G01X3144987Y398532D02*
X3144975Y399193D01*
G01X3144955D02*
X3144985Y397604D01*
G01X3141050Y398532D02*
X3141038Y399193D01*
G01X3141018D02*
X3141048Y397604D01*
G01X3137113Y398532D02*
X3137101Y399193D01*
G01X3137081D02*
X3137111Y397604D01*
G01X3144937Y401063D02*
X3143826D01*
G01X3144937Y400078D02*
X3143826D01*
G01X3141070Y398602D02*
X3139819D01*
G01X3145007D02*
X3143756D01*
G01X3148944D02*
X3147693D01*
G01X3147713Y398532D02*
X3148924D01*
G01X3143776D02*
X3144987D01*
G01X3139839D02*
X3141050D01*
G01X3141059Y398306D02*
X3139830D01*
G01X3144996D02*
X3143767D01*
G01X3148933D02*
X3147704D01*
G01X3147691Y397691D02*
X3148946D01*
G01X3143754D02*
X3145009D01*
G01X3139817D02*
X3141072D01*
G01X3141048Y397604D02*
X3139841D01*
G01X3144985D02*
X3143778D01*
G01X3148922D02*
X3147715D01*
G01X3141059Y397322D02*
X3139830D01*
G01X3144996D02*
X3143767D01*
G01X3148933D02*
X3147704D01*
G01X3152849Y392106D02*
X3152861Y392767D01*
G01X3152859Y393694D02*
X3152829Y392106D01*
G01X3151620D02*
X3151630Y392697D01*
G01X3151628Y393607D02*
X3151603Y392106D01*
G01X3151691Y389519D02*
X3151686Y387732D01*
G01X3151676Y388000D02*
X3151682Y389787D01*
G01X3152844Y387283D02*
Y386299D01*
G01X3152689Y391220D02*
Y390236D01*
G01X3151822Y391220D02*
Y390236D01*
G01X3151667Y386299D02*
Y387283D01*
G01X3152830Y389787D02*
X3152835Y388000D01*
G01X3152825Y387732D02*
X3152820Y389519D01*
G01X3152908Y392106D02*
X3152883Y393607D01*
G01X3152881Y392697D02*
X3152891Y392106D01*
G01X3151683D02*
X3151652Y393694D01*
G01X3151650Y392767D02*
X3151663Y392106D01*
G01X3151641Y393977D02*
X3152870D01*
G01X3151652Y393694D02*
X3152859D01*
G01X3152883Y393607D02*
X3151628D01*
G01X3151641Y392993D02*
X3152870D01*
G01X3152861Y392767D02*
X3151650D01*
G01X3151630Y392697D02*
X3152881D01*
G01X3152811Y391220D02*
X3151700D01*
G01Y390236D02*
X3152811D01*
G01X3151682Y389787D02*
X3152830D01*
G01X3152820Y389519D02*
X3151691D01*
G01X3152835Y388000D02*
X3151676D01*
G01X3151686Y387732D02*
X3152825D01*
G01X3151667Y387283D02*
X3152844D01*
G01Y386299D02*
X3151667D01*
G01X3151652Y397604D02*
X3151683Y399193D01*
G01X3151663D02*
X3151650Y398532D01*
G01X3152883Y397691D02*
X3152908Y399193D01*
G01X3152891D02*
X3152881Y398602D01*
G01X3152689Y401063D02*
Y400078D01*
G01X3151822D02*
Y401063D01*
G01X3151630Y398602D02*
X3151620Y399193D01*
G01X3151603D02*
X3151628Y397691D01*
G01X3152861Y398532D02*
X3152849Y399193D01*
G01X3152829D02*
X3152859Y397604D01*
G01X3152811Y401063D02*
X3151700D01*
G01X3152811Y400078D02*
X3151700D01*
G01X3152881Y398602D02*
X3151630D01*
G01X3151650Y398532D02*
X3152861D01*
G01X3152870Y398306D02*
X3151641D01*
G01X3151628Y397691D02*
X3152883D01*
G01X3152859Y397604D02*
X3151652D01*
G01X3152870Y397322D02*
X3151641D01*
G01X3141000Y408937D02*
X3139889D01*
G01X3148874D02*
X3147763D01*
G01X3141000Y407952D02*
X3139889D01*
G01X3148874D02*
X3147763D01*
G01X3147745Y407504D02*
X3148893D01*
G01X3139870D02*
X3141019D01*
G01X3141009Y407236D02*
X3139880D01*
G01X3148883D02*
X3147754D01*
G01X3141024Y405716D02*
X3139865D01*
G01X3148898D02*
X3147739D01*
G01X3147749Y405449D02*
X3148888D01*
G01X3139875D02*
X3141014D01*
G01X3141033Y405000D02*
X3139856D01*
G01X3144970D02*
X3143793D01*
G01X3148907D02*
X3147730D01*
G01X3141033Y404015D02*
X3139856D01*
G01X3144970D02*
X3143793D01*
G01X3148907D02*
X3147730D01*
G01X3144951Y403567D02*
X3143812D01*
G01X3143802Y403299D02*
X3144961D01*
G01X3147754Y407236D02*
X3147749Y405449D01*
G01X3147739Y405716D02*
X3147745Y407504D01*
G01X3144961Y403299D02*
X3144956Y401512D01*
G01X3144946Y401779D02*
X3144951Y403567D01*
G01X3139880Y407236D02*
X3139875Y405449D01*
G01X3139865Y405716D02*
X3139870Y407504D01*
G01X3137087Y403299D02*
X3137082Y401512D01*
G01X3137072Y401779D02*
X3137077Y403567D01*
G01X3148907Y404015D02*
Y405000D01*
G01X3148752Y408937D02*
Y407952D01*
G01X3147885D02*
Y408937D01*
G01X3147730Y405000D02*
Y404015D01*
G01X3144970Y405000D02*
Y404015D01*
G01X3143793D02*
Y405000D01*
G01X3141941Y415728D02*
Y410118D01*
G01X3141033Y404015D02*
Y405000D01*
G01X3140878Y408937D02*
Y407952D01*
G01X3140011D02*
Y408937D01*
G01X3139856Y405000D02*
Y404015D01*
G01X3137096Y405000D02*
Y404015D01*
G01X3136941Y415728D02*
Y410118D01*
G01X3148893Y407504D02*
X3148898Y405716D01*
G01X3148888Y405449D02*
X3148883Y407236D01*
G01X3143812Y403567D02*
X3143817Y401779D01*
G01X3143807Y401512D02*
X3143802Y403299D01*
G01X3141019Y407504D02*
X3141024Y405716D01*
G01X3141014Y405449D02*
X3141009Y407236D01*
G01X3143817Y401779D02*
X3144946D01*
G01X3144956Y401512D02*
X3143807D01*
G01X3157846Y415728D02*
X3141941D01*
G01X3152844Y405000D02*
X3151667D01*
G01X3152844Y404015D02*
X3151667D01*
G01X3152825Y403567D02*
X3151686D01*
G01X3151676Y403299D02*
X3152835D01*
G01D02*
X3152830Y401512D01*
G01X3152820Y401779D02*
X3152825Y403567D01*
G01X3152844Y405000D02*
Y404015D01*
G01X3151667D02*
Y405000D01*
G01X3151686Y403567D02*
X3151691Y401779D01*
G01X3151682Y401512D02*
X3151676Y403299D01*
G01X3151691Y401779D02*
X3152820D01*
G01X3152830Y401512D02*
X3151682D01*
G01X3144982Y464600D02*
X3138830Y459071D01*
G01X3136862D02*
X3143752Y465354D01*
G01X3138830Y459071D02*
X3145720D01*
G01Y457815D02*
X3136862D01*
G01X3148919D02*
X3147689D01*
G01X3148919Y464097D02*
Y457815D01*
G01X3147689D02*
Y465856D01*
G01X3145720Y459071D02*
Y457815D01*
G01X3136862D02*
Y459071D01*
G01X3150149Y464851D02*
X3149411Y464600D01*
G01Y465605D02*
X3150149Y465856D01*
G01X3147689D02*
X3148919D01*
G01X3149411Y464600D02*
X3148919Y464097D01*
G01Y465102D02*
X3149411Y465605D01*
G01X3145474Y465354D02*
X3144982Y464600D01*
G01X3143752Y465354D02*
X3144244Y466359D01*
G01X3145720D02*
X3145474Y465354D01*
G01X3148919Y465856D02*
Y465102D01*
G01X3145720Y466861D02*
Y466359D01*
G01X3144244D02*
Y466861D01*
G01X3152856Y457815D02*
X3151626D01*
G01X3152856Y463846D02*
Y457815D01*
G01X3151626D02*
Y463846D01*
G01X3150149Y465856D02*
X3151133D01*
G01X3150641Y464851D02*
X3150149D01*
G01X3153348Y464600D02*
X3153102Y464348D01*
G01X3152610Y464851D02*
X3153348Y465605D01*
G01X3153102Y464348D02*
X3152856Y463846D01*
G01X3151626D02*
X3151380Y464348D01*
G01X3151872Y465605D02*
X3152610Y464851D01*
G01X3151380Y464348D02*
X3151133Y464600D01*
G01D02*
X3150641Y464851D01*
G01X3151133Y465856D02*
X3151872Y465605D01*
G01X3141045Y469626D02*
X3142029D01*
G01X3141783Y468369D02*
X3140799D01*
G01X3138338Y466861D02*
X3137108D01*
G01X3139322Y469374D02*
X3141045Y469626D01*
G01X3140799Y468369D02*
X3139569Y468118D01*
G01X3138338Y468872D02*
X3139322Y469374D01*
G01X3139569Y468118D02*
X3138830Y467615D01*
G01X3137354Y467867D02*
X3138338Y468872D01*
G01X3138830Y467615D02*
X3138338Y466861D01*
G01X3145474Y467867D02*
X3145720Y466861D01*
G01X3144244D02*
X3143752Y467615D01*
G01X3144490Y468872D02*
X3145474Y467867D01*
G01X3143752Y467615D02*
X3143013Y468118D01*
G01X3143506Y469374D02*
X3144490Y468872D01*
G01X3143013Y468118D02*
X3141783Y468369D01*
G01X3142029Y469626D02*
X3143506Y469374D01*
G01X3137108Y466861D02*
X3137354Y467867D01*
G01X3154635Y505295D02*
Y513956D01*
X3153336Y512224D01*
G01Y505295D02*
X3155934D01*
G01X3163296Y513956D02*
X3162430Y513667D01*
X3161780Y512946D01*
X3161347Y512080D01*
X3161022Y510925D01*
X3160914Y509625D01*
X3161022Y508326D01*
X3161347Y507171D01*
X3161780Y506305D01*
X3162430Y505584D01*
X3163296Y505295D01*
X3164162Y505584D01*
X3164812Y506305D01*
X3165245Y507171D01*
X3165570Y508326D01*
X3165678Y509625D01*
X3165570Y510925D01*
X3165245Y512080D01*
X3164812Y512946D01*
X3164162Y513667D01*
X3163296Y513956D01*
G01X3173256Y505295D02*
Y513956D01*
X3169250Y507749D01*
X3174664D01*
G01X3180618Y505006D02*
X3180401Y505151D01*
Y505439D01*
X3180618Y505584D01*
X3180835Y505439D01*
Y505151D01*
X3180618Y505006D01*
G01X3186897Y507027D02*
X3187547Y506017D01*
X3188413Y505439D01*
X3189387Y505295D01*
X3190253Y505439D01*
X3191120Y506161D01*
X3191661Y507027D01*
X3191769Y507893D01*
X3191553Y508904D01*
X3190795Y509625D01*
X3190037Y509914D01*
X3189062D01*
G01X3190037D02*
X3190686Y510347D01*
X3191228Y511069D01*
X3191444Y511935D01*
X3191228Y512801D01*
X3190686Y513523D01*
X3189712Y513956D01*
X3188738Y513812D01*
X3187763Y513234D01*
G01X3197940Y513956D02*
X3197074Y513667D01*
X3196424Y512946D01*
X3195991Y512080D01*
X3195666Y510925D01*
X3195558Y509625D01*
X3195666Y508326D01*
X3195991Y507171D01*
X3196424Y506305D01*
X3197074Y505584D01*
X3197940Y505295D01*
X3198806Y505584D01*
X3199456Y506305D01*
X3199889Y507171D01*
X3200214Y508326D01*
X3200322Y509625D01*
X3200214Y510925D01*
X3199889Y512080D01*
X3199456Y512946D01*
X3198806Y513667D01*
X3197940Y513956D01*
G01X3160632Y-1002613D02*
X3159549Y-1001169D01*
X3159008Y-999726D01*
Y-993952D01*
X3159549Y-992508D01*
X3160632Y-991065D01*
G01X3167993Y-999726D02*
Y-991065D01*
G01Y-995251D02*
X3168535Y-994529D01*
X3169076Y-994096D01*
X3169942Y-993952D01*
X3170592Y-994096D01*
X3171350Y-994674D01*
X3171675Y-995540D01*
Y-999726D01*
G01X3177088Y-998138D02*
X3179902D01*
G01Y-995540D02*
X3177088D01*
G01X3187156Y-991065D02*
X3186290Y-991354D01*
X3185640Y-992075D01*
X3185207Y-992941D01*
X3184882Y-994096D01*
X3184774Y-995396D01*
X3184882Y-996695D01*
X3185207Y-997850D01*
X3185640Y-998716D01*
X3186290Y-999437D01*
X3187156Y-999726D01*
X3188022Y-999437D01*
X3188672Y-998716D01*
X3189105Y-997850D01*
X3189430Y-996695D01*
X3189538Y-995396D01*
X3189430Y-994096D01*
X3189105Y-992941D01*
X3188672Y-992075D01*
X3188022Y-991354D01*
X3187156Y-991065D01*
G01X3192569Y-999726D02*
Y-993952D01*
G01Y-995540D02*
X3192894Y-994818D01*
X3193435Y-994241D01*
X3194193Y-993952D01*
X3194951Y-994241D01*
X3195492Y-994818D01*
X3195817Y-995540D01*
Y-999726D01*
G01Y-995540D02*
X3196142Y-994818D01*
X3196683Y-994241D01*
X3197441Y-993952D01*
X3198199Y-994241D01*
X3198740Y-994818D01*
X3199065Y-995684D01*
Y-999726D01*
G01X3201230D02*
Y-993952D01*
G01Y-995540D02*
X3201555Y-994818D01*
X3202096Y-994241D01*
X3202854Y-993952D01*
X3203612Y-994241D01*
X3204153Y-994818D01*
X3204478Y-995540D01*
Y-999726D01*
G01Y-995540D02*
X3204803Y-994818D01*
X3205344Y-994241D01*
X3206102Y-993952D01*
X3206860Y-994241D01*
X3207401Y-994818D01*
X3207726Y-995684D01*
Y-999726D01*
G01X3213680Y-1002613D02*
X3214763Y-1001169D01*
X3215304Y-999726D01*
Y-993952D01*
X3214763Y-992508D01*
X3213680Y-991065D01*
G01X3158201Y-983828D02*
X3157118Y-982384D01*
X3156577Y-980941D01*
Y-975167D01*
X3157118Y-973723D01*
X3158201Y-972280D01*
G01X3164913Y-980941D02*
Y-972280D01*
X3169893Y-980941D01*
Y-972280D01*
G01X3173899Y-980941D02*
Y-972280D01*
X3176497D01*
X3177363Y-972713D01*
X3178013Y-973723D01*
X3178229Y-974878D01*
X3178013Y-976033D01*
X3177471Y-976899D01*
X3176497Y-977332D01*
X3173899D01*
G01X3184725Y-972280D02*
Y-980941D01*
G01X3182235Y-972280D02*
X3187215D01*
G01X3191112Y-980941D02*
Y-972280D01*
G01X3195660D02*
Y-980941D01*
G01Y-976611D02*
X3191112D01*
G01X3202588Y-983828D02*
X3203671Y-982384D01*
X3204212Y-980941D01*
Y-975167D01*
X3203671Y-973723D01*
X3202588Y-972280D01*
G01X3169292Y-682988D02*
X3165483D01*
G01X3169292Y-663533D02*
Y-682988D01*
G01X3165483D02*
Y-658086D01*
G01X3155577Y-679875D02*
X3157863Y-676763D01*
G01X3154815Y-667424D02*
X3153291Y-665868D01*
G01X3155577Y-669759D02*
X3154815Y-667424D01*
G01X3159387Y-668981D02*
X3157863Y-665090D01*
G01X3159387Y-672872D02*
Y-668981D01*
G01X3155577Y-672093D02*
Y-669759D01*
G01X3157863Y-676763D02*
X3159387Y-672872D01*
G01X3154815Y-674428D02*
X3155577Y-672093D01*
G01X3153291Y-676763D02*
X3154815Y-674428D01*
G01X3157863Y-665090D02*
X3155577Y-662755D01*
G01X3154053Y-654973D02*
X3157863D01*
G01X3157101Y-652639D02*
X3154815Y-649526D01*
G01X3157863Y-654973D02*
X3157101Y-652639D01*
G01X3170816Y-661977D02*
X3169292Y-663533D01*
G01X3165483Y-658086D02*
X3169292D01*
G01D02*
Y-660420D01*
G01D02*
X3170816Y-658864D01*
G01X3154283Y85807D02*
G03X3153496Y86594I-787J0D01*
G01X3162895Y85846D02*
X3162502Y85452D01*
G01X3160671Y85846D02*
X3160277Y85452D01*
G01X3165651Y107106D02*
Y85846D01*
G01X3165317Y86567D02*
Y99064D01*
G01X3162895Y92145D02*
Y85452D01*
G01X3162167D02*
Y91752D01*
G01X3160671Y85846D02*
Y109074D01*
G01X3160592Y85767D02*
Y85452D01*
G01X3160484D02*
Y107106D01*
G01X3159007Y84626D02*
Y85413D01*
G01X3158220D02*
Y84626D01*
G01X3157433D02*
Y85413D01*
G01X3156842Y129153D02*
Y86830D01*
G01X3155070Y84626D02*
Y85413D01*
G01X3154283Y85807D02*
Y84626D01*
G01X3165651Y85846D02*
X3166045Y85452D01*
G01X3156842Y86830D02*
X3158220Y85452D01*
G01X3167876Y88996D02*
X3165651D01*
G01X3167876Y88684D02*
X3165651D01*
G01X3165317Y88338D02*
X3167876D01*
G01Y88165D02*
X3165651D01*
G01X3167876Y87846D02*
X3165317D01*
G01X3167876Y87815D02*
X3165651D01*
G01X3167876Y87452D02*
X3165317D01*
G01X3167876Y87354D02*
X3165317D01*
G01X3167876Y86567D02*
X3165317D01*
G01X3154178Y86200D02*
X3176822D01*
G01X3160671Y85846D02*
X3167876D01*
G01X3169047Y87775D02*
G03X3168732Y88405I-787J0D01*
G01X3168956Y85927D02*
G03X3170507Y84626I1551J274D01*
G01X3169047D02*
Y88405D01*
G01X3168259Y85413D02*
Y84626D01*
G01X3168063Y85659D02*
Y129153D01*
G01X3167876Y109074D02*
Y85846D01*
G01X3169732Y86064D02*
X3168127Y95165D01*
G01X3167352Y95028D02*
X3168956Y85927D01*
G01X3168063Y86240D02*
X3168850Y85452D01*
G01X3167876Y85846D02*
X3168269Y85452D01*
G01X3168063Y86166D02*
X3168137D01*
G01X3153732Y94903D02*
X3153738Y95043D01*
G01X3155307Y94979D02*
X3155313Y95043D01*
G01X3153738D02*
X3153732Y94979D01*
G01X3155313Y95043D02*
X3155307Y94903D01*
G01X3157748D02*
X3157756Y95043D01*
G01X3159322Y94979D02*
X3159331Y95043D01*
G01X3157756D02*
X3157748Y94979D01*
G01X3159331Y95043D02*
X3159322Y94903D01*
G01X3161576Y93326D02*
G03Y94901I0J788D01*
G01X3165317Y91752D02*
G03X3162167I-1575J0D01*
G01X3159677Y99148D02*
X3159331Y95043D01*
G01X3158229Y100655D02*
X3157756Y95043D01*
G01X3155649Y100655D02*
X3155313Y95043D01*
G01X3154074Y100655D02*
X3153738Y95043D01*
G01X3162561Y108287D02*
Y98641D01*
G01X3160789Y101713D02*
Y98670D01*
G01X3159677Y89980D02*
Y110059D01*
G01X3159322Y92484D02*
Y120985D01*
G01X3157748Y92484D02*
Y120985D01*
G01X3157315Y89980D02*
Y110059D01*
G01X3155661Y89980D02*
Y110059D01*
G01X3155307Y92484D02*
Y120985D01*
G01X3153732Y92484D02*
Y120985D01*
G01X3153299Y110059D02*
Y89980D01*
G01X3165317Y99064D02*
X3160789D01*
G01Y98670D02*
X3165317D01*
G01X3162561Y98641D02*
X3160671D01*
G01X3155307Y97483D02*
X3153732D01*
G01X3159322D02*
X3157748D01*
G01X3155307Y96989D02*
X3153732D01*
G01X3159322D02*
X3157748D01*
G01Y96778D02*
X3159322D01*
G01X3153732D02*
X3155307D01*
G01X3157748Y95043D02*
X3159331D01*
G01X3153732D02*
X3155313D01*
G01X3160671Y94901D02*
X3161576D01*
G01X3157748Y94838D02*
X3159322D01*
G01X3153732D02*
X3155307D01*
G01X3157748Y93862D02*
X3159322D01*
G01X3153732D02*
X3155307D01*
G01X3160671Y93326D02*
X3161576D01*
G01X3157748Y92484D02*
X3159322D01*
G01X3153732D02*
X3155307D01*
G01X3157315Y92342D02*
X3159677D01*
G01X3153299D02*
X3155661D01*
G01X3162895Y92145D02*
X3165651D01*
G01Y91752D02*
X3162895D01*
G01X3155661Y89980D02*
X3153299D01*
G01X3159677D02*
X3157315D01*
G01X3154074Y100655D02*
X3154083Y100861D01*
G01X3154109Y101446D02*
X3154083Y100861D01*
G01X3155649Y100655D02*
X3155661Y100783D01*
G01X3158229Y100655D02*
X3158242Y100861D01*
G01X3154109Y101020D02*
G03X3154074Y100655I80210J-7876D01*
G01X3158279Y101446D02*
G03X3158242Y100861I234187J-15105D01*
G01X3158278Y101020D02*
G03X3158229Y100655I57533J-7909D01*
G01X3160235Y105329D02*
G03X3160284Y106120I-251914J16002D01*
G01X3158660Y105329D02*
G03X3158710Y106120I-256486J16610D01*
G01X3155956Y105329D02*
G03X3155991Y106120I-353672J16045D01*
G01X3154381Y105329D02*
G03X3154416Y106120I-360086J16329D01*
G01X3160096Y103759D02*
X3160235Y105329D01*
G01X3158660D02*
X3158279Y101020D01*
G01X3158660Y105755D02*
X3158279Y101446D01*
G01X3163317Y133484D02*
X3160852Y104350D01*
G01X3162922Y133484D02*
X3160456Y104350D01*
G01X3160560Y133484D02*
X3158094Y104350D01*
G01X3157699D02*
X3160165Y133484D01*
G01X3160077Y103759D02*
X3160235Y105736D01*
G01X3155857Y103759D02*
X3155956Y105329D01*
G01X3154381D02*
X3154109Y101020D01*
G01X3154381Y105755D02*
X3154109Y101446D01*
G01X3158373Y133484D02*
X3156613Y104350D01*
G01X3157979Y133484D02*
X3156218Y104350D01*
G01X3155617Y133484D02*
X3153856Y104350D01*
G01X3153461D02*
X3155222Y133484D01*
G01X3155843Y103759D02*
X3155956Y105736D01*
G01X3160235Y105329D02*
Y105736D01*
G01X3158660Y105755D02*
Y105329D01*
G01X3158279Y101446D02*
Y101020D01*
G01X3155956Y105329D02*
Y105736D01*
G01X3154381Y105755D02*
Y105329D01*
G01X3154109Y101446D02*
Y101020D01*
G01X3155956Y105329D02*
X3154381D01*
G01X3160235D02*
X3158660D01*
G01X3159677Y103759D02*
X3170622D01*
G01X3155661D02*
X3157315D01*
G01X3167876Y101713D02*
X3160789D01*
G01X3155661Y101446D02*
X3154109D01*
G01X3159677D02*
X3158279D01*
G01X3160789Y101319D02*
X3167876D01*
G01X3155661Y101020D02*
X3154109D01*
G01X3159677D02*
X3158279D01*
G01X3158242Y100861D02*
X3159677D01*
G01X3154083D02*
X3155661D01*
G01X3158229Y100655D02*
X3159677D01*
G01X3154074D02*
X3155649D01*
G01X3168305Y97194D02*
G03X3168127Y95165I3699J-1347D01*
G01X3167565Y97464D02*
G03X3167352Y95028I4439J-1615D01*
G01X3168305Y97194D02*
X3169263Y99829D01*
G01X3168524Y100098D02*
X3167565Y97464D01*
G01X3169263Y99829D02*
X3168524Y100098D01*
G01X3168994Y99089D02*
X3168254Y99358D01*
G01X3169342Y118130D02*
Y105137D01*
G01D02*
X3171773D01*
G01X3169933Y103011D02*
X3168063D01*
G01X3163348Y109074D02*
G03X3162561Y108287I0J-787D01*
G01X3158660Y105755D02*
G03X3158709Y106120I-62245J8542D01*
G01X3154381Y105755D02*
G03X3154416Y106120I-86778J8505D01*
G01X3162713Y134960D02*
X3160284Y106120D01*
G01X3161139Y134960D02*
X3158709Y106120D01*
G01X3157718Y134960D02*
X3155991Y106120D01*
G01X3156143Y134960D02*
X3154416Y106120D01*
G01X3155661Y110059D02*
X3153299D01*
G01X3159677D02*
X3157315D01*
G01X3160671Y109074D02*
X3167876D01*
G01X3168063Y107106D02*
X3160484D01*
G01X3158709Y106120D02*
X3160284D01*
G01X3154416D02*
X3155991D01*
G01X3155661Y105755D02*
X3154381D01*
G01X3159677D02*
X3158660D01*
G01X3157945Y120859D02*
X3157748Y120491D01*
G01X3157945Y121353D02*
X3157748Y120985D01*
G01X3153929Y120859D02*
X3153732Y120491D01*
G01X3153929Y121353D02*
X3153732Y120985D01*
G01X3162157Y121279D02*
Y125216D01*
G01X3159126Y120859D02*
Y128520D01*
G01X3157945D02*
Y120859D01*
G01X3155110D02*
Y128520D01*
G01X3153929D02*
Y120859D01*
G01X3159322Y120985D02*
X3159126Y121353D01*
G01X3159322Y120491D02*
X3159126Y120859D01*
G01X3155307Y120985D02*
X3155110Y121353D01*
G01X3155307Y120491D02*
X3155110Y120859D01*
G01X3168063Y121279D02*
X3162157D01*
G01X3168063Y119311D02*
X3156842D01*
G01X3167876Y108287D02*
G03X3167088Y109074I-787J0D01*
G01X3160987Y132548D02*
G03X3165887I2450J4086D01*
G01X3169815Y136634D02*
G03I-6378J0D01*
G01X3169972Y136633D02*
X3163437Y130098D01*
G01X3158141Y128761D02*
X3157945Y128026D01*
G01X3158141Y129255D02*
X3157945Y128520D01*
G01X3154126Y128761D02*
X3153929Y128026D01*
G01X3154126Y129255D02*
X3153929Y128520D01*
G01X3160759Y137421D02*
Y131909D01*
G01X3159677D02*
Y125216D01*
G01X3158929Y129255D02*
Y128761D01*
G01X3158141Y129255D02*
Y128761D01*
G01X3157315Y131909D02*
Y125216D01*
G01X3155759Y138479D02*
Y131909D01*
G01X3155661D02*
Y125216D01*
G01X3154913Y129255D02*
Y128761D01*
G01X3154126Y129255D02*
Y128761D01*
G01X3153299Y131909D02*
Y125216D01*
G01X3159126Y128520D02*
X3158929Y129255D01*
G01X3159126Y128026D02*
X3158929Y128761D01*
G01X3155110Y128520D02*
X3154913Y129255D01*
G01X3155110Y128026D02*
X3154913Y128761D01*
G01X3156901Y136633D02*
X3163437Y130098D01*
G01X3158141Y129255D02*
X3158929D01*
G01X3154126D02*
X3154913D01*
G01Y128761D02*
X3154126D01*
G01X3158929D02*
X3158141D01*
G01X3157315Y128484D02*
X3155661D01*
G01X3170622D02*
X3159677D01*
G01X3168063Y124232D02*
X3162157D01*
G01X3156153Y135203D02*
X3156143Y134960D01*
G01X3157718D02*
X3157728Y135203D01*
G01X3156153Y135061D02*
X3156143Y134960D01*
G01X3157718D02*
X3157728Y135061D01*
G01X3161153Y135203D02*
X3161139Y134960D01*
G01X3162713D02*
X3162728Y135203D01*
G01X3161153Y135061D02*
X3161139Y134960D01*
G01X3162713D02*
X3162728Y135061D01*
G01X3159351Y139083D02*
G03Y134183I4086J-2450D01*
G01X3156901Y136633D02*
X3163437Y143169D01*
G01X3163279Y137421D02*
X3163908Y138208D01*
G01X3158279Y137421D02*
X3158908Y138208D01*
G01X3153279Y137421D02*
X3153908Y138208D01*
G01X3166488Y138479D02*
Y137101D01*
G01X3166462Y138479D02*
Y137101D01*
G01X3166389D02*
Y148897D01*
G01X3166245Y137101D02*
Y138479D01*
G01X3166219D02*
Y137101D01*
G01X3166193Y138479D02*
Y137101D01*
G01X3165208Y138479D02*
Y137101D01*
G01X3165183D02*
Y138479D01*
G01X3165156D02*
Y137101D01*
G01X3165011D02*
Y148897D01*
G01X3164939Y137101D02*
Y138479D01*
G01X3164913Y138602D02*
Y134665D01*
G01X3164867Y138479D02*
Y137101D01*
G01X3164815Y138479D02*
Y137101D01*
G01X3164480Y137322D02*
Y135944D01*
G01X3164224Y138479D02*
Y137322D01*
G01X3163929Y134665D02*
Y133484D01*
G01X3163909Y135846D02*
Y134665D01*
G01X3163908Y138208D02*
Y135846D01*
G01X3163279D02*
Y137421D01*
G01X3163122Y133484D02*
Y137421D01*
G01X3162728Y135061D02*
Y137322D01*
G01X3162452D02*
Y138479D01*
G01X3162334Y135944D02*
Y137322D01*
G01X3161862Y138479D02*
Y137101D01*
G01X3161809D02*
Y138479D01*
G01X3161763D02*
Y137101D01*
G01X3161738Y138479D02*
Y137101D01*
G01X3161665Y137322D02*
Y148897D01*
G01X3161547Y137322D02*
Y135944D01*
G01X3161521Y137101D02*
Y138479D01*
G01X3161494D02*
Y137101D01*
G01X3161468Y138479D02*
Y137101D01*
G01X3161153Y135061D02*
Y137322D01*
G01X3160602Y137421D02*
Y135846D01*
G01X3160484Y138479D02*
Y137101D01*
G01X3160458D02*
Y138479D01*
G01X3160431D02*
Y137101D01*
G01X3160287Y137322D02*
Y148897D01*
G01X3160215Y137101D02*
Y138479D01*
G01X3160189D02*
Y137101D01*
G01X3160143Y138479D02*
Y137101D01*
G01X3160090Y138479D02*
Y137101D01*
G01X3159973Y135846D02*
Y138208D01*
G01X3159972Y134665D02*
Y135846D01*
G01X3159500Y138479D02*
Y137322D01*
G01X3158909Y135846D02*
Y134665D01*
G01X3158908Y138208D02*
Y135846D01*
G01X3158279D02*
Y137421D01*
G01X3158122Y133484D02*
Y137421D01*
G01X3157728Y135061D02*
Y138479D01*
G01X3157334Y135944D02*
Y137322D01*
G01X3157137Y138479D02*
Y137101D01*
G01X3157085D02*
Y138479D01*
G01X3157039D02*
Y137101D01*
G01X3157013Y138479D02*
Y137101D01*
G01X3156941Y137322D02*
Y148897D01*
G01X3156796Y137101D02*
Y138479D01*
G01X3156770D02*
Y137101D01*
G01X3156744Y138479D02*
Y137101D01*
G01X3156547Y137322D02*
Y135944D01*
G01X3156153Y135061D02*
Y137322D01*
G01X3155734Y137101D02*
Y138479D01*
G01X3155707D02*
Y137101D01*
G01X3155602Y135846D02*
Y137421D01*
G01X3155563Y137322D02*
Y148897D01*
G01X3155490Y137101D02*
Y138479D01*
G01X3155464D02*
Y137101D01*
G01X3155419Y138479D02*
Y137101D01*
G01X3155366Y138479D02*
Y137101D01*
G01X3154973Y135846D02*
Y138208D01*
G01X3154972Y134665D02*
Y135846D01*
G01X3154775Y138479D02*
Y137322D01*
G01X3153909Y135846D02*
Y134665D01*
G01X3153908Y138208D02*
Y135846D01*
G01X3153279D02*
Y137421D01*
G01X3159973Y138208D02*
X3160602Y137421D01*
G01X3154973Y138208D02*
X3155602Y137421D01*
G01X3163437Y143169D02*
X3169972Y136633D01*
G01X3157728Y138479D02*
X3154775D01*
G01X3162452D02*
X3159500D01*
G01X3167177D02*
X3164224D01*
G01X3159973Y138208D02*
X3163908D01*
G01X3154973D02*
X3158908D01*
G01X3160602Y137421D02*
X3163279D01*
G01X3155602D02*
X3158279D01*
G01X3164480Y137101D02*
X3167177D01*
G01X3157137D02*
X3155366D01*
G01X3161862D02*
X3160090D01*
G01X3158903Y135846D02*
X3154978D01*
G01X3163903D02*
X3159978D01*
G01X3161139Y134960D02*
X3162713D01*
G01X3156143D02*
X3157718D01*
G01X3160560Y133484D02*
X3157979D01*
G01X3163929D02*
X3162922D01*
G01X3168203Y137368D02*
Y132337D01*
G01X3168063Y133484D02*
Y132696D01*
G01X3168203Y132337D02*
X3172795D01*
G01X3167522Y134183D02*
G03Y139083I-4085J2450D01*
G01X3169663Y137368D02*
Y138479D01*
G01X3169637D02*
Y137368D01*
G01X3169592Y138479D02*
Y137368D01*
G01X3169539Y138479D02*
Y137368D01*
G01X3168948Y138479D02*
Y137368D01*
G01X3167177Y137101D02*
Y138479D01*
G01X3166586D02*
Y137101D01*
G01X3166533D02*
Y138479D01*
G01X3171901D02*
X3168948D01*
G01X3172795Y137368D02*
X3168203D01*
G01Y133484D02*
X3168063D01*
G01X3165887Y140719D02*
G03X3160987I-2450J-4085D01*
G01X3156941Y148897D02*
X3155563D01*
G01X3161665D02*
X3160287D01*
G01X3166389D02*
X3165011D01*
G01X3156941Y147519D02*
X3155563D01*
G01X3161665D02*
X3160287D01*
G01X3166389D02*
X3165011D01*
G01X3156941Y146535D02*
X3155563D01*
G01X3161665D02*
X3160287D01*
G01X3166389D02*
X3165011D01*
G01X3156941Y139463D02*
X3155563D01*
G01X3161665D02*
X3160287D01*
G01X3166389D02*
X3165011D01*
G01X3157610Y162618D02*
G03I-1181J0D01*
G01X3165602D02*
G03I-1181J0D01*
G01X3166574D02*
G03I-2153J0D01*
G01X3158582D02*
G03I-2153J0D01*
G01X3165287Y171304D02*
Y161929D01*
G01X3163515D02*
Y171304D01*
G01X3157295D02*
Y161929D01*
G01X3155523D02*
Y171304D01*
G01X3163515Y164291D02*
X3165287D01*
G01X3155523D02*
X3157295D01*
G01Y163307D02*
X3155523D01*
G01X3165287D02*
X3163515D01*
G01X3157295Y161929D02*
X3155523D01*
G01X3165287D02*
X3163515D01*
G01X3162578Y172618D02*
G03I-2153J0D01*
G01X3170032Y174043D02*
G03Y171193I-1615J-1425D01*
G01X3166074Y171304D02*
Y169926D01*
G01X3165582Y171304D02*
Y169926D01*
G01X3165189Y171304D02*
Y169926D01*
G01X3164893Y171304D02*
Y169926D01*
G01X3163909Y171304D02*
Y169926D01*
G01X3163614D02*
Y171304D01*
G01X3163220Y169926D02*
Y171304D01*
G01X3162728Y169926D02*
Y171304D01*
G01X3158082D02*
Y169926D01*
G01X3157590Y171304D02*
Y169926D01*
G01X3157196Y171304D02*
Y169926D01*
G01X3156901Y171304D02*
Y169926D01*
G01X3155917Y171304D02*
Y169926D01*
G01X3155622D02*
Y171304D01*
G01X3155228Y169926D02*
Y171304D01*
G01X3154736Y169926D02*
Y171304D01*
G01X3158082D02*
X3154736D01*
G01X3166074D02*
X3162728D01*
G01X3158082Y169926D02*
X3154736D01*
G01X3166074D02*
X3162728D01*
G01X3163515Y168941D02*
X3165287D01*
G01X3155523D02*
X3157295D01*
G01X3168586Y161106D02*
X3168048Y160465D01*
G01Y161198D02*
X3168586Y161839D01*
G01D02*
Y161106D01*
G01X3168048Y164771D02*
Y161198D01*
G01X3167510Y160465D02*
Y164771D01*
G01D02*
X3168048D01*
G01Y160465D02*
X3167510D01*
G01X3161606Y172618D02*
G03I-1181J0D01*
G01X3161178Y173586D02*
X3160952Y173398D01*
G01X3161178Y174715D02*
X3160952Y174527D01*
G01X3162098Y171929D02*
Y173307D01*
G01X3161606D02*
Y171929D01*
G01X3161311Y173307D02*
Y171929D01*
G01X3161212Y174847D02*
Y173650D01*
G01X3161178Y174715D02*
Y173586D01*
G01X3161114Y171929D02*
Y173307D01*
G01X3161015Y173831D02*
Y174959D01*
G01X3160952Y174527D02*
Y173398D01*
G01X3160917Y174463D02*
Y171929D01*
G01X3159933D02*
Y174463D01*
G01X3159898Y173398D02*
Y174527D01*
G01X3159834Y174959D02*
Y173831D01*
G01X3159736Y173307D02*
Y171929D01*
G01X3159672Y173586D02*
Y174715D01*
G01X3159637Y174847D02*
Y173650D01*
G01X3159539Y173307D02*
Y171929D01*
G01X3159244Y173307D02*
Y171929D01*
G01X3158752Y173307D02*
Y171929D01*
G01X3154106D02*
Y173307D01*
G01X3153614D02*
Y171929D01*
G01X3153319Y173307D02*
Y171929D01*
G01X3159898Y174527D02*
X3159672Y174715D01*
G01X3159898Y173398D02*
X3159672Y173586D01*
G01X3159834Y174959D02*
X3161015D01*
G01Y173831D02*
X3159834D01*
G01X3158752Y173307D02*
X3162098D01*
G01X3159933Y172178D02*
X3160917D01*
G01X3158752Y171929D02*
X3162098D01*
G01X3169598Y172618D02*
G03I-1181J0D01*
G01X3169170Y173586D02*
X3168944Y173398D01*
G01X3169170Y174715D02*
X3168944Y174527D01*
G01X3169598Y173307D02*
Y171929D01*
G01X3169303Y173307D02*
Y171929D01*
G01X3169204Y174847D02*
Y173650D01*
G01X3169170Y174715D02*
Y173586D01*
G01X3169106Y171929D02*
Y173307D01*
G01X3169007Y173831D02*
Y174959D01*
G01X3168944Y174527D02*
Y173398D01*
G01X3168909Y174463D02*
Y171929D01*
G01X3167925D02*
Y174463D01*
G01X3167890Y173398D02*
Y174527D01*
G01X3167826Y174959D02*
Y173831D01*
G01X3167728Y173307D02*
Y171929D01*
G01X3167664Y173586D02*
Y174715D01*
G01X3167630Y174847D02*
Y173650D01*
G01X3167531Y173307D02*
Y171929D01*
G01X3167236Y173307D02*
Y171929D01*
G01X3166744Y173307D02*
Y171929D01*
G01X3167890Y174527D02*
X3167664Y174715D01*
G01X3167890Y173398D02*
X3167664Y173586D01*
G01X3167826Y174959D02*
X3169007D01*
G01Y173831D02*
X3167826D01*
G01X3166744Y173307D02*
X3170090D01*
G01X3167925Y172178D02*
X3168909D01*
G01X3166744Y171929D02*
X3170090D01*
G01X3164646Y385582D02*
X3164641Y383795D01*
G01X3164632Y384063D02*
X3164636Y385850D01*
G01X3156772Y385582D02*
X3156767Y383795D01*
G01X3156757Y384063D02*
X3156762Y385850D01*
G01X3164500Y383346D02*
Y382362D01*
G01X3163633Y383346D02*
Y382362D01*
G01X3156626Y383346D02*
Y382362D01*
G01X3155759Y383346D02*
Y382362D01*
G01X3163497Y385850D02*
X3163502Y384063D01*
G01X3163493Y383795D02*
X3163487Y385582D01*
G01X3155623Y385850D02*
X3155628Y384063D01*
G01X3155619Y383795D02*
X3155613Y385582D01*
G01X3163502Y384063D02*
X3164632D01*
G01X3155628D02*
X3156757D01*
G01X3156767Y383795D02*
X3155619D01*
G01X3164641D02*
X3163493D01*
G01X3156748Y383346D02*
X3155637D01*
G01X3164622D02*
X3163511D01*
G01Y382362D02*
X3164622D01*
G01X3155637D02*
X3156748D01*
G01X3164660Y392106D02*
X3164672Y392767D01*
G01X3164670Y393694D02*
X3164640Y392106D01*
G01X3160723D02*
X3160735Y392767D01*
G01X3160733Y393694D02*
X3160703Y392106D01*
G01X3156786D02*
X3156798Y392767D01*
G01X3156796Y393694D02*
X3156766Y392106D01*
G01X3163432D02*
X3163441Y392697D01*
G01X3163439Y393607D02*
X3163414Y392106D01*
G01X3159495D02*
X3159504Y392697D01*
G01X3159502Y393607D02*
X3159477Y392106D01*
G01X3155557D02*
X3155567Y392697D01*
G01X3155565Y393607D02*
X3155540Y392106D01*
G01X3159565Y389519D02*
X3159560Y387732D01*
G01X3159550Y388000D02*
X3159556Y389787D01*
G01X3164655Y386299D02*
Y387283D01*
G01X3163478D02*
Y386299D01*
G01X3160718Y387283D02*
Y386299D01*
G01X3160563Y391220D02*
Y390236D01*
G01X3159696Y391220D02*
Y390236D01*
G01X3159541Y386299D02*
Y387283D01*
G01X3156781Y386299D02*
Y387283D01*
G01X3155604D02*
Y386299D01*
G01X3160704Y389787D02*
X3160709Y388000D01*
G01X3160699Y387732D02*
X3160695Y389519D01*
G01X3164719Y392106D02*
X3164695Y393607D01*
G01X3164692Y392697D02*
X3164702Y392106D01*
G01X3160782D02*
X3160757Y393607D01*
G01X3160755Y392697D02*
X3160765Y392106D01*
G01X3156845D02*
X3156820Y393607D01*
G01X3156818Y392697D02*
X3156828Y392106D01*
G01X3163494D02*
X3163463Y393694D01*
G01X3163461Y392767D02*
X3163474Y392106D01*
G01X3159557D02*
X3159526Y393694D01*
G01X3159524Y392767D02*
X3159537Y392106D01*
G01X3155620D02*
X3155589Y393694D01*
G01X3155587Y392767D02*
X3155600Y392106D01*
G01X3163452Y393977D02*
X3164682D01*
G01X3159515D02*
X3160745D01*
G01X3155578D02*
X3156807D01*
G01X3163463Y393694D02*
X3164670D01*
G01X3159526D02*
X3160733D01*
G01X3155589D02*
X3156796D01*
G01X3156820Y393607D02*
X3155565D01*
G01X3160757D02*
X3159502D01*
G01X3164695D02*
X3163439D01*
G01X3163452Y392993D02*
X3164682D01*
G01X3159515D02*
X3160745D01*
G01X3155578D02*
X3156807D01*
G01X3156798Y392767D02*
X3155587D01*
G01X3160735D02*
X3159524D01*
G01X3164672D02*
X3163461D01*
G01X3163441Y392697D02*
X3164692D01*
G01X3159504D02*
X3160755D01*
G01X3155567D02*
X3156818D01*
G01X3160685Y391220D02*
X3159574D01*
G01Y390236D02*
X3160685D01*
G01X3159556Y389787D02*
X3160704D01*
G01X3160695Y389519D02*
X3159565D01*
G01X3160709Y388000D02*
X3159550D01*
G01X3159560Y387732D02*
X3160699D01*
G01X3163478Y387283D02*
X3164655D01*
G01X3159541D02*
X3160718D01*
G01X3155604D02*
X3156781D01*
G01Y386299D02*
X3155604D01*
G01X3160718D02*
X3159541D01*
G01X3164655D02*
X3163478D01*
G01X3156762Y385850D02*
X3155623D01*
G01X3164636D02*
X3163497D01*
G01X3163487Y385582D02*
X3164646D01*
G01X3155613D02*
X3156772D01*
G01X3163463Y397604D02*
X3163494Y399193D01*
G01X3163474D02*
X3163461Y398532D01*
G01X3159526Y397604D02*
X3159557Y399193D01*
G01X3159537D02*
X3159524Y398532D01*
G01X3155589Y397604D02*
X3155620Y399193D01*
G01X3155600D02*
X3155587Y398532D01*
G01X3164695Y397691D02*
X3164719Y399193D01*
G01X3164702D02*
X3164692Y398602D01*
G01X3160757Y397691D02*
X3160782Y399193D01*
G01X3160765D02*
X3160755Y398602D01*
G01X3156820Y397691D02*
X3156845Y399193D01*
G01X3156828D02*
X3156818Y398602D01*
G01X3160563Y401063D02*
Y400078D01*
G01X3159696D02*
Y401063D01*
G01X3163441Y398602D02*
X3163432Y399193D01*
G01X3163414D02*
X3163439Y397691D01*
G01X3159504Y398602D02*
X3159495Y399193D01*
G01X3159477D02*
X3159502Y397691D01*
G01X3155567Y398602D02*
X3155557Y399193D01*
G01X3155540D02*
X3155565Y397691D01*
G01X3164672Y398532D02*
X3164660Y399193D01*
G01X3164640D02*
X3164670Y397604D01*
G01X3160735Y398532D02*
X3160723Y399193D01*
G01X3160703D02*
X3160733Y397604D01*
G01X3156798Y398532D02*
X3156786Y399193D01*
G01X3156766D02*
X3156796Y397604D01*
G01X3160685Y401063D02*
X3159574D01*
G01X3160685Y400078D02*
X3159574D01*
G01X3156818Y398602D02*
X3155567D01*
G01X3160755D02*
X3159504D01*
G01X3164692D02*
X3163441D01*
G01X3163461Y398532D02*
X3164672D01*
G01X3159524D02*
X3160735D01*
G01X3155587D02*
X3156798D01*
G01X3156807Y398306D02*
X3155578D01*
G01X3160745D02*
X3159515D01*
G01X3164682D02*
X3163452D01*
G01X3163439Y397691D02*
X3164695D01*
G01X3159502D02*
X3160757D01*
G01X3155565D02*
X3156820D01*
G01X3156796Y397604D02*
X3155589D01*
G01X3160733D02*
X3159526D01*
G01X3164670D02*
X3163463D01*
G01X3156807Y397322D02*
X3155578D01*
G01X3160745D02*
X3159515D01*
G01X3164682D02*
X3163452D01*
G01X3168597Y392106D02*
X3168609Y392767D01*
G01X3168607Y393694D02*
X3168577Y392106D01*
G01X3167369D02*
X3167378Y392697D01*
G01X3167376Y393607D02*
X3167351Y392106D01*
G01X3167439Y389519D02*
X3167434Y387732D01*
G01X3167424Y388000D02*
X3167430Y389787D01*
G01X3168592Y387283D02*
Y386299D01*
G01X3168437Y391220D02*
Y390236D01*
G01X3167570Y391220D02*
Y390236D01*
G01X3167415Y386299D02*
Y387283D01*
G01X3168578Y389787D02*
X3168583Y388000D01*
G01X3168573Y387732D02*
X3168569Y389519D01*
G01X3168656Y392106D02*
X3168632Y393607D01*
G01X3168629Y392697D02*
X3168639Y392106D01*
G01X3167431D02*
X3167400Y393694D01*
G01X3167398Y392767D02*
X3167411Y392106D01*
G01X3167389Y393977D02*
X3168619D01*
G01X3167400Y393694D02*
X3168607D01*
G01X3168632Y393607D02*
X3167376D01*
G01X3167389Y392993D02*
X3168619D01*
G01X3168609Y392767D02*
X3167398D01*
G01X3167378Y392697D02*
X3168629D01*
G01X3168559Y391220D02*
X3167448D01*
G01Y390236D02*
X3168559D01*
G01X3167430Y389787D02*
X3168578D01*
G01X3168569Y389519D02*
X3167439D01*
G01X3168583Y388000D02*
X3167424D01*
G01X3167434Y387732D02*
X3168573D01*
G01X3167415Y387283D02*
X3168592D01*
G01Y386299D02*
X3167415D01*
G01X3167400Y397604D02*
X3167431Y399193D01*
G01X3167411D02*
X3167398Y398532D01*
G01X3168632Y397691D02*
X3168656Y399193D01*
G01X3168639D02*
X3168629Y398602D01*
G01X3168437Y401063D02*
Y400078D01*
G01X3167570D02*
Y401063D01*
G01X3167378Y398602D02*
X3167369Y399193D01*
G01X3167351D02*
X3167376Y397691D01*
G01X3168609Y398532D02*
X3168597Y399193D01*
G01X3168577D02*
X3168607Y397604D01*
G01X3168559Y401063D02*
X3167448D01*
G01X3168559Y400078D02*
X3167448D01*
G01X3168629Y398602D02*
X3167378D01*
G01X3167398Y398532D02*
X3168609D01*
G01X3168619Y398306D02*
X3167389D01*
G01X3167376Y397691D02*
X3168632D01*
G01X3168607Y397604D02*
X3167400D01*
G01X3168619Y397322D02*
X3167389D01*
G01X3156748Y408937D02*
X3155637D01*
G01X3164622D02*
X3163511D01*
G01X3156748Y407952D02*
X3155637D01*
G01X3164622D02*
X3163511D01*
G01X3163493Y407504D02*
X3164641D01*
G01X3155619D02*
X3156767D01*
G01X3156757Y407236D02*
X3155628D01*
G01X3164632D02*
X3163502D01*
G01X3156772Y405716D02*
X3155613D01*
G01X3164646D02*
X3163487D01*
G01X3163497Y405449D02*
X3164636D01*
G01X3155623D02*
X3156762D01*
G01X3156781Y405000D02*
X3155604D01*
G01X3160718D02*
X3159541D01*
G01X3164655D02*
X3163478D01*
G01X3156781Y404015D02*
X3155604D01*
G01X3160718D02*
X3159541D01*
G01X3164655D02*
X3163478D01*
G01X3160699Y403567D02*
X3159560D01*
G01X3159550Y403299D02*
X3160709D01*
G01X3163502Y407236D02*
X3163497Y405449D01*
G01X3163487Y405716D02*
X3163493Y407504D01*
G01X3160709Y403299D02*
X3160704Y401512D01*
G01X3160695Y401779D02*
X3160699Y403567D01*
G01X3155628Y407236D02*
X3155623Y405449D01*
G01X3155613Y405716D02*
X3155619Y407504D01*
G01X3164655Y404015D02*
Y405000D01*
G01X3164500Y408937D02*
Y407952D01*
G01X3163633D02*
Y408937D01*
G01X3163478Y405000D02*
Y404015D01*
G01X3162846Y415728D02*
Y410118D01*
G01X3160718Y405000D02*
Y404015D01*
G01X3159541D02*
Y405000D01*
G01X3157846Y415728D02*
Y410118D01*
G01X3156781Y405000D02*
Y404015D01*
G01X3156626Y408937D02*
Y407952D01*
G01X3155759D02*
Y408937D01*
G01X3155604Y404015D02*
Y405000D01*
G01X3164641Y407504D02*
X3164646Y405716D01*
G01X3164636Y405449D02*
X3164632Y407236D01*
G01X3159560Y403567D02*
X3159565Y401779D01*
G01X3159556Y401512D02*
X3159550Y403299D01*
G01X3156767Y407504D02*
X3156772Y405716D01*
G01X3156762Y405449D02*
X3156757Y407236D01*
G01X3159565Y401779D02*
X3160695D01*
G01X3160704Y401512D02*
X3159556D01*
G01X3178752Y415728D02*
X3162846D01*
G01X3168592Y405000D02*
X3167415D01*
G01X3168592Y404015D02*
X3167415D01*
G01X3168573Y403567D02*
X3167434D01*
G01X3167424Y403299D02*
X3168583D01*
G01D02*
X3168578Y401512D01*
G01X3168569Y401779D02*
X3168573Y403567D01*
G01X3168592Y405000D02*
Y404015D01*
G01X3167415D02*
Y405000D01*
G01X3167434Y403567D02*
X3167439Y401779D01*
G01X3167430Y401512D02*
X3167424Y403299D01*
G01X3167439Y401779D02*
X3168569D01*
G01X3168578Y401512D02*
X3167430D01*
G01X3157694Y448208D02*
X3158452Y448352D01*
X3159318Y448785D01*
X3159859Y449507D01*
X3160076Y450518D01*
X3159859Y451528D01*
X3159210Y452394D01*
X3158235Y452827D01*
X3157153D01*
X3156503Y453116D01*
X3155962Y453838D01*
X3155745Y454848D01*
X3156070Y455859D01*
X3156828Y456580D01*
X3157694Y456869D01*
X3158560Y456580D01*
X3159318Y455859D01*
X3159643Y454848D01*
X3159426Y453838D01*
X3158885Y453116D01*
X3158235Y452827D01*
X3157153D01*
X3156178Y452394D01*
X3155529Y451528D01*
X3155312Y450518D01*
X3155529Y449507D01*
X3156070Y448785D01*
X3156936Y448352D01*
X3157694Y448208D01*
G01X3164514Y449218D02*
X3165272Y448497D01*
X3166138Y448208D01*
X3167005Y448497D01*
X3167762Y449363D01*
X3168304Y450662D01*
X3168520Y451961D01*
Y453549D01*
X3168304Y454848D01*
X3167762Y456003D01*
X3167113Y456580D01*
X3166355Y456869D01*
X3165489Y456580D01*
X3164839Y456003D01*
X3164406Y455137D01*
X3164190Y453982D01*
X3164406Y452972D01*
X3164948Y451961D01*
X3165597Y451384D01*
X3166355Y451239D01*
X3167221Y451528D01*
X3167871Y452250D01*
X3168520Y453549D01*
G01X3175016Y447919D02*
X3174799Y448064D01*
Y448352D01*
X3175016Y448497D01*
X3175233Y448352D01*
Y448064D01*
X3175016Y447919D01*
G01X3183677Y448208D02*
X3184435Y448352D01*
X3185301Y448785D01*
X3185842Y449507D01*
X3186059Y450518D01*
X3185842Y451528D01*
X3185193Y452394D01*
X3184218Y452827D01*
X3183136D01*
X3182486Y453116D01*
X3181945Y453838D01*
X3181728Y454848D01*
X3182053Y455859D01*
X3182811Y456580D01*
X3183677Y456869D01*
X3184543Y456580D01*
X3185301Y455859D01*
X3185626Y454848D01*
X3185409Y453838D01*
X3184868Y453116D01*
X3184218Y452827D01*
X3183136D01*
X3182161Y452394D01*
X3181512Y451528D01*
X3181295Y450518D01*
X3181512Y449507D01*
X3182053Y448785D01*
X3182919Y448352D01*
X3183677Y448208D01*
G01X3192338Y456869D02*
X3191472Y456580D01*
X3190822Y455859D01*
X3190389Y454993D01*
X3190064Y453838D01*
X3189956Y452538D01*
X3190064Y451239D01*
X3190389Y450084D01*
X3190822Y449218D01*
X3191472Y448497D01*
X3192338Y448208D01*
X3193204Y448497D01*
X3193854Y449218D01*
X3194287Y450084D01*
X3194612Y451239D01*
X3194720Y452538D01*
X3194612Y453838D01*
X3194287Y454993D01*
X3193854Y455859D01*
X3193204Y456580D01*
X3192338Y456869D01*
G01X3156793Y457815D02*
X3155563D01*
G01X3159992D02*
X3158761D01*
G01X3163929D02*
X3162698D01*
G01X3163929Y463846D02*
Y457815D01*
G01X3162698D02*
Y463846D01*
G01X3159992Y464097D02*
Y457815D01*
G01X3158761D02*
Y465856D01*
G01X3156793Y463846D02*
Y457815D01*
G01X3155563D02*
Y463846D01*
G01X3164421Y465605D02*
X3165159Y465856D01*
G01X3161222Y464851D02*
X3160484Y464600D01*
G01Y465605D02*
X3161222Y465856D01*
G01X3153348Y465605D02*
X3154086Y465856D01*
G01X3164913Y464851D02*
X3164421Y464600D01*
G01X3153840Y464851D02*
X3153348Y464600D01*
G01X3165159Y465856D02*
X3166143D01*
G01X3158761D02*
X3159992D01*
G01X3161222D02*
X3162206D01*
G01X3154086D02*
X3155070D01*
G01X3154578Y464851D02*
X3153840D01*
G01X3161714D02*
X3161222D01*
G01X3165651D02*
X3164913D01*
G01X3164421Y464600D02*
X3164175Y464348D01*
G01X3163683Y464851D02*
X3164421Y465605D01*
G01X3160484Y464600D02*
X3159992Y464097D01*
G01Y465102D02*
X3160484Y465605D01*
G01X3164175Y464348D02*
X3163929Y463846D01*
G01X3156301Y465102D02*
X3156793Y463846D01*
G01X3166635D02*
X3166389Y464348D01*
G01X3162698Y463846D02*
X3162452Y464348D01*
G01X3155563Y463846D02*
X3155317Y464348D01*
G01X3166389D02*
X3166143Y464600D01*
G01X3162945Y465605D02*
X3163683Y464851D01*
G01X3162452Y464348D02*
X3162206Y464600D01*
G01X3155809Y465605D02*
X3156301Y465102D01*
G01X3155317Y464348D02*
X3155070Y464600D01*
G01X3166143D02*
X3165651Y464851D01*
G01X3162206Y464600D02*
X3161714Y464851D01*
G01X3155070Y464600D02*
X3154578Y464851D01*
G01X3166143Y465856D02*
X3166882Y465605D01*
G01X3162206Y465856D02*
X3162945Y465605D01*
G01X3155070Y465856D02*
X3155809Y465605D01*
G01X3159992Y465856D02*
Y465102D01*
G01X3167866Y457815D02*
X3166635D01*
G01X3167866Y463846D02*
Y457815D01*
G01X3166635D02*
Y463846D01*
G01X3167374Y465102D02*
X3167866Y463846D01*
G01X3166882Y465605D02*
X3167374Y465102D01*
G01X3181484Y-682988D02*
X3177674D01*
G01D02*
Y-664311D01*
G01X3181484D02*
Y-682988D01*
G01X3176912Y-662755D02*
X3176150Y-661977D01*
G01D02*
X3174626Y-661199D01*
G01X3177674Y-664311D02*
X3176912Y-662755D01*
G01X3173102Y-661199D02*
X3170816Y-661977D01*
G01X3176150Y-658086D02*
X3178436Y-658864D01*
G01X3173102Y-658086D02*
X3176150D01*
G01X3174626Y-661199D02*
X3173102D01*
G01X3178436Y-658864D02*
X3180722Y-661199D01*
G01X3170816Y-658864D02*
X3173102Y-658086D01*
G01X3182246Y-662755D02*
X3181484Y-664311D01*
G01X3183008Y-661977D02*
X3182246Y-662755D01*
G01X3184532Y-661199D02*
X3183008Y-661977D01*
G01X3185294Y-658086D02*
X3188342D01*
G01X3186818Y-661199D02*
X3184532D01*
G01X3180722D02*
X3183008Y-658864D01*
G01D02*
X3185294Y-658086D01*
G01X3177324Y85442D02*
X3177213Y85449D01*
G01X3171901Y86200D02*
G03X3171114Y85413I0J-787D01*
G01X3169732Y86064D02*
G03X3170507Y85413I775J136D01*
G01X3176822Y86200D02*
G03X3177610Y86988I0J788D01*
G01X3173279Y88956D02*
G03X3174067Y88169I787J0D01*
G01X3177610Y85413D02*
G03X3178397Y86200I0J787D01*
G01X3171226Y85670D02*
G03X3171984Y84854I787J-29D01*
G01X3176508Y84685D02*
G03X3177324Y85442I29J787D01*
G01X3177610Y84626D02*
G03X3179185Y86200I0J1575D01*
G01X3178004Y86240D02*
X3177216Y85452D01*
G01X3177324Y85442D02*
X3178397Y114110D01*
G01X3172437Y118030D02*
X3171226Y85670D01*
G01X3179185Y86200D02*
Y178102D01*
G01X3178397D02*
Y86200D01*
G01X3178004Y86240D02*
Y179114D01*
G01X3177610Y86988D02*
Y177736D01*
G01X3177216Y179676D02*
Y85452D01*
G01X3173279Y90003D02*
Y88956D01*
G01X3172954Y88405D02*
Y152578D01*
G01X3171901Y84626D02*
Y85124D01*
G01X3171212Y105137D02*
Y85452D01*
G01X3171114Y85413D02*
Y84626D01*
G01X3170901Y85413D02*
Y84626D01*
G01X3170507Y85413D02*
Y84626D01*
G01X3169933Y103011D02*
Y86240D01*
G01X3169834Y85413D02*
Y84626D01*
G01X3170720Y85452D02*
X3169933Y86240D01*
G01X3171226Y85670D02*
X3177324Y85442D01*
G01X3177108Y84929D02*
X3171901Y85124D01*
G01X3176508Y84685D02*
X3171984Y84854D01*
G01X3174067Y88169D02*
X3179185D01*
G01Y87381D02*
X3178397D01*
G01Y86988D02*
X3179185D01*
G01Y86200D02*
X3178397D01*
G01X3176006Y101771D02*
G03I-1969J0D01*
G01X3171773Y98838D02*
X3172757Y99822D01*
G01X3177049Y90003D02*
Y96231D01*
G01X3176301Y98838D02*
Y118130D01*
G01X3175317Y123444D02*
Y99822D01*
G01X3172757D02*
Y123444D01*
G01X3171982Y96231D02*
Y90003D01*
G01X3171773Y98838D02*
Y118130D01*
G01X3176301Y98838D02*
X3175317Y99822D01*
G01D02*
X3172757D01*
G01X3171773Y98838D02*
X3176301D01*
G01X3179185Y96830D02*
X3178397D01*
G01X3177049Y96231D02*
X3171982D01*
G01X3179185Y96043D02*
X3177049D01*
G01X3171982Y90003D02*
X3177049D01*
G01X3175317Y104153D02*
X3176301Y105137D01*
G01X3177777Y105433D02*
Y117834D01*
G01X3175120Y100354D02*
Y103897D01*
G01X3174923Y108681D02*
Y100649D01*
G01X3173151D02*
Y108681D01*
G01X3170622Y131909D02*
Y103759D01*
G01X3170326Y104350D02*
Y132337D01*
G01X3170297Y117834D02*
Y105433D01*
G01X3170130Y105137D02*
Y118130D01*
G01X3171773Y105137D02*
X3172757Y104153D01*
G01X3177777Y105433D02*
X3170297D01*
G01X3178004Y105137D02*
X3176301D01*
G01X3172954Y103897D02*
X3175120D01*
G01X3173151Y103405D02*
X3174923D01*
G01X3175120Y102913D02*
X3172954D01*
G01X3174923Y102618D02*
X3173151D01*
G01Y101633D02*
X3174923D01*
G01Y100649D02*
X3173151D01*
G01X3175120Y100354D02*
X3172954D01*
G01X3176006Y111771D02*
G03I-1969J0D01*
G01X3175120Y112913D02*
Y110354D01*
G01X3174923Y112618D02*
Y110649D01*
G01X3173151Y112618D02*
Y110649D01*
G01X3172091Y108784D02*
X3178189Y108556D01*
G01X3175120Y112913D02*
X3172954D01*
G01X3174923Y112618D02*
X3173151D01*
G01X3174923Y110649D02*
X3173151D01*
G01X3175120Y110354D02*
X3172954D01*
G01X3174923Y108681D02*
X3173151D01*
G01X3174923Y106712D02*
X3173151D01*
G01Y106667D02*
X3174923D01*
G01X3173151Y105728D02*
X3174923D01*
G01X3178397Y117806D02*
X3177777Y117832D01*
G01X3176006Y121634D02*
G03I-1969J0D01*
G01X3171773Y118130D02*
X3172757Y119114D01*
G01X3176301D02*
Y124429D01*
G01X3175120Y119370D02*
Y122913D01*
G01X3171773Y124429D02*
Y119114D01*
G01X3171212D02*
Y118130D01*
G01X3175317Y119114D02*
X3176301Y118130D01*
G01X3177652Y117834D02*
X3172437Y118030D01*
G01X3175120Y120354D02*
X3172954D01*
G01X3175120Y119370D02*
X3172954D01*
G01X3175317Y119114D02*
X3178004D01*
G01X3172757D02*
X3171212D01*
G01X3176301Y118130D02*
X3178004D01*
G01X3170297Y117834D02*
X3177777D01*
G01X3175317Y123444D02*
X3176301Y124429D01*
G01X3174559Y177972D02*
Y131909D01*
G01X3174362Y132696D02*
Y140570D01*
G01X3172795Y132337D02*
Y137368D01*
G01X3171901Y132337D02*
Y131909D01*
G01X3171773Y124429D02*
X3172757Y123444D01*
G01X3179185Y132998D02*
X3178397D01*
G01X3179185Y132854D02*
X3178397D01*
G01X3174362Y132696D02*
X3172795D01*
G01X3178397Y132265D02*
X3179185D01*
G01Y132192D02*
X3178397D01*
G01Y132067D02*
X3179185D01*
G01X3178397Y131458D02*
X3179185D01*
G01X3178397Y127761D02*
X3179185D01*
G01X3178397Y126535D02*
X3179185D01*
G01Y125802D02*
X3178397D01*
G01X3171773Y124429D02*
X3176301D01*
G01X3175317Y123444D02*
X3172757D01*
G01X3175120Y122913D02*
X3172954D01*
G01X3182118Y136634D02*
G03I-3091J0D01*
G01X3171901Y177972D02*
Y137368D01*
G01X3171606D02*
Y140570D01*
G01X3171311Y138479D02*
Y137368D01*
G01X3171258D02*
Y138479D01*
G01X3171212D02*
Y137368D01*
G01X3171187Y138479D02*
Y137368D01*
G01X3171114D02*
Y148897D01*
G01X3170970Y137368D02*
Y138479D01*
G01X3170943D02*
Y137368D01*
G01X3170917Y138479D02*
Y137368D01*
G01X3169933Y138479D02*
Y137368D01*
G01X3169907D02*
Y138479D01*
G01X3169880D02*
Y137368D01*
G01X3169736D02*
Y148897D01*
G01X3179185Y137836D02*
X3178397D01*
G01Y135353D02*
X3179185D01*
G01X3178397Y134429D02*
X3179185D01*
G01X3174362Y133484D02*
X3172795D01*
G01X3173279Y144665D02*
G03X3174067Y143878I787J0D01*
G01X3176822Y149429D02*
Y177972D01*
G01X3173279Y150964D02*
Y144665D01*
G01X3178004Y149429D02*
X3176822D01*
G01X3171114Y148897D02*
X3169736D01*
G01X3171114Y147519D02*
X3169736D01*
G01X3171114Y146535D02*
X3169736D01*
G01X3174067Y143878D02*
X3179185D01*
G01Y143090D02*
X3178397D01*
G01Y142303D02*
X3179185D01*
G01Y141122D02*
X3178397D01*
G01Y140334D02*
X3179185D01*
G01X3171114Y139463D02*
X3169736D01*
G01X3179185Y138759D02*
X3178397D01*
G01X3174067Y151752D02*
G03X3173279Y150964I0J-788D01*
G01X3179185Y153523D02*
X3177216D01*
G01X3179185Y153326D02*
X3178397D01*
G01X3178004Y152578D02*
X3172954D01*
G01X3178397Y152539D02*
X3179185D01*
G01Y151752D02*
X3174067D01*
G01X3178004Y165974D02*
G03X3178397Y165292I787J0D01*
G01Y163928D02*
G03X3178004Y164610I-787J1D01*
G01X3177216Y165974D02*
G03X3178004Y164610I1575J0D01*
G01X3179185Y163928D02*
G03X3178397Y165292I-1575J0D01*
G01X3177267Y161004D02*
Y161200D01*
G01X3174362Y177185D02*
Y159862D01*
G01X3171606Y177185D02*
Y159862D01*
G01X3170031Y171193D02*
Y159862D01*
G01X3178004Y161437D02*
X3177216Y162224D01*
G01X3179185Y165763D02*
X3178397D01*
G01Y165199D02*
X3179185D01*
G01X3177216Y162224D02*
X3176822D01*
G01X3178397Y161200D02*
X3179185D01*
G01X3177216D02*
X3178004D01*
G01X3179185Y161004D02*
X3177267D01*
G01X3178004Y171240D02*
X3177216D01*
G01X3179185Y170818D02*
X3178397D01*
G01X3179185Y170228D02*
X3178397D01*
G01Y166331D02*
X3179185D01*
G01Y166094D02*
X3178397D01*
G01Y178102D02*
G03X3177610Y178889I-787J0D01*
G01X3170228Y177933D02*
G03X3171234Y178495I0J1181D01*
G01X3179185Y178102D02*
G03X3177610Y179676I-1575J-1D01*
G01X3178004Y175177D02*
X3177295Y174941D01*
G01X3178215Y178606D02*
X3178819Y179110D01*
G01X3177610Y177578D02*
X3177216Y177185D01*
G01X3171361Y178774D02*
Y179331D01*
G01X3171234Y179676D02*
Y178889D01*
G01X3170228Y179676D02*
Y178889D01*
G01X3170090Y171929D02*
Y173307D01*
G01X3170031Y177185D02*
Y174043D01*
G01X3179185Y171633D02*
X3178004Y175177D01*
G01X3177216D02*
X3178397Y171633D01*
G01X3178004Y177185D02*
X3177216Y177972D01*
G01X3178004Y179114D02*
X3177216D01*
G01Y178495D02*
X3171234D01*
G01X3177216Y178326D02*
X3178004D01*
G01X3179185Y178102D02*
X3178397D01*
G01X3178819Y177736D02*
X3177216D01*
G01X3178397Y177244D02*
X3179185D01*
G01X3177216Y175177D02*
X3178004D01*
G01X3179185Y174952D02*
X3178397D01*
G01X3179185Y174361D02*
X3178397D01*
G01X3179185Y171633D02*
X3178397D01*
G01X3180394Y385582D02*
X3180389Y383795D01*
G01X3180380Y384063D02*
X3180384Y385850D01*
G01X3172520Y385582D02*
X3172515Y383795D01*
G01X3172506Y384063D02*
X3172510Y385850D01*
G01X3180248Y383346D02*
Y382362D01*
G01X3179382Y383346D02*
Y382362D01*
G01X3172374Y383346D02*
Y382362D01*
G01X3171507Y383346D02*
Y382362D01*
G01X3179245Y385850D02*
X3179250Y384063D01*
G01X3179241Y383795D02*
X3179235Y385582D01*
G01X3171371Y385850D02*
X3171376Y384063D01*
G01X3171367Y383795D02*
X3171361Y385582D01*
G01X3179250Y384063D02*
X3180380D01*
G01X3171376D02*
X3172506D01*
G01X3172515Y383795D02*
X3171367D01*
G01X3180389D02*
X3179241D01*
G01X3172496Y383346D02*
X3171385D01*
G01X3180370D02*
X3179259D01*
G01Y382362D02*
X3180370D01*
G01X3171385D02*
X3172496D01*
G01X3180408Y392106D02*
X3180420Y392767D01*
G01X3180419Y393694D02*
X3180388Y392106D01*
G01X3176471D02*
X3176483Y392767D01*
G01X3176482Y393694D02*
X3176451Y392106D01*
G01X3172534D02*
X3172546Y392767D01*
G01X3172545Y393694D02*
X3172514Y392106D01*
G01X3179180D02*
X3179189Y392697D01*
G01X3179187Y393607D02*
X3179162Y392106D01*
G01X3175243D02*
X3175252Y392697D01*
G01X3175250Y393607D02*
X3175225Y392106D01*
G01X3171306D02*
X3171315Y392697D01*
G01X3171313Y393607D02*
X3171288Y392106D01*
G01X3175313Y389519D02*
X3175308Y387732D01*
G01X3175298Y388000D02*
X3175304Y389787D01*
G01X3180403Y386299D02*
Y387283D01*
G01X3179226D02*
Y386299D01*
G01X3176466Y387283D02*
Y386299D01*
G01X3176311Y391220D02*
Y390236D01*
G01X3175445Y391220D02*
Y390236D01*
G01X3175289Y386299D02*
Y387283D01*
G01X3172529Y386299D02*
Y387283D01*
G01X3171352D02*
Y386299D01*
G01X3176452Y389787D02*
X3176457Y388000D01*
G01X3176447Y387732D02*
X3176443Y389519D01*
G01X3180467Y392106D02*
X3180443Y393607D01*
G01X3180440Y392697D02*
X3180450Y392106D01*
G01X3176530D02*
X3176506Y393607D01*
G01X3176503Y392697D02*
X3176513Y392106D01*
G01X3179242D02*
X3179211Y393694D01*
G01X3179209Y392767D02*
X3179222Y392106D01*
G01X3175305D02*
X3175274Y393694D01*
G01X3175272Y392767D02*
X3175285Y392106D01*
G01X3172593D02*
X3172569Y393607D01*
G01X3172566Y392697D02*
X3172576Y392106D01*
G01X3171368D02*
X3171337Y393694D01*
G01X3171335Y392767D02*
X3171348Y392106D01*
G01X3179200Y393977D02*
X3180430D01*
G01X3175263D02*
X3176493D01*
G01X3171326D02*
X3172556D01*
G01X3179211Y393694D02*
X3180419D01*
G01X3175274D02*
X3176482D01*
G01X3171337D02*
X3172545D01*
G01X3176506Y393607D02*
X3175250D01*
G01X3172569D02*
X3171313D01*
G01X3180443D02*
X3179187D01*
G01X3179200Y392993D02*
X3180430D01*
G01X3175263D02*
X3176493D01*
G01X3171326D02*
X3172556D01*
G01X3176483Y392767D02*
X3175272D01*
G01X3172546D02*
X3171335D01*
G01X3180420D02*
X3179209D01*
G01X3179189Y392697D02*
X3180440D01*
G01X3175252D02*
X3176503D01*
G01X3171315D02*
X3172566D01*
G01X3176433Y391220D02*
X3175322D01*
G01Y390236D02*
X3176433D01*
G01X3175304Y389787D02*
X3176452D01*
G01X3176443Y389519D02*
X3175313D01*
G01X3176457Y388000D02*
X3175298D01*
G01X3175308Y387732D02*
X3176447D01*
G01X3179226Y387283D02*
X3180403D01*
G01X3171352D02*
X3172529D01*
G01X3175289D02*
X3176466D01*
G01X3172529Y386299D02*
X3171352D01*
G01X3176466D02*
X3175289D01*
G01X3180403D02*
X3179226D01*
G01X3172510Y385850D02*
X3171371D01*
G01X3180384D02*
X3179245D01*
G01X3179235Y385582D02*
X3180394D01*
G01X3171361D02*
X3172520D01*
G01X3179211Y397604D02*
X3179242Y399193D01*
G01X3179222D02*
X3179209Y398532D01*
G01X3175274Y397604D02*
X3175305Y399193D01*
G01X3175285D02*
X3175272Y398532D01*
G01X3171337Y397604D02*
X3171368Y399193D01*
G01X3171348D02*
X3171335Y398532D01*
G01X3180443Y397691D02*
X3180467Y399193D01*
G01X3180450D02*
X3180440Y398602D01*
G01X3176506Y397691D02*
X3176530Y399193D01*
G01X3176513D02*
X3176503Y398602D01*
G01X3172569Y397691D02*
X3172593Y399193D01*
G01X3172576D02*
X3172566Y398602D01*
G01X3176311Y401063D02*
Y400078D01*
G01X3175445D02*
Y401063D01*
G01X3179189Y398602D02*
X3179180Y399193D01*
G01X3179162D02*
X3179187Y397691D01*
G01X3175252Y398602D02*
X3175243Y399193D01*
G01X3175225D02*
X3175250Y397691D01*
G01X3180420Y398532D02*
X3180408Y399193D01*
G01X3180388D02*
X3180419Y397604D01*
G01X3176483Y398532D02*
X3176471Y399193D01*
G01X3176451D02*
X3176482Y397604D01*
G01X3171315Y398602D02*
X3171306Y399193D01*
G01X3171288D02*
X3171313Y397691D01*
G01X3172546Y398532D02*
X3172534Y399193D01*
G01X3172514D02*
X3172545Y397604D01*
G01X3176433Y401063D02*
X3175322D01*
G01X3176433Y400078D02*
X3175322D01*
G01X3176503Y398602D02*
X3175252D01*
G01X3172566D02*
X3171315D01*
G01X3180440D02*
X3179189D01*
G01X3179209Y398532D02*
X3180420D01*
G01X3175272D02*
X3176483D01*
G01X3171335D02*
X3172546D01*
G01X3176493Y398306D02*
X3175263D01*
G01X3172556D02*
X3171326D01*
G01X3180430D02*
X3179200D01*
G01X3179187Y397691D02*
X3180443D01*
G01X3175250D02*
X3176506D01*
G01X3171313D02*
X3172569D01*
G01X3176482Y397604D02*
X3175274D01*
G01X3172545D02*
X3171337D01*
G01X3180419D02*
X3179211D01*
G01X3176493Y397322D02*
X3175263D01*
G01X3172556D02*
X3171326D01*
G01X3180430D02*
X3179200D01*
G01X3184345Y392106D02*
X3184357Y392767D01*
G01X3184356Y393694D02*
X3184325Y392106D01*
G01X3183117D02*
X3183126Y392697D01*
G01X3183124Y393607D02*
X3183099Y392106D01*
G01X3183187Y389519D02*
X3183182Y387732D01*
G01X3183172Y388000D02*
X3183178Y389787D01*
G01X3184340Y387283D02*
Y386299D01*
G01X3184185Y391220D02*
Y390236D01*
G01X3183319Y391220D02*
Y390236D01*
G01X3183163Y386299D02*
Y387283D01*
G01X3184326Y389787D02*
X3184331Y388000D01*
G01X3184321Y387732D02*
X3184317Y389519D01*
G01X3184404Y392106D02*
X3184380Y393607D01*
G01X3184377Y392697D02*
X3184387Y392106D01*
G01X3183179D02*
X3183148Y393694D01*
G01X3183146Y392767D02*
X3183159Y392106D01*
G01X3183137Y393977D02*
X3184367D01*
G01X3183148Y393694D02*
X3184356D01*
G01X3184380Y393607D02*
X3183124D01*
G01X3183137Y392993D02*
X3184367D01*
G01X3184357Y392767D02*
X3183146D01*
G01X3183126Y392697D02*
X3184377D01*
G01X3184307Y391220D02*
X3183196D01*
G01Y390236D02*
X3184307D01*
G01X3183178Y389787D02*
X3184326D01*
G01X3184317Y389519D02*
X3183187D01*
G01X3184331Y388000D02*
X3183172D01*
G01X3183182Y387732D02*
X3184321D01*
G01X3183163Y387283D02*
X3184340D01*
G01Y386299D02*
X3183163D01*
G01X3183148Y397604D02*
X3183179Y399193D01*
G01X3183159D02*
X3183146Y398532D01*
G01X3184380Y397691D02*
X3184404Y399193D01*
G01X3184387D02*
X3184377Y398602D01*
G01X3184185Y401063D02*
Y400078D01*
G01X3183319D02*
Y401063D01*
G01X3183126Y398602D02*
X3183117Y399193D01*
G01X3183099D02*
X3183124Y397691D01*
G01X3184357Y398532D02*
X3184345Y399193D01*
G01X3184325D02*
X3184356Y397604D01*
G01X3184307Y401063D02*
X3183196D01*
G01X3184307Y400078D02*
X3183196D01*
G01X3184377Y398602D02*
X3183126D01*
G01X3183146Y398532D02*
X3184357D01*
G01X3184367Y398306D02*
X3183137D01*
G01X3183124Y397691D02*
X3184380D01*
G01X3184356Y397604D02*
X3183148D01*
G01X3184367Y397322D02*
X3183137D01*
G01X3179250Y407236D02*
X3179245Y405449D01*
G01X3179235Y405716D02*
X3179241Y407504D01*
G01X3176457Y403299D02*
X3176452Y401512D01*
G01X3176443Y401779D02*
X3176447Y403567D01*
G01X3171376Y407236D02*
X3171371Y405449D01*
G01X3171361Y405716D02*
X3171367Y407504D01*
G01X3180403Y404015D02*
Y405000D01*
G01X3180248Y408937D02*
Y407952D01*
G01X3179382D02*
Y408937D01*
G01X3179226Y405000D02*
Y404015D01*
G01X3178752Y415728D02*
Y410118D01*
G01X3176466Y405000D02*
Y404015D01*
G01X3175289D02*
Y405000D01*
G01X3172529Y404015D02*
Y405000D01*
G01X3172374Y408937D02*
Y407952D01*
G01X3171507D02*
Y408937D01*
G01X3171352Y405000D02*
Y404015D01*
G01X3180389Y407504D02*
X3180394Y405716D01*
G01X3180384Y405449D02*
X3180380Y407236D01*
G01X3175308Y403567D02*
X3175313Y401779D01*
G01X3175304Y401512D02*
X3175298Y403299D01*
G01X3172515Y407504D02*
X3172520Y405716D01*
G01X3172510Y405449D02*
X3172506Y407236D01*
G01X3172496Y408937D02*
X3171385D01*
G01X3180370D02*
X3179259D01*
G01X3172496Y407952D02*
X3171385D01*
G01X3180370D02*
X3179259D01*
G01X3179241Y407504D02*
X3180389D01*
G01X3171367D02*
X3172515D01*
G01X3172506Y407236D02*
X3171376D01*
G01X3180380D02*
X3179250D01*
G01X3172520Y405716D02*
X3171361D01*
G01X3180394D02*
X3179235D01*
G01X3179245Y405449D02*
X3180384D01*
G01X3171371D02*
X3172510D01*
G01X3172529Y405000D02*
X3171352D01*
G01X3176466D02*
X3175289D01*
G01X3180403D02*
X3179226D01*
G01X3172529Y404015D02*
X3171352D01*
G01X3176466D02*
X3175289D01*
G01X3180403D02*
X3179226D01*
G01X3176447Y403567D02*
X3175308D01*
G01X3175298Y403299D02*
X3176457D01*
G01X3175313Y401779D02*
X3176443D01*
G01X3176452Y401512D02*
X3175304D01*
G01X3184331Y403299D02*
X3184326Y401512D01*
G01X3184317Y401779D02*
X3184321Y403567D01*
G01X3184340Y405000D02*
Y404015D01*
G01X3183752Y415728D02*
Y410118D01*
G01X3183163Y404015D02*
Y405000D01*
G01X3183182Y403567D02*
X3183187Y401779D01*
G01X3183178Y401512D02*
X3183172Y403299D01*
G01X3184340Y405000D02*
X3183163D01*
G01X3184340Y404015D02*
X3183163D01*
G01X3184321Y403567D02*
X3183182D01*
G01X3183172Y403299D02*
X3184331D01*
G01X3183187Y401779D02*
X3184317D01*
G01X3184326Y401512D02*
X3183178D01*
G01X3199657Y415728D02*
X3183752D01*
G01X3193675Y-682988D02*
X3189866D01*
G01X3193675Y-664311D02*
Y-682988D01*
G01X3189866D02*
Y-664311D01*
G01X3203581Y-682988D02*
X3199772D01*
G01D02*
Y-658086D01*
G01X3189104Y-662755D02*
X3188342Y-661977D01*
G01D02*
X3186818Y-661199D01*
G01X3192152Y-660420D02*
X3193675Y-664311D01*
G01X3189866D02*
X3189104Y-662755D01*
G01X3188342Y-658086D02*
X3190628Y-658864D01*
G01D02*
X3192152Y-660420D01*
G01X3199772Y-658086D02*
X3203581D01*
G01X3200688Y-305311D02*
G03X3204625Y-301374I0J3937D01*
G01X3196142Y385582D02*
X3196137Y383795D01*
G01X3196128Y384063D02*
X3196132Y385850D01*
G01X3188268Y385582D02*
X3188263Y383795D01*
G01X3188254Y384063D02*
X3188258Y385850D01*
G01X3195996Y383346D02*
Y382362D01*
G01X3195130Y383346D02*
Y382362D01*
G01X3188122Y383346D02*
Y382362D01*
G01X3187256Y383346D02*
Y382362D01*
G01X3194993Y385850D02*
X3194998Y384063D01*
G01X3194989Y383795D02*
X3194983Y385582D01*
G01X3187119Y385850D02*
X3187124Y384063D01*
G01X3187115Y383795D02*
X3187109Y385582D01*
G01X3194998Y384063D02*
X3196128D01*
G01X3187124D02*
X3188254D01*
G01X3188263Y383795D02*
X3187115D01*
G01X3196137D02*
X3194989D01*
G01X3188244Y383346D02*
X3187133D01*
G01X3196118D02*
X3195007D01*
G01Y382362D02*
X3196118D01*
G01X3187133D02*
X3188244D01*
G01X3196156Y392106D02*
X3196169Y392767D01*
G01X3196167Y393694D02*
X3196136Y392106D01*
G01X3192219D02*
X3192232Y392767D01*
G01X3192230Y393694D02*
X3192199Y392106D01*
G01X3188282D02*
X3188295Y392767D01*
G01X3188293Y393694D02*
X3188262Y392106D01*
G01X3198865D02*
X3198874Y392697D01*
G01X3198872Y393607D02*
X3198847Y392106D01*
G01X3194928D02*
X3194937Y392697D01*
G01X3194935Y393607D02*
X3194910Y392106D01*
G01X3190991D02*
X3191000Y392697D01*
G01X3190998Y393607D02*
X3190973Y392106D01*
G01X3187054D02*
X3187063Y392697D01*
G01X3187061Y393607D02*
X3187036Y392106D01*
G01X3198935Y389519D02*
X3198930Y387732D01*
G01X3198920Y388000D02*
X3198926Y389787D01*
G01X3191061Y389519D02*
X3191056Y387732D01*
G01X3191046Y388000D02*
X3191052Y389787D01*
G01X3199067Y391220D02*
Y390236D01*
G01X3198911Y386299D02*
Y387283D01*
G01X3196151Y386299D02*
Y387283D01*
G01X3194974D02*
Y386299D01*
G01X3192214Y387283D02*
Y386299D01*
G01X3192059Y391220D02*
Y390236D01*
G01X3191193Y391220D02*
Y390236D01*
G01X3191037Y386299D02*
Y387283D01*
G01X3188277Y386299D02*
Y387283D01*
G01X3187100D02*
Y386299D01*
G01X3192200Y389787D02*
X3192205Y388000D01*
G01X3192195Y387732D02*
X3192191Y389519D01*
G01X3196215Y392106D02*
X3196191Y393607D01*
G01X3196188Y392697D02*
X3196198Y392106D01*
G01X3192278D02*
X3192254Y393607D01*
G01X3192251Y392697D02*
X3192261Y392106D01*
G01X3188341D02*
X3188317Y393607D01*
G01X3188314Y392697D02*
X3188324Y392106D01*
G01X3198927D02*
X3198896Y393694D01*
G01X3198894Y392767D02*
X3198907Y392106D01*
G01X3194990D02*
X3194959Y393694D01*
G01X3194957Y392767D02*
X3194970Y392106D01*
G01X3191053D02*
X3191022Y393694D01*
G01X3191020Y392767D02*
X3191033Y392106D01*
G01X3187116D02*
X3187085Y393694D01*
G01X3187083Y392767D02*
X3187096Y392106D01*
G01X3198885Y393977D02*
X3200115D01*
G01X3194948D02*
X3196178D01*
G01X3191011D02*
X3192241D01*
G01X3187074D02*
X3188304D01*
G01X3198896Y393694D02*
X3200104D01*
G01X3194959D02*
X3196167D01*
G01X3191022D02*
X3192230D01*
G01X3187085D02*
X3188293D01*
G01X3188317Y393607D02*
X3187061D01*
G01X3192254D02*
X3190998D01*
G01X3200128D02*
X3198872D01*
G01X3196191D02*
X3194935D01*
G01X3198885Y392993D02*
X3200115D01*
G01X3194948D02*
X3196178D01*
G01X3191011D02*
X3192241D01*
G01X3187074D02*
X3188304D01*
G01X3188295Y392767D02*
X3187083D01*
G01X3192232D02*
X3191020D01*
G01X3200106D02*
X3198894D01*
G01X3196169D02*
X3194957D01*
G01X3198874Y392697D02*
X3200125D01*
G01X3194937D02*
X3196188D01*
G01X3191000D02*
X3192251D01*
G01X3187063D02*
X3188314D01*
G01X3192181Y391220D02*
X3191070D01*
G01X3200055D02*
X3198945D01*
G01Y390236D02*
X3200055D01*
G01X3191070D02*
X3192181D01*
G01X3198926Y389787D02*
X3200074D01*
G01X3191052D02*
X3192200D01*
G01X3192191Y389519D02*
X3191061D01*
G01X3200065D02*
X3198935D01*
G01X3192205Y388000D02*
X3191046D01*
G01X3200079D02*
X3198920D01*
G01X3198930Y387732D02*
X3200069D01*
G01X3191056D02*
X3192195D01*
G01X3194974Y387283D02*
X3196151D01*
G01X3198911D02*
X3200088D01*
G01X3191037D02*
X3192214D01*
G01X3187100D02*
X3188277D01*
G01Y386299D02*
X3187100D01*
G01X3192214D02*
X3191037D01*
G01X3196151D02*
X3194974D01*
G01X3200088D02*
X3198911D01*
G01X3188258Y385850D02*
X3187119D01*
G01X3196132D02*
X3194993D01*
G01X3194983Y385582D02*
X3196142D01*
G01X3187109D02*
X3188268D01*
G01X3198896Y397604D02*
X3198927Y399193D01*
G01X3198907D02*
X3198894Y398532D01*
G01X3194959Y397604D02*
X3194990Y399193D01*
G01X3194970D02*
X3194957Y398532D01*
G01X3191022Y397604D02*
X3191053Y399193D01*
G01X3191033D02*
X3191020Y398532D01*
G01X3187085Y397604D02*
X3187116Y399193D01*
G01X3187096D02*
X3187083Y398532D01*
G01X3196191Y397691D02*
X3196215Y399193D01*
G01X3196198D02*
X3196188Y398602D01*
G01X3192254Y397691D02*
X3192278Y399193D01*
G01X3192261D02*
X3192251Y398602D01*
G01X3188317Y397691D02*
X3188341Y399193D01*
G01X3188324D02*
X3188314Y398602D01*
G01X3199067Y400078D02*
Y401063D01*
G01X3192059D02*
Y400078D01*
G01X3191193D02*
Y401063D01*
G01X3198874Y398602D02*
X3198865Y399193D01*
G01X3198847D02*
X3198872Y397691D01*
G01X3194937Y398602D02*
X3194928Y399193D01*
G01X3194910D02*
X3194935Y397691D01*
G01X3191000Y398602D02*
X3190991Y399193D01*
G01X3190973D02*
X3190998Y397691D01*
G01X3187063Y398602D02*
X3187054Y399193D01*
G01X3187036D02*
X3187061Y397691D01*
G01X3196169Y398532D02*
X3196156Y399193D01*
G01X3196136D02*
X3196167Y397604D01*
G01X3192232Y398532D02*
X3192219Y399193D01*
G01X3192199D02*
X3192230Y397604D01*
G01X3188295Y398532D02*
X3188282Y399193D01*
G01X3188262D02*
X3188293Y397604D01*
G01X3192181Y401063D02*
X3191070D01*
G01X3200055D02*
X3198945D01*
G01X3192181Y400078D02*
X3191070D01*
G01X3200055D02*
X3198945D01*
G01X3188314Y398602D02*
X3187063D01*
G01X3192251D02*
X3191000D01*
G01X3200125D02*
X3198874D01*
G01X3196188D02*
X3194937D01*
G01X3198894Y398532D02*
X3200106D01*
G01X3194957D02*
X3196169D01*
G01X3191020D02*
X3192232D01*
G01X3187083D02*
X3188295D01*
G01X3188304Y398306D02*
X3187074D01*
G01X3192241D02*
X3191011D01*
G01X3200115D02*
X3198885D01*
G01X3196178D02*
X3194948D01*
G01X3198872Y397691D02*
X3200128D01*
G01X3194935D02*
X3196191D01*
G01X3190998D02*
X3192254D01*
G01X3187061D02*
X3188317D01*
G01X3188293Y397604D02*
X3187085D01*
G01X3192230D02*
X3191022D01*
G01X3200104D02*
X3198896D01*
G01X3196167D02*
X3194959D01*
G01X3188304Y397322D02*
X3187074D01*
G01X3192241D02*
X3191011D01*
G01X3200115D02*
X3198885D01*
G01X3196178D02*
X3194948D01*
G01X3200093Y392106D02*
X3200106Y392767D01*
G01X3200104Y393694D02*
X3200073Y392106D01*
G01X3200088Y387283D02*
Y386299D01*
G01X3199933Y391220D02*
Y390236D01*
G01X3200074Y389787D02*
X3200079Y388000D01*
G01X3200069Y387732D02*
X3200065Y389519D01*
G01X3200152Y392106D02*
X3200128Y393607D01*
G01X3200125Y392697D02*
X3200135Y392106D01*
G01X3200128Y397691D02*
X3200152Y399193D01*
G01X3200135D02*
X3200125Y398602D01*
G01X3199933Y401063D02*
Y400078D01*
G01X3200106Y398532D02*
X3200093Y399193D01*
G01X3200073D02*
X3200104Y397604D01*
G01X3194998Y407236D02*
X3194993Y405449D01*
G01X3194983Y405716D02*
X3194989Y407504D01*
G01X3192205Y403299D02*
X3192200Y401512D01*
G01X3192191Y401779D02*
X3192195Y403567D01*
G01X3187124Y407236D02*
X3187119Y405449D01*
G01X3187109Y405716D02*
X3187115Y407504D01*
G01X3198911Y404015D02*
Y405000D01*
G01X3196151Y404015D02*
Y405000D01*
G01X3195996Y408937D02*
Y407952D01*
G01X3195130D02*
Y408937D01*
G01X3194974Y405000D02*
Y404015D01*
G01X3192214Y405000D02*
Y404015D01*
G01X3191037D02*
Y405000D01*
G01X3188277Y404015D02*
Y405000D01*
G01X3188122Y408937D02*
Y407952D01*
G01X3187256D02*
Y408937D01*
G01X3187100Y405000D02*
Y404015D01*
G01X3198930Y403567D02*
X3198935Y401779D01*
G01X3198926Y401512D02*
X3198920Y403299D01*
G01X3196137Y407504D02*
X3196142Y405716D01*
G01X3196132Y405449D02*
X3196128Y407236D01*
G01X3191056Y403567D02*
X3191061Y401779D01*
G01X3191052Y401512D02*
X3191046Y403299D01*
G01X3188263Y407504D02*
X3188268Y405716D01*
G01X3188258Y405449D02*
X3188254Y407236D01*
G01X3188244Y408937D02*
X3187133D01*
G01X3196118D02*
X3195007D01*
G01X3188244Y407952D02*
X3187133D01*
G01X3196118D02*
X3195007D01*
G01X3194989Y407504D02*
X3196137D01*
G01X3187115D02*
X3188263D01*
G01X3188254Y407236D02*
X3187124D01*
G01X3196128D02*
X3194998D01*
G01X3188268Y405716D02*
X3187109D01*
G01X3196142D02*
X3194983D01*
G01X3194993Y405449D02*
X3196132D01*
G01X3187119D02*
X3188258D01*
G01X3188277Y405000D02*
X3187100D01*
G01X3192214D02*
X3191037D01*
G01X3200088D02*
X3198911D01*
G01X3196151D02*
X3194974D01*
G01X3188277Y404015D02*
X3187100D01*
G01X3192214D02*
X3191037D01*
G01X3200088D02*
X3198911D01*
G01X3196151D02*
X3194974D01*
G01X3192195Y403567D02*
X3191056D01*
G01X3200069D02*
X3198930D01*
G01X3198920Y403299D02*
X3200079D01*
G01X3191046D02*
X3192205D01*
G01X3198935Y401779D02*
X3200065D01*
G01X3191061D02*
X3192191D01*
G01X3192200Y401512D02*
X3191052D01*
G01X3200074D02*
X3198926D01*
G01X3200079Y403299D02*
X3200074Y401512D01*
G01X3200065Y401779D02*
X3200069Y403567D01*
G01X3200088Y405000D02*
Y404015D01*
G01X3199657Y415728D02*
Y410118D01*
G01X3264460Y446043D02*
X3199917D01*
G01X3247145Y-939956D02*
G03I-15748J0D01*
G01Y-882870D02*
G03I-15748J0D01*
G01X3203581Y-663533D02*
Y-682988D01*
G01X3215773D02*
X3211963D01*
G01X3215773Y-664311D02*
Y-682988D01*
G01X3211963D02*
Y-664311D01*
G01X3211201Y-662755D02*
X3210439Y-661977D01*
G01D02*
X3208915Y-661199D01*
G01X3211963Y-664311D02*
X3211201Y-662755D01*
G01X3205105Y-661977D02*
X3203581Y-663533D01*
G01X3207391Y-661199D02*
X3205105Y-661977D01*
G01X3210439Y-658086D02*
X3212725Y-658864D01*
G01X3207391Y-658086D02*
X3210439D01*
G01X3208915Y-661199D02*
X3207391D01*
G01X3203581Y-658086D02*
Y-660420D01*
G01D02*
X3205105Y-658864D01*
G01D02*
X3207391Y-658086D01*
G01X3216535Y-662755D02*
X3215773Y-664311D01*
G01X3218821Y-661199D02*
X3217297Y-661977D01*
G01D02*
X3216535Y-662755D01*
G01X3221107Y-661199D02*
X3218821D01*
G01X3212725Y-658864D02*
X3215011Y-661199D01*
G01D02*
X3217297Y-658864D01*
G01D02*
X3219583Y-658086D01*
G01X3204625Y-271846D02*
Y-301374D01*
G01X3208563Y-291925D02*
X3205807D01*
G01X3212500D02*
X3209744D01*
G01D02*
Y-275389D01*
G01X3208563D02*
Y-291925D01*
G01X3205807D02*
Y-275389D01*
G01X3216437Y-291925D02*
X3213681D01*
G01X3220374D02*
X3217618D01*
G01D02*
Y-275389D01*
G01X3216437D02*
Y-291925D01*
G01X3213681D02*
Y-275389D01*
G01X3212500D02*
Y-291925D01*
G01X3209744Y-275389D02*
X3212500D01*
G01X3205807D02*
X3208563D01*
G01X3232972D02*
X3204625D01*
G01X3217618D02*
X3220374D01*
G01X3213681D02*
X3216437D01*
G01X3231003Y-269878D02*
X3206594D01*
G01D02*
X3204625Y-271846D01*
G01X3211890Y385582D02*
X3211885Y383795D01*
G01X3211876Y384063D02*
X3211880Y385850D01*
G01X3204016Y385582D02*
X3204011Y383795D01*
G01X3204002Y384063D02*
X3204006Y385850D01*
G01X3211744Y383346D02*
Y382362D01*
G01X3210878Y383346D02*
Y382362D01*
G01X3203870Y383346D02*
Y382362D01*
G01X3203004Y383346D02*
Y382362D01*
G01X3210741Y385850D02*
X3210746Y384063D01*
G01X3210737Y383795D02*
X3210732Y385582D01*
G01X3202867Y385850D02*
X3202872Y384063D01*
G01X3202863Y383795D02*
X3202857Y385582D01*
G01X3210746Y384063D02*
X3211876D01*
G01X3202872D02*
X3204002D01*
G01X3204011Y383795D02*
X3202863D01*
G01X3211885D02*
X3210737D01*
G01X3203992Y383346D02*
X3202882D01*
G01X3211866D02*
X3210756D01*
G01Y382362D02*
X3211866D01*
G01X3202882D02*
X3203992D01*
G01X3218752Y383346D02*
Y382362D01*
G01X3218615Y385850D02*
X3218620Y384063D01*
G01X3218611Y383795D02*
X3218606Y385582D01*
G01X3218620Y384063D02*
X3219750D01*
G01X3219759Y383795D02*
X3218611D01*
G01X3219740Y383346D02*
X3218630D01*
G01Y382362D02*
X3219740D01*
G01X3211904Y392106D02*
X3211917Y392767D01*
G01X3211915Y393694D02*
X3211884Y392106D01*
G01X3207967D02*
X3207980Y392767D01*
G01X3207978Y393694D02*
X3207947Y392106D01*
G01X3204030D02*
X3204043Y392767D01*
G01X3204041Y393694D02*
X3204010Y392106D01*
G01X3214613D02*
X3214622Y392697D01*
G01X3214620Y393607D02*
X3214595Y392106D01*
G01X3210676D02*
X3210685Y392697D01*
G01X3210683Y393607D02*
X3210658Y392106D01*
G01X3206739D02*
X3206748Y392697D01*
G01X3206746Y393607D02*
X3206721Y392106D01*
G01X3202802D02*
X3202811Y392697D01*
G01X3202809Y393607D02*
X3202784Y392106D01*
G01X3214683Y389519D02*
X3214678Y387732D01*
G01X3214669Y388000D02*
X3214674Y389787D01*
G01X3206809Y389519D02*
X3206804Y387732D01*
G01X3206795Y388000D02*
X3206800Y389787D01*
G01X3215681Y391220D02*
Y390236D01*
G01X3214815Y391220D02*
Y390236D01*
G01X3214659Y387283D02*
Y386299D01*
G01X3211899D02*
Y387283D01*
G01X3210722D02*
Y386299D01*
G01X3207962Y387283D02*
Y386299D01*
G01X3207807Y391220D02*
Y390236D01*
G01X3206941Y391220D02*
Y390236D01*
G01X3206785Y386299D02*
Y387283D01*
G01X3204025Y386299D02*
Y387283D01*
G01X3202848D02*
Y386299D01*
G01X3207948Y389787D02*
X3207953Y388000D01*
G01X3207943Y387732D02*
X3207939Y389519D01*
G01X3211963Y392106D02*
X3211939Y393607D01*
G01X3211936Y392697D02*
X3211946Y392106D01*
G01X3208026D02*
X3208002Y393607D01*
G01X3207999Y392697D02*
X3208009Y392106D01*
G01X3204089D02*
X3204065Y393607D01*
G01X3204062Y392697D02*
X3204072Y392106D01*
G01X3214675D02*
X3214644Y393694D01*
G01X3214642Y392767D02*
X3214655Y392106D01*
G01X3210738D02*
X3210707Y393694D01*
G01X3210705Y392767D02*
X3210718Y392106D01*
G01X3206801D02*
X3206770Y393694D01*
G01X3206768Y392767D02*
X3206781Y392106D01*
G01X3202864D02*
X3202833Y393694D01*
G01X3202831Y392767D02*
X3202844Y392106D01*
G01X3214633Y393977D02*
X3215863D01*
G01X3210696D02*
X3211926D01*
G01X3206759D02*
X3207989D01*
G01X3202822D02*
X3204052D01*
G01X3214644Y393694D02*
X3215852D01*
G01X3210707D02*
X3211915D01*
G01X3206770D02*
X3207978D01*
G01X3202833D02*
X3204041D01*
G01X3204065Y393607D02*
X3202809D01*
G01X3208002D02*
X3206746D01*
G01X3211939D02*
X3210683D01*
G01X3215876D02*
X3214620D01*
G01X3214633Y392993D02*
X3215863D01*
G01X3210696D02*
X3211926D01*
G01X3206759D02*
X3207989D01*
G01X3202822D02*
X3204052D01*
G01X3204043Y392767D02*
X3202831D01*
G01X3207980D02*
X3206768D01*
G01X3211917D02*
X3210705D01*
G01X3215854D02*
X3214642D01*
G01X3214622Y392697D02*
X3215873D01*
G01X3210685D02*
X3211936D01*
G01X3206748D02*
X3207999D01*
G01X3202811D02*
X3204062D01*
G01X3207929Y391220D02*
X3206819D01*
G01X3215803D02*
X3214693D01*
G01Y390236D02*
X3215803D01*
G01X3206819D02*
X3207929D01*
G01X3214674Y389787D02*
X3215822D01*
G01X3206800D02*
X3207948D01*
G01X3207939Y389519D02*
X3206809D01*
G01X3215813D02*
X3214683D01*
G01X3207953Y388000D02*
X3206795D01*
G01X3215827D02*
X3214669D01*
G01X3214678Y387732D02*
X3215817D01*
G01X3206804D02*
X3207943D01*
G01X3214659Y387283D02*
X3215836D01*
G01X3210722D02*
X3211899D01*
G01X3206785D02*
X3207962D01*
G01X3202848D02*
X3204025D01*
G01Y386299D02*
X3202848D01*
G01X3207962D02*
X3206785D01*
G01X3211899D02*
X3210722D01*
G01X3215836D02*
X3214659D01*
G01X3204006Y385850D02*
X3202867D01*
G01X3211880D02*
X3210741D01*
G01X3210732Y385582D02*
X3211890D01*
G01X3202857D02*
X3204016D01*
G01X3214644Y397604D02*
X3214675Y399193D01*
G01X3214655D02*
X3214642Y398532D01*
G01X3210707Y397604D02*
X3210738Y399193D01*
G01X3210718D02*
X3210705Y398532D01*
G01X3206770Y397604D02*
X3206801Y399193D01*
G01X3206781D02*
X3206768Y398532D01*
G01X3202833Y397604D02*
X3202864Y399193D01*
G01X3202844D02*
X3202831Y398532D01*
G01X3211939Y397691D02*
X3211963Y399193D01*
G01X3211946D02*
X3211936Y398602D01*
G01X3208002Y397691D02*
X3208026Y399193D01*
G01X3208009D02*
X3207999Y398602D01*
G01X3204065Y397691D02*
X3204089Y399193D01*
G01X3204072D02*
X3204062Y398602D01*
G01X3215681Y401063D02*
Y400078D01*
G01X3214815D02*
Y401063D01*
G01X3207807D02*
Y400078D01*
G01X3206941D02*
Y401063D01*
G01X3214622Y398602D02*
X3214613Y399193D01*
G01X3214595D02*
X3214620Y397691D01*
G01X3210685Y398602D02*
X3210676Y399193D01*
G01X3210658D02*
X3210683Y397691D01*
G01X3206748Y398602D02*
X3206739Y399193D01*
G01X3206721D02*
X3206746Y397691D01*
G01X3202811Y398602D02*
X3202802Y399193D01*
G01X3202784D02*
X3202809Y397691D01*
G01X3211917Y398532D02*
X3211904Y399193D01*
G01X3211884D02*
X3211915Y397604D01*
G01X3207980Y398532D02*
X3207967Y399193D01*
G01X3207947D02*
X3207978Y397604D01*
G01X3204043Y398532D02*
X3204030Y399193D01*
G01X3204010D02*
X3204041Y397604D01*
G01X3207929Y401063D02*
X3206819D01*
G01X3215803D02*
X3214693D01*
G01X3207929Y400078D02*
X3206819D01*
G01X3215803D02*
X3214693D01*
G01X3204062Y398602D02*
X3202811D01*
G01X3207999D02*
X3206748D01*
G01X3211936D02*
X3210685D01*
G01X3215873D02*
X3214622D01*
G01X3214642Y398532D02*
X3215854D01*
G01X3210705D02*
X3211917D01*
G01X3206768D02*
X3207980D01*
G01X3202831D02*
X3204043D01*
G01X3204052Y398306D02*
X3202822D01*
G01X3207989D02*
X3206759D01*
G01X3211926D02*
X3210696D01*
G01X3215863D02*
X3214633D01*
G01X3214620Y397691D02*
X3215876D01*
G01X3210683D02*
X3211939D01*
G01X3206746D02*
X3208002D01*
G01X3202809D02*
X3204065D01*
G01X3204041Y397604D02*
X3202833D01*
G01X3207978D02*
X3206770D01*
G01X3211915D02*
X3210707D01*
G01X3215852D02*
X3214644D01*
G01X3204052Y397322D02*
X3202822D01*
G01X3207989D02*
X3206759D01*
G01X3211926D02*
X3210696D01*
G01X3215863D02*
X3214633D01*
G01X3215841Y392106D02*
X3215854Y392767D01*
G01X3215852Y393694D02*
X3215821Y392106D01*
G01X3218550D02*
X3218559Y392697D01*
G01X3218557Y393607D02*
X3218532Y392106D01*
G01X3218596Y387283D02*
Y386299D01*
G01X3215836D02*
Y387283D01*
G01X3215822Y389787D02*
X3215827Y388000D01*
G01X3215817Y387732D02*
X3215813Y389519D01*
G01X3215900Y392106D02*
X3215876Y393607D01*
G01X3215873Y392697D02*
X3215883Y392106D01*
G01X3218612D02*
X3218581Y393694D01*
G01X3218579Y392767D02*
X3218592Y392106D01*
G01X3218570Y393977D02*
X3219800D01*
G01X3218581Y393694D02*
X3219789D01*
G01X3219813Y393607D02*
X3218557D01*
G01X3218570Y392993D02*
X3219800D01*
G01X3219791Y392767D02*
X3218579D01*
G01X3218559Y392697D02*
X3219810D01*
G01X3218596Y387283D02*
X3219773D01*
G01Y386299D02*
X3218596D01*
G01X3219754Y385850D02*
X3218615D01*
G01X3218606Y385582D02*
X3219764D01*
G01X3218581Y397604D02*
X3218612Y399193D01*
G01X3218592D02*
X3218579Y398532D01*
G01X3215876Y397691D02*
X3215900Y399193D01*
G01X3215883D02*
X3215873Y398602D01*
G01X3218559D02*
X3218550Y399193D01*
G01X3218532D02*
X3218557Y397691D01*
G01X3215854Y398532D02*
X3215841Y399193D01*
G01X3215821D02*
X3215852Y397604D01*
G01X3219810Y398602D02*
X3218559D01*
G01X3218579Y398532D02*
X3219791D01*
G01X3219800Y398306D02*
X3218570D01*
G01X3218557Y397691D02*
X3219813D01*
G01X3219789Y397604D02*
X3218581D01*
G01X3219800Y397322D02*
X3218570D01*
G01X3210746Y407236D02*
X3210741Y405449D01*
G01X3210732Y405716D02*
X3210737Y407504D01*
G01X3207953Y403299D02*
X3207948Y401512D01*
G01X3207939Y401779D02*
X3207943Y403567D01*
G01X3202872Y407236D02*
X3202867Y405449D01*
G01X3202857Y405716D02*
X3202863Y407504D01*
G01X3214659Y404015D02*
Y405000D01*
G01X3211899Y404015D02*
Y405000D01*
G01X3211744Y408937D02*
Y407952D01*
G01X3210878D02*
Y408937D01*
G01X3210722Y405000D02*
Y404015D01*
G01X3207962Y405000D02*
Y404015D01*
G01X3206785D02*
Y405000D01*
G01X3204657Y415728D02*
Y410118D01*
G01X3204025Y404015D02*
Y405000D01*
G01X3203870Y408937D02*
Y407952D01*
G01X3203004D02*
Y408937D01*
G01X3202848Y405000D02*
Y404015D01*
G01X3214678Y403567D02*
X3214683Y401779D01*
G01X3214674Y401512D02*
X3214669Y403299D01*
G01X3211885Y407504D02*
X3211890Y405716D01*
G01X3211880Y405449D02*
X3211876Y407236D01*
G01X3206804Y403567D02*
X3206809Y401779D01*
G01X3206800Y401512D02*
X3206795Y403299D01*
G01X3204011Y407504D02*
X3204016Y405716D01*
G01X3204006Y405449D02*
X3204002Y407236D01*
G01X3203992Y408937D02*
X3202882D01*
G01X3211866D02*
X3210756D01*
G01X3203992Y407952D02*
X3202882D01*
G01X3211866D02*
X3210756D01*
G01X3210737Y407504D02*
X3211885D01*
G01X3202863D02*
X3204011D01*
G01X3204002Y407236D02*
X3202872D01*
G01X3211876D02*
X3210746D01*
G01X3204016Y405716D02*
X3202857D01*
G01X3211890D02*
X3210732D01*
G01X3210741Y405449D02*
X3211880D01*
G01X3202867D02*
X3204006D01*
G01X3204025Y405000D02*
X3202848D01*
G01X3207962D02*
X3206785D01*
G01X3211899D02*
X3210722D01*
G01X3215836D02*
X3214659D01*
G01X3204025Y404015D02*
X3202848D01*
G01X3207962D02*
X3206785D01*
G01X3211899D02*
X3210722D01*
G01X3215836D02*
X3214659D01*
G01X3207943Y403567D02*
X3206804D01*
G01X3215817D02*
X3214678D01*
G01X3214669Y403299D02*
X3215827D01*
G01X3206795D02*
X3207953D01*
G01X3214683Y401779D02*
X3215813D01*
G01X3206809D02*
X3207939D01*
G01X3207948Y401512D02*
X3206800D01*
G01X3215822D02*
X3214674D01*
G01X3220563Y415728D02*
X3204657D01*
G01X3218620Y407236D02*
X3218615Y405449D01*
G01X3218606Y405716D02*
X3218611Y407504D01*
G01X3215827Y403299D02*
X3215822Y401512D01*
G01X3215813Y401779D02*
X3215817Y403567D01*
G01X3218752Y407952D02*
Y408937D01*
G01X3218596Y405000D02*
Y404015D01*
G01X3215836Y405000D02*
Y404015D01*
G01X3219740Y408937D02*
X3218630D01*
G01X3219740Y407952D02*
X3218630D01*
G01X3218611Y407504D02*
X3219759D01*
G01X3219750Y407236D02*
X3218620D01*
G01X3219764Y405716D02*
X3218606D01*
G01X3218615Y405449D02*
X3219754D01*
G01X3219773Y405000D02*
X3218596D01*
G01X3219773Y404015D02*
X3218596D01*
G01X3264460Y503130D02*
X3205519D01*
G01X3234833Y-1852994D02*
Y-1841587D01*
X3233122Y-1843868D01*
G01Y-1852994D02*
X3236544D01*
G01X3245956D02*
X3246241Y-1850523D01*
X3246669Y-1848431D01*
X3247239Y-1846530D01*
X3247952Y-1844439D01*
X3249093Y-1841587D01*
X3243389D01*
G01X3237696Y-939956D02*
G03I-6299J0D01*
G01Y-882870D02*
G03I-6299J0D01*
G01X3227964Y-682988D02*
X3224155D01*
G01X3227964Y-664311D02*
Y-682988D01*
G01X3224155D02*
Y-664311D01*
G01X3222631Y-661977D02*
X3221107Y-661199D01*
G01X3223393Y-662755D02*
X3222631Y-661977D01*
G01X3226440Y-660420D02*
X3227964Y-664311D01*
G01X3224155D02*
X3223393Y-662755D01*
G01X3222631Y-658086D02*
X3224917Y-658864D01*
G01X3219583Y-658086D02*
X3222631D01*
G01X3224917Y-658864D02*
X3226440Y-660420D01*
G01X3224311Y-291925D02*
X3221555D01*
G01X3228248D02*
X3225492D01*
G01D02*
Y-275389D01*
G01X3224311D02*
Y-291925D01*
G01X3221555D02*
Y-275389D01*
G01X3220374D02*
Y-291925D01*
G01X3232972Y-299208D02*
G03X3240452I3740J0D01*
G01X3232185Y-291925D02*
X3229429D01*
G01X3232972Y-299208D02*
Y-271846D01*
G01X3232185Y-275389D02*
Y-291925D01*
G01X3229429D02*
Y-275389D01*
G01X3228248D02*
Y-291925D01*
G01X3221555Y-275389D02*
X3224311D01*
G01X3225492D02*
X3228248D01*
G01X3229429D02*
X3232185D01*
G01X3232972Y-271846D02*
X3231003Y-269878D01*
G01X3227638Y385582D02*
X3227633Y383795D01*
G01X3227624Y384063D02*
X3227628Y385850D01*
G01X3219764Y385582D02*
X3219759Y383795D01*
G01X3219750Y384063D02*
X3219754Y385850D01*
G01X3227492Y383346D02*
Y382362D01*
G01X3226626Y383346D02*
Y382362D01*
G01X3219618Y383346D02*
Y382362D01*
G01X3226489Y385850D02*
X3226494Y384063D01*
G01X3226485Y383795D02*
X3226480Y385582D01*
G01X3226494Y384063D02*
X3227624D01*
G01X3227633Y383795D02*
X3226485D01*
G01X3227614Y383346D02*
X3226504D01*
G01Y382362D02*
X3227614D01*
G01X3234500Y383346D02*
Y382362D01*
G01X3234363Y385850D02*
X3234368Y384063D01*
G01X3234359Y383795D02*
X3234354Y385582D01*
G01X3234368Y384063D02*
X3235498D01*
G01X3235507Y383795D02*
X3234359D01*
G01X3235488Y383346D02*
X3234378D01*
G01Y382362D02*
X3235488D01*
G01X3231589Y392106D02*
X3231602Y392767D01*
G01X3231600Y393694D02*
X3231569Y392106D01*
G01X3227652D02*
X3227665Y392767D01*
G01X3227663Y393694D02*
X3227632Y392106D01*
G01X3223715D02*
X3223728Y392767D01*
G01X3223726Y393694D02*
X3223695Y392106D01*
G01X3219778D02*
X3219791Y392767D01*
G01X3219789Y393694D02*
X3219758Y392106D01*
G01X3230361D02*
X3230370Y392697D01*
G01X3230368Y393607D02*
X3230343Y392106D01*
G01X3226424D02*
X3226433Y392697D01*
G01X3226431Y393607D02*
X3226406Y392106D01*
G01X3222487D02*
X3222496Y392697D01*
G01X3222494Y393607D02*
X3222469Y392106D01*
G01X3230431Y389519D02*
X3230426Y387732D01*
G01X3230417Y388000D02*
X3230422Y389787D01*
G01X3222557Y389519D02*
X3222552Y387732D01*
G01X3222543Y388000D02*
X3222548Y389787D01*
G01X3231584Y387283D02*
Y386299D01*
G01X3231429Y391220D02*
Y390236D01*
G01X3230563Y391220D02*
Y390236D01*
G01X3230407Y386299D02*
Y387283D01*
G01X3227647Y386299D02*
Y387283D01*
G01X3226470D02*
Y386299D01*
G01X3223710Y387283D02*
Y386299D01*
G01X3223555Y391220D02*
Y390236D01*
G01X3222689Y391220D02*
Y390236D01*
G01X3222533Y386299D02*
Y387283D01*
G01X3219773Y386299D02*
Y387283D01*
G01X3231570Y389787D02*
X3231575Y388000D01*
G01X3231565Y387732D02*
X3231561Y389519D01*
G01X3223696Y389787D02*
X3223701Y388000D01*
G01X3223691Y387732D02*
X3223687Y389519D01*
G01X3231648Y392106D02*
X3231624Y393607D01*
G01X3231621Y392697D02*
X3231631Y392106D01*
G01X3227711D02*
X3227687Y393607D01*
G01X3227684Y392697D02*
X3227694Y392106D01*
G01X3223774D02*
X3223750Y393607D01*
G01X3223747Y392697D02*
X3223757Y392106D01*
G01X3219837D02*
X3219813Y393607D01*
G01X3219810Y392697D02*
X3219820Y392106D01*
G01X3230423D02*
X3230392Y393694D01*
G01X3230390Y392767D02*
X3230403Y392106D01*
G01X3226486D02*
X3226455Y393694D01*
G01X3226453Y392767D02*
X3226466Y392106D01*
G01X3222549D02*
X3222518Y393694D01*
G01X3222516Y392767D02*
X3222529Y392106D01*
G01X3230381Y393977D02*
X3231611D01*
G01X3222507D02*
X3223737D01*
G01X3226444D02*
X3227674D01*
G01X3230392Y393694D02*
X3231600D01*
G01X3222518D02*
X3223726D01*
G01X3226455D02*
X3227663D01*
G01X3223750Y393607D02*
X3222494D01*
G01X3227687D02*
X3226431D01*
G01X3231624D02*
X3230368D01*
G01X3230381Y392993D02*
X3231611D01*
G01X3222507D02*
X3223737D01*
G01X3226444D02*
X3227674D01*
G01X3223728Y392767D02*
X3222516D01*
G01X3227665D02*
X3226453D01*
G01X3231602D02*
X3230390D01*
G01X3230370Y392697D02*
X3231621D01*
G01X3222496D02*
X3223747D01*
G01X3226433D02*
X3227684D01*
G01X3223677Y391220D02*
X3222567D01*
G01X3231551D02*
X3230441D01*
G01Y390236D02*
X3231551D01*
G01X3222567D02*
X3223677D01*
G01X3230422Y389787D02*
X3231570D01*
G01X3222548D02*
X3223696D01*
G01X3223687Y389519D02*
X3222557D01*
G01X3231561D02*
X3230431D01*
G01X3223701Y388000D02*
X3222543D01*
G01X3231575D02*
X3230417D01*
G01X3230426Y387732D02*
X3231565D01*
G01X3222552D02*
X3223691D01*
G01X3230407Y387283D02*
X3231584D01*
G01X3226470D02*
X3227647D01*
G01X3222533D02*
X3223710D01*
G01X3227647Y386299D02*
X3226470D01*
G01X3223710D02*
X3222533D01*
G01X3231584D02*
X3230407D01*
G01X3227628Y385850D02*
X3226489D01*
G01X3226480Y385582D02*
X3227638D01*
G01X3231624Y397691D02*
X3231648Y399193D01*
G01X3231631D02*
X3231621Y398602D01*
G01X3230392Y397604D02*
X3230423Y399193D01*
G01X3230403D02*
X3230390Y398532D01*
G01X3226455Y397604D02*
X3226486Y399193D01*
G01X3226466D02*
X3226453Y398532D01*
G01X3222518Y397604D02*
X3222549Y399193D01*
G01X3222529D02*
X3222516Y398532D01*
G01X3227687Y397691D02*
X3227711Y399193D01*
G01X3227694D02*
X3227684Y398602D01*
G01X3223750Y397691D02*
X3223774Y399193D01*
G01X3223757D02*
X3223747Y398602D01*
G01X3219813Y397691D02*
X3219837Y399193D01*
G01X3219820D02*
X3219810Y398602D01*
G01X3231429Y401063D02*
Y400078D01*
G01X3230563D02*
Y401063D01*
G01X3223555D02*
Y400078D01*
G01X3222689D02*
Y401063D01*
G01X3230370Y398602D02*
X3230361Y399193D01*
G01X3230343D02*
X3230368Y397691D01*
G01X3226433Y398602D02*
X3226424Y399193D01*
G01X3226406D02*
X3226431Y397691D01*
G01X3222496Y398602D02*
X3222487Y399193D01*
G01X3222469D02*
X3222494Y397691D01*
G01X3231602Y398532D02*
X3231589Y399193D01*
G01X3231569D02*
X3231600Y397604D01*
G01X3227665Y398532D02*
X3227652Y399193D01*
G01X3227632D02*
X3227663Y397604D01*
G01X3223728Y398532D02*
X3223715Y399193D01*
G01X3223695D02*
X3223726Y397604D01*
G01X3219791Y398532D02*
X3219778Y399193D01*
G01X3219758D02*
X3219789Y397604D01*
G01X3223677Y401063D02*
X3222567D01*
G01X3231551D02*
X3230441D01*
G01X3223677Y400078D02*
X3222567D01*
G01X3231551D02*
X3230441D01*
G01X3223747Y398602D02*
X3222496D01*
G01X3227684D02*
X3226433D01*
G01X3231621D02*
X3230370D01*
G01X3230390Y398532D02*
X3231602D01*
G01X3222516D02*
X3223728D01*
G01X3226453D02*
X3227665D01*
G01X3223737Y398306D02*
X3222507D01*
G01X3227674D02*
X3226444D01*
G01X3231611D02*
X3230381D01*
G01X3230368Y397691D02*
X3231624D01*
G01X3222494D02*
X3223750D01*
G01X3226431D02*
X3227687D01*
G01X3223726Y397604D02*
X3222518D01*
G01X3227663D02*
X3226455D01*
G01X3231600D02*
X3230392D01*
G01X3223737Y397322D02*
X3222507D01*
G01X3227674D02*
X3226444D01*
G01X3231611D02*
X3230381D01*
G01X3234298Y392106D02*
X3234307Y392697D01*
G01X3234305Y393607D02*
X3234280Y392106D01*
G01X3234345Y387283D02*
Y386299D01*
G01X3234360Y392106D02*
X3234329Y393694D01*
G01X3234327Y392767D02*
X3234340Y392106D01*
G01X3234318Y393977D02*
X3235548D01*
G01X3234329Y393694D02*
X3235537D01*
G01X3235561Y393607D02*
X3234305D01*
G01X3234318Y392993D02*
X3235548D01*
G01X3235539Y392767D02*
X3234327D01*
G01X3234307Y392697D02*
X3235558D01*
G01X3234345Y387283D02*
X3235521D01*
G01Y386299D02*
X3234345D01*
G01X3235502Y385850D02*
X3234363D01*
G01X3234354Y385582D02*
X3235512D01*
G01X3234329Y397604D02*
X3234360Y399193D01*
G01X3234340D02*
X3234327Y398532D01*
G01X3234307Y398602D02*
X3234298Y399193D01*
G01X3234280D02*
X3234305Y397691D01*
G01X3235558Y398602D02*
X3234307D01*
G01X3234327Y398532D02*
X3235539D01*
G01X3235548Y398306D02*
X3234318D01*
G01X3234305Y397691D02*
X3235561D01*
G01X3235537Y397604D02*
X3234329D01*
G01X3235548Y397322D02*
X3234318D01*
G01X3231575Y403299D02*
X3231570Y401512D01*
G01X3231561Y401779D02*
X3231565Y403567D01*
G01X3226494Y407236D02*
X3226489Y405449D01*
G01X3226480Y405716D02*
X3226485Y407504D01*
G01X3223701Y403299D02*
X3223696Y401512D01*
G01X3223687Y401779D02*
X3223691Y403567D01*
G01X3231584Y405000D02*
Y404015D01*
G01X3230407D02*
Y405000D01*
G01X3227647Y404015D02*
Y405000D01*
G01X3227492Y408937D02*
Y407952D01*
G01X3226626D02*
Y408937D01*
G01X3226470Y405000D02*
Y404015D01*
G01X3225563Y415728D02*
Y410118D01*
G01X3223710Y405000D02*
Y404015D01*
G01X3222533D02*
Y405000D01*
G01X3220563Y415728D02*
Y410118D01*
G01X3219773Y404015D02*
Y405000D01*
G01X3219618Y408937D02*
Y407952D01*
G01X3230426Y403567D02*
X3230431Y401779D01*
G01X3230422Y401512D02*
X3230417Y403299D01*
G01X3227633Y407504D02*
X3227638Y405716D01*
G01X3227628Y405449D02*
X3227624Y407236D01*
G01X3222552Y403567D02*
X3222557Y401779D01*
G01X3222548Y401512D02*
X3222543Y403299D01*
G01X3219759Y407504D02*
X3219764Y405716D01*
G01X3219754Y405449D02*
X3219750Y407236D01*
G01X3227614Y408937D02*
X3226504D01*
G01X3227614Y407952D02*
X3226504D01*
G01X3226485Y407504D02*
X3227633D01*
G01X3227624Y407236D02*
X3226494D01*
G01X3227638Y405716D02*
X3226480D01*
G01X3226489Y405449D02*
X3227628D01*
G01X3227647Y405000D02*
X3226470D01*
G01X3223710D02*
X3222533D01*
G01X3231584D02*
X3230407D01*
G01X3227647Y404015D02*
X3226470D01*
G01X3223710D02*
X3222533D01*
G01X3231584D02*
X3230407D01*
G01X3223691Y403567D02*
X3222552D01*
G01X3231565D02*
X3230426D01*
G01X3230417Y403299D02*
X3231575D01*
G01X3222543D02*
X3223701D01*
G01X3230431Y401779D02*
X3231561D01*
G01X3222557D02*
X3223687D01*
G01X3223696Y401512D02*
X3222548D01*
G01X3231570D02*
X3230422D01*
G01X3241468Y415728D02*
X3225563D01*
G01X3234368Y407236D02*
X3234363Y405449D01*
G01X3234354Y405716D02*
X3234359Y407504D01*
G01X3234500Y407952D02*
Y408937D01*
G01X3234345Y405000D02*
Y404015D01*
G01X3235488Y408937D02*
X3234378D01*
G01X3235488Y407952D02*
X3234378D01*
G01X3234359Y407504D02*
X3235507D01*
G01X3235498Y407236D02*
X3234368D01*
G01X3235512Y405716D02*
X3234354D01*
G01X3234363Y405449D02*
X3235502D01*
G01X3235521Y405000D02*
X3234345D01*
G01X3235521Y404015D02*
X3234345D01*
G01X3234833Y1438719D02*
Y1450126D01*
X3233122Y1447845D01*
G01Y1438719D02*
X3236544D01*
G01X3245956D02*
X3246241Y1441190D01*
X3246669Y1443282D01*
X3247239Y1445183D01*
X3247952Y1447274D01*
X3249093Y1450126D01*
X3243389D01*
G01X3236751Y-936637D02*
X3261621Y-921214D01*
G01X3239957Y-926738D02*
X3254597Y-904132D01*
G01X3237017Y-880024D02*
X3261412Y-867669D01*
G01X3238420Y-868774D02*
X3249497Y-846538D01*
G01D02*
X3252647D01*
G01X3241240Y-291925D02*
X3243996D01*
G01D02*
Y-275389D01*
G01X3241240D02*
Y-291925D01*
G01X3240452Y-271846D02*
Y-299208D01*
G01X3245177Y-291925D02*
X3247933D01*
G01X3249114D02*
X3251870D01*
G01X3249114Y-275389D02*
Y-291925D01*
G01X3247933D02*
Y-275389D01*
G01X3245177D02*
Y-291925D01*
G01X3243996Y-275389D02*
X3241240D01*
G01X3284547D02*
X3240452D01*
G01X3247933D02*
X3245177D01*
G01X3251870D02*
X3249114D01*
G01X3282578Y-269878D02*
X3242421D01*
G01D02*
X3240452Y-271846D01*
G01X3247000Y111572D02*
Y106043D01*
G01Y117854D02*
Y113079D01*
G01X3245523Y106043D02*
Y117854D01*
G01X3247000Y113079D02*
X3253889D01*
G01Y111572D02*
X3247000D01*
G01Y106043D02*
X3245523D01*
G01Y117854D02*
X3247000D01*
G01X3243386Y385582D02*
X3243381Y383795D01*
G01X3243372Y384063D02*
X3243376Y385850D01*
G01X3235512Y385582D02*
X3235507Y383795D01*
G01X3235498Y384063D02*
X3235502Y385850D01*
G01X3243240Y383346D02*
Y382362D01*
G01X3242374Y383346D02*
Y382362D01*
G01X3235366Y383346D02*
Y382362D01*
G01X3242237Y385850D02*
X3242242Y384063D01*
G01X3242233Y383795D02*
X3242228Y385582D01*
G01X3242242Y384063D02*
X3243372D01*
G01X3243381Y383795D02*
X3242233D01*
G01X3243362Y383346D02*
X3242252D01*
G01Y382362D02*
X3243362D01*
G01X3251260Y385582D02*
X3251255Y383795D01*
G01X3251246Y384063D02*
X3251250Y385850D01*
G01X3251114Y383346D02*
Y382362D01*
G01X3250248Y383346D02*
Y382362D01*
G01X3250111Y385850D02*
X3250116Y384063D01*
G01X3250107Y383795D02*
X3250102Y385582D01*
G01X3250116Y384063D02*
X3251246D01*
G01X3251255Y383795D02*
X3250107D01*
G01X3251236Y383346D02*
X3250126D01*
G01Y382362D02*
X3251236D01*
G01X3247337Y392106D02*
X3247350Y392767D01*
G01X3247348Y393694D02*
X3247317Y392106D01*
G01X3243400D02*
X3243413Y392767D01*
G01X3243411Y393694D02*
X3243380Y392106D01*
G01X3239463D02*
X3239476Y392767D01*
G01X3239474Y393694D02*
X3239443Y392106D01*
G01X3235526D02*
X3235539Y392767D01*
G01X3235537Y393694D02*
X3235506Y392106D01*
G01X3246109D02*
X3246119Y392697D01*
G01X3246116Y393607D02*
X3246091Y392106D01*
G01X3242172D02*
X3242182Y392697D01*
G01X3242179Y393607D02*
X3242154Y392106D01*
G01X3238235D02*
X3238245Y392697D01*
G01X3238242Y393607D02*
X3238217Y392106D01*
G01X3246179Y389519D02*
X3246174Y387732D01*
G01X3246165Y388000D02*
X3246170Y389787D01*
G01X3238305Y389519D02*
X3238300Y387732D01*
G01X3238291Y388000D02*
X3238296Y389787D01*
G01X3247332Y387283D02*
Y386299D01*
G01X3247177Y391220D02*
Y390236D01*
G01X3246311Y391220D02*
Y390236D01*
G01X3246156Y386299D02*
Y387283D01*
G01X3243395Y386299D02*
Y387283D01*
G01X3242219D02*
Y386299D01*
G01X3239458Y387283D02*
Y386299D01*
G01X3239303Y391220D02*
Y390236D01*
G01X3238437Y391220D02*
Y390236D01*
G01X3238282Y386299D02*
Y387283D01*
G01X3235521Y386299D02*
Y387283D01*
G01X3247318Y389787D02*
X3247323Y388000D01*
G01X3247313Y387732D02*
X3247309Y389519D01*
G01X3239444Y389787D02*
X3239449Y388000D01*
G01X3239439Y387732D02*
X3239435Y389519D01*
G01X3247396Y392106D02*
X3247372Y393607D01*
G01X3247369Y392697D02*
X3247379Y392106D01*
G01X3243459D02*
X3243435Y393607D01*
G01X3243432Y392697D02*
X3243442Y392106D01*
G01X3239522D02*
X3239498Y393607D01*
G01X3239495Y392697D02*
X3239505Y392106D01*
G01X3235585D02*
X3235561Y393607D01*
G01X3235558Y392697D02*
X3235568Y392106D01*
G01X3246171D02*
X3246140Y393694D01*
G01X3246138Y392767D02*
X3246151Y392106D01*
G01X3242234D02*
X3242203Y393694D01*
G01X3242201Y392767D02*
X3242214Y392106D01*
G01X3238297D02*
X3238266Y393694D01*
G01X3238264Y392767D02*
X3238277Y392106D01*
G01X3246129Y393977D02*
X3247359D01*
G01X3242192D02*
X3243422D01*
G01X3238255D02*
X3239485D01*
G01X3246140Y393694D02*
X3247348D01*
G01X3242203D02*
X3243411D01*
G01X3238266D02*
X3239474D01*
G01X3239498Y393607D02*
X3238242D01*
G01X3243435D02*
X3242179D01*
G01X3247372D02*
X3246116D01*
G01X3246129Y392993D02*
X3247359D01*
G01X3242192D02*
X3243422D01*
G01X3238255D02*
X3239485D01*
G01X3239476Y392767D02*
X3238264D01*
G01X3243413D02*
X3242201D01*
G01X3247350D02*
X3246138D01*
G01X3246119Y392697D02*
X3247369D01*
G01X3242182D02*
X3243432D01*
G01X3238245D02*
X3239495D01*
G01X3239425Y391220D02*
X3238315D01*
G01X3247299D02*
X3246189D01*
G01Y390236D02*
X3247299D01*
G01X3238315D02*
X3239425D01*
G01X3246170Y389787D02*
X3247318D01*
G01X3238296D02*
X3239444D01*
G01X3239435Y389519D02*
X3238305D01*
G01X3247309D02*
X3246179D01*
G01X3239449Y388000D02*
X3238291D01*
G01X3247323D02*
X3246165D01*
G01X3246174Y387732D02*
X3247313D01*
G01X3238300D02*
X3239439D01*
G01X3246156Y387283D02*
X3247332D01*
G01X3242219D02*
X3243395D01*
G01X3238282D02*
X3239458D01*
G01Y386299D02*
X3238282D01*
G01X3243395D02*
X3242219D01*
G01X3247332D02*
X3246156D01*
G01X3243376Y385850D02*
X3242237D01*
G01X3242228Y385582D02*
X3243386D01*
G01X3246140Y397604D02*
X3246171Y399193D01*
G01X3246151D02*
X3246138Y398532D01*
G01X3242203Y397604D02*
X3242234Y399193D01*
G01X3242214D02*
X3242201Y398532D01*
G01X3238266Y397604D02*
X3238297Y399193D01*
G01X3238277D02*
X3238264Y398532D01*
G01X3247372Y397691D02*
X3247396Y399193D01*
G01X3247379D02*
X3247369Y398602D01*
G01X3243435Y397691D02*
X3243459Y399193D01*
G01X3243442D02*
X3243432Y398602D01*
G01X3239498Y397691D02*
X3239522Y399193D01*
G01X3239505D02*
X3239495Y398602D01*
G01X3235561Y397691D02*
X3235585Y399193D01*
G01X3235568D02*
X3235558Y398602D01*
G01X3247177Y401063D02*
Y400078D01*
G01X3246311D02*
Y401063D01*
G01X3239303D02*
Y400078D01*
G01X3238437D02*
Y401063D01*
G01X3246119Y398602D02*
X3246109Y399193D01*
G01X3246091D02*
X3246116Y397691D01*
G01X3242182Y398602D02*
X3242172Y399193D01*
G01X3242154D02*
X3242179Y397691D01*
G01X3238245Y398602D02*
X3238235Y399193D01*
G01X3238217D02*
X3238242Y397691D01*
G01X3247350Y398532D02*
X3247337Y399193D01*
G01X3247317D02*
X3247348Y397604D01*
G01X3243413Y398532D02*
X3243400Y399193D01*
G01X3243380D02*
X3243411Y397604D01*
G01X3239476Y398532D02*
X3239463Y399193D01*
G01X3239443D02*
X3239474Y397604D01*
G01X3235539Y398532D02*
X3235526Y399193D01*
G01X3235506D02*
X3235537Y397604D01*
G01X3239425Y401063D02*
X3238315D01*
G01X3247299D02*
X3246189D01*
G01X3239425Y400078D02*
X3238315D01*
G01X3247299D02*
X3246189D01*
G01X3239495Y398602D02*
X3238245D01*
G01X3243432D02*
X3242182D01*
G01X3247369D02*
X3246119D01*
G01X3246138Y398532D02*
X3247350D01*
G01X3242201D02*
X3243413D01*
G01X3238264D02*
X3239476D01*
G01X3239485Y398306D02*
X3238255D01*
G01X3243422D02*
X3242192D01*
G01X3247359D02*
X3246129D01*
G01X3246116Y397691D02*
X3247372D01*
G01X3242179D02*
X3243435D01*
G01X3238242D02*
X3239498D01*
G01X3239474Y397604D02*
X3238266D01*
G01X3243411D02*
X3242203D01*
G01X3247348D02*
X3246140D01*
G01X3239485Y397322D02*
X3238255D01*
G01X3243422D02*
X3242192D01*
G01X3247359D02*
X3246129D01*
G01X3251274Y392106D02*
X3251287Y392767D01*
G01X3251285Y393694D02*
X3251254Y392106D01*
G01X3250046D02*
X3250056Y392697D01*
G01X3250053Y393607D02*
X3250028Y392106D01*
G01X3251269Y386299D02*
Y387283D01*
G01X3250093D02*
Y386299D01*
G01X3251333Y392106D02*
X3251309Y393607D01*
G01X3251306Y392697D02*
X3251316Y392106D01*
G01X3250108D02*
X3250077Y393694D01*
G01X3250075Y392767D02*
X3250088Y392106D01*
G01X3250066Y393977D02*
X3251296D01*
G01X3250077Y393694D02*
X3251285D01*
G01X3251309Y393607D02*
X3250053D01*
G01X3250066Y392993D02*
X3251296D01*
G01X3251287Y392767D02*
X3250075D01*
G01X3250056Y392697D02*
X3251306D01*
G01X3250093Y387283D02*
X3251269D01*
G01Y386299D02*
X3250093D01*
G01X3251250Y385850D02*
X3250111D01*
G01X3250102Y385582D02*
X3251260D01*
G01X3250077Y397604D02*
X3250108Y399193D01*
G01X3250088D02*
X3250075Y398532D01*
G01X3251309Y397691D02*
X3251333Y399193D01*
G01X3251316D02*
X3251306Y398602D01*
G01X3250056D02*
X3250046Y399193D01*
G01X3250028D02*
X3250053Y397691D01*
G01X3251287Y398532D02*
X3251274Y399193D01*
G01X3251254D02*
X3251285Y397604D01*
G01X3251306Y398602D02*
X3250056D01*
G01X3250075Y398532D02*
X3251287D01*
G01X3251296Y398306D02*
X3250066D01*
G01X3250053Y397691D02*
X3251309D01*
G01X3251285Y397604D02*
X3250077D01*
G01X3251296Y397322D02*
X3250066D01*
G01X3247323Y403299D02*
X3247318Y401512D01*
G01X3247309Y401779D02*
X3247313Y403567D01*
G01X3242242Y407236D02*
X3242237Y405449D01*
G01X3242228Y405716D02*
X3242233Y407504D01*
G01X3239449Y403299D02*
X3239444Y401512D01*
G01X3239435Y401779D02*
X3239439Y403567D01*
G01X3247332Y405000D02*
Y404015D01*
G01X3246468Y415728D02*
Y410118D01*
G01X3246156Y404015D02*
Y405000D01*
G01X3243395Y404015D02*
Y405000D01*
G01X3243240Y408937D02*
Y407952D01*
G01X3242374D02*
Y408937D01*
G01X3242219Y405000D02*
Y404015D01*
G01X3241468Y415728D02*
Y410118D01*
G01X3239458Y405000D02*
Y404015D01*
G01X3238282D02*
Y405000D01*
G01X3235521Y404015D02*
Y405000D01*
G01X3235366Y408937D02*
Y407952D01*
G01X3246174Y403567D02*
X3246179Y401779D01*
G01X3246170Y401512D02*
X3246165Y403299D01*
G01X3243381Y407504D02*
X3243386Y405716D01*
G01X3243376Y405449D02*
X3243372Y407236D01*
G01X3238300Y403567D02*
X3238305Y401779D01*
G01X3238296Y401512D02*
X3238291Y403299D01*
G01X3235507Y407504D02*
X3235512Y405716D01*
G01X3235502Y405449D02*
X3235498Y407236D01*
G01X3243362Y408937D02*
X3242252D01*
G01X3243362Y407952D02*
X3242252D01*
G01X3242233Y407504D02*
X3243381D01*
G01X3243372Y407236D02*
X3242242D01*
G01X3243386Y405716D02*
X3242228D01*
G01X3242237Y405449D02*
X3243376D01*
G01X3239458Y405000D02*
X3238282D01*
G01X3243395D02*
X3242219D01*
G01X3247332D02*
X3246156D01*
G01X3239458Y404015D02*
X3238282D01*
G01X3243395D02*
X3242219D01*
G01X3247332D02*
X3246156D01*
G01X3239439Y403567D02*
X3238300D01*
G01X3247313D02*
X3246174D01*
G01X3246165Y403299D02*
X3247323D01*
G01X3238291D02*
X3239449D01*
G01X3246179Y401779D02*
X3247309D01*
G01X3238305D02*
X3239435D01*
G01X3239444Y401512D02*
X3238296D01*
G01X3247318D02*
X3246170D01*
G01X3243791Y521633D02*
Y416712D01*
G01X3262374Y415728D02*
X3246468D01*
G01X3250116Y407236D02*
X3250111Y405449D01*
G01X3250102Y405716D02*
X3250107Y407504D01*
G01X3251269Y404015D02*
Y405000D01*
G01X3251114Y408937D02*
Y407952D01*
G01X3250248D02*
Y408937D01*
G01X3250093Y405000D02*
Y404015D01*
G01X3251255Y407504D02*
X3251260Y405716D01*
G01X3251250Y405449D02*
X3251246Y407236D01*
G01X3251236Y408937D02*
X3250126D01*
G01X3251236Y407952D02*
X3250126D01*
G01X3250107Y407504D02*
X3251255D01*
G01X3251246Y407236D02*
X3250116D01*
G01X3251260Y405716D02*
X3250102D01*
G01X3250111Y405449D02*
X3251250D01*
G01X3251269Y405000D02*
X3250093D01*
G01X3251269Y404015D02*
X3250093D01*
G01X3243791Y496383D02*
X3269041Y521633D01*
G01X3237689Y1080689D02*
G03X3241626Y1084626I0J3937D01*
G01Y1114153D02*
Y1084626D01*
G01X3245563Y1094074D02*
X3242807D01*
G01X3249500D02*
X3246744D01*
G01D02*
Y1106673D01*
G01X3245563Y1110610D02*
Y1094074D01*
G01X3242807D02*
Y1110610D01*
G01X3246744Y1106673D02*
X3249500D01*
G01X3253437Y1094074D02*
X3250681D01*
G01D02*
Y1110610D01*
G01X3249500Y1106673D02*
Y1094074D01*
G01X3268004Y1116122D02*
X3243594D01*
G01X3242807Y1110610D02*
X3245563D01*
G01X3269972D02*
X3241626D01*
G01X3243594Y1116122D02*
X3241626Y1114153D01*
G01X3250681Y1110610D02*
X3253437D01*
G01X3264771Y-921214D02*
X3371595D01*
G01X3261621D02*
X3264771D01*
G01X3267815Y-901966D02*
Y-896192D01*
G01Y-897636D02*
X3268249Y-896914D01*
X3268898Y-896336D01*
X3269764Y-896192D01*
X3270522Y-896336D01*
X3271172Y-896914D01*
X3271497Y-897924D01*
Y-901966D01*
G01X3257747Y-904132D02*
X3356775D01*
G01X3254597D02*
X3257747D01*
G01X3264562Y-867669D02*
X3371386D01*
G01X3261412D02*
X3264562D01*
G01X3262715Y-844373D02*
Y-838599D01*
G01Y-840043D02*
X3263149Y-839321D01*
X3263798Y-838743D01*
X3264664Y-838599D01*
X3265422Y-838743D01*
X3266072Y-839321D01*
X3266397Y-840331D01*
Y-844373D01*
G01X3252647Y-846538D02*
X3351676D01*
G01X3256988Y-291925D02*
X3259744D01*
G01X3253051D02*
X3255807D01*
G01X3259744D02*
Y-275389D01*
G01X3256988D02*
Y-291925D01*
G01X3255807D02*
Y-275389D01*
G01X3253051D02*
Y-291925D01*
G01X3251870D02*
Y-275389D01*
G01X3264862Y-291925D02*
X3267618D01*
G01X3260925D02*
X3263681D01*
G01X3267618D02*
Y-275389D01*
G01X3264862D02*
Y-291925D01*
G01X3263681D02*
Y-275389D01*
G01X3260925D02*
Y-291925D01*
G01X3255807Y-275389D02*
X3253051D01*
G01X3259744D02*
X3256988D01*
G01X3263681D02*
X3260925D01*
G01X3267618D02*
X3264862D01*
G01X3264962Y116849D02*
X3264224Y116095D01*
G01X3265700Y115844D02*
X3264716Y114336D01*
G01X3264224Y116095D02*
X3263732Y115090D01*
G01D02*
X3263486Y114336D01*
G01D02*
X3263240Y113079D01*
G01X3264716Y114336D02*
X3264470Y112828D01*
G01D02*
Y111069D01*
G01X3263240Y113079D02*
Y110818D01*
G01X3261271Y111069D02*
Y110064D01*
G01Y114085D02*
Y113079D01*
G01X3257334D02*
Y114085D01*
G01Y110064D02*
Y111069D01*
G01X3255366Y117854D02*
Y106043D01*
G01X3253889Y113079D02*
Y117854D01*
G01Y106043D02*
Y111572D01*
G01X3264470Y111069D02*
X3264716Y109561D01*
G01X3263240Y110818D02*
X3263486Y109561D01*
G01D02*
X3263732Y108807D01*
G01D02*
X3264224Y107802D01*
G01X3264716Y109561D02*
X3265700Y108054D01*
G01X3264224Y107802D02*
X3264962Y107048D01*
G01D02*
X3266193Y106294D01*
G01X3257334Y114085D02*
X3261271D01*
G01Y113079D02*
X3257334D01*
G01Y111069D02*
X3261271D01*
G01Y110064D02*
X3257334D01*
G01X3255366Y106043D02*
X3253889D01*
G01X3266193Y117603D02*
X3264962Y116849D01*
G01X3253889Y117854D02*
X3255366D01*
G01X3266439Y116346D02*
X3265700Y115844D01*
G01Y108054D02*
X3266439Y107551D01*
G01X3268899Y116346D02*
X3267669Y116598D01*
G01X3266439Y107551D02*
X3267669Y107300D01*
G01X3266193Y106294D02*
X3267669Y106043D01*
G01D02*
X3269145Y106294D01*
G01X3267669Y116598D02*
X3266439Y116346D01*
G01X3267669Y107300D02*
X3268899Y107551D01*
G01X3269145Y117603D02*
X3267669Y117854D01*
G01D02*
X3266193Y117603D01*
G01X3259134Y385582D02*
X3259129Y383795D01*
G01X3259120Y384063D02*
X3259124Y385850D01*
G01X3258988Y383346D02*
Y382362D01*
G01X3258122Y383346D02*
Y382362D01*
G01X3257985Y385850D02*
X3257990Y384063D01*
G01X3257981Y383795D02*
X3257976Y385582D01*
G01X3257990Y384063D02*
X3259120D01*
G01X3259129Y383795D02*
X3257981D01*
G01X3259110Y383346D02*
X3258000D01*
G01Y382362D02*
X3259110D01*
G01X3267008Y385582D02*
X3267003Y383795D01*
G01X3266994Y384063D02*
X3266998Y385850D01*
G01X3266862Y383346D02*
Y382362D01*
G01X3265996Y383346D02*
Y382362D01*
G01X3265859Y385850D02*
X3265864Y384063D01*
G01X3265855Y383795D02*
X3265850Y385582D01*
G01X3265864Y384063D02*
X3266994D01*
G01X3267003Y383795D02*
X3265855D01*
G01X3266984Y383346D02*
X3265874D01*
G01Y382362D02*
X3266984D01*
G01X3263085Y392106D02*
X3263098Y392767D01*
G01X3263096Y393694D02*
X3263065Y392106D01*
G01X3259148D02*
X3259161Y392767D01*
G01X3259159Y393694D02*
X3259128Y392106D01*
G01X3255211D02*
X3255224Y392767D01*
G01X3255222Y393694D02*
X3255191Y392106D01*
G01X3261857D02*
X3261867Y392697D01*
G01X3261864Y393607D02*
X3261839Y392106D01*
G01X3257920D02*
X3257930Y392697D01*
G01X3257927Y393607D02*
X3257902Y392106D01*
G01X3253983D02*
X3253993Y392697D01*
G01X3253990Y393607D02*
X3253965Y392106D01*
G01X3261927Y389519D02*
X3261922Y387732D01*
G01X3261913Y388000D02*
X3261918Y389787D01*
G01X3254053Y389519D02*
X3254048Y387732D01*
G01X3254039Y388000D02*
X3254044Y389787D01*
G01X3263080Y386299D02*
Y387283D01*
G01X3262925Y391220D02*
Y390236D01*
G01X3262059Y391220D02*
Y390236D01*
G01X3261904Y387283D02*
Y386299D01*
G01X3259143D02*
Y387283D01*
G01X3257967D02*
Y386299D01*
G01X3255206Y387283D02*
Y386299D01*
G01X3255051Y391220D02*
Y390236D01*
G01X3254185Y391220D02*
Y390236D01*
G01X3254030Y386299D02*
Y387283D01*
G01X3263066Y389787D02*
X3263071Y388000D01*
G01X3263061Y387732D02*
X3263057Y389519D01*
G01X3255192Y389787D02*
X3255197Y388000D01*
G01X3255187Y387732D02*
X3255183Y389519D01*
G01X3263145Y392106D02*
X3263120Y393607D01*
G01X3263117Y392697D02*
X3263127Y392106D01*
G01X3259207D02*
X3259183Y393607D01*
G01X3259180Y392697D02*
X3259190Y392106D01*
G01X3255270D02*
X3255246Y393607D01*
G01X3255243Y392697D02*
X3255253Y392106D01*
G01X3261919D02*
X3261888Y393694D01*
G01X3261886Y392767D02*
X3261899Y392106D01*
G01X3257982D02*
X3257951Y393694D01*
G01X3257949Y392767D02*
X3257962Y392106D01*
G01X3254045D02*
X3254014Y393694D01*
G01X3254012Y392767D02*
X3254025Y392106D01*
G01X3261877Y393977D02*
X3263107D01*
G01X3257940D02*
X3259170D01*
G01X3254003D02*
X3255233D01*
G01X3261888Y393694D02*
X3263096D01*
G01X3257951D02*
X3259159D01*
G01X3254014D02*
X3255222D01*
G01X3255246Y393607D02*
X3253990D01*
G01X3259183D02*
X3257927D01*
G01X3263120D02*
X3261864D01*
G01X3261877Y392993D02*
X3263107D01*
G01X3257940D02*
X3259170D01*
G01X3254003D02*
X3255233D01*
G01X3255224Y392767D02*
X3254012D01*
G01X3259161D02*
X3257949D01*
G01X3263098D02*
X3261886D01*
G01X3261867Y392697D02*
X3263117D01*
G01X3257930D02*
X3259180D01*
G01X3253993D02*
X3255243D01*
G01X3255173Y391220D02*
X3254063D01*
G01X3263047D02*
X3261937D01*
G01Y390236D02*
X3263047D01*
G01X3254063D02*
X3255173D01*
G01X3261918Y389787D02*
X3263066D01*
G01X3254044D02*
X3255192D01*
G01X3255183Y389519D02*
X3254053D01*
G01X3263057D02*
X3261927D01*
G01X3255197Y388000D02*
X3254039D01*
G01X3263071D02*
X3261913D01*
G01X3261922Y387732D02*
X3263061D01*
G01X3254048D02*
X3255187D01*
G01X3261904Y387283D02*
X3263080D01*
G01X3257967D02*
X3259143D01*
G01X3254030D02*
X3255206D01*
G01Y386299D02*
X3254030D01*
G01X3259143D02*
X3257967D01*
G01X3263080D02*
X3261904D01*
G01X3259124Y385850D02*
X3257985D01*
G01X3257976Y385582D02*
X3259134D01*
G01X3261888Y397604D02*
X3261919Y399193D01*
G01X3261899D02*
X3261886Y398532D01*
G01X3257951Y397604D02*
X3257982Y399193D01*
G01X3257962D02*
X3257949Y398532D01*
G01X3254014Y397604D02*
X3254045Y399193D01*
G01X3254025D02*
X3254012Y398532D01*
G01X3263120Y397691D02*
X3263145Y399193D01*
G01X3263127D02*
X3263117Y398602D01*
G01X3259183Y397691D02*
X3259207Y399193D01*
G01X3259190D02*
X3259180Y398602D01*
G01X3255246Y397691D02*
X3255270Y399193D01*
G01X3255253D02*
X3255243Y398602D01*
G01X3262925Y401063D02*
Y400078D01*
G01X3262059D02*
Y401063D01*
G01X3255051D02*
Y400078D01*
G01X3254185D02*
Y401063D01*
G01X3261867Y398602D02*
X3261857Y399193D01*
G01X3261839D02*
X3261864Y397691D01*
G01X3257930Y398602D02*
X3257920Y399193D01*
G01X3257902D02*
X3257927Y397691D01*
G01X3253993Y398602D02*
X3253983Y399193D01*
G01X3253965D02*
X3253990Y397691D01*
G01X3263098Y398532D02*
X3263085Y399193D01*
G01X3263065D02*
X3263096Y397604D01*
G01X3259161Y398532D02*
X3259148Y399193D01*
G01X3259128D02*
X3259159Y397604D01*
G01X3255224Y398532D02*
X3255211Y399193D01*
G01X3255191D02*
X3255222Y397604D01*
G01X3255173Y401063D02*
X3254063D01*
G01X3263047D02*
X3261937D01*
G01X3255173Y400078D02*
X3254063D01*
G01X3263047D02*
X3261937D01*
G01X3255243Y398602D02*
X3253993D01*
G01X3259180D02*
X3257930D01*
G01X3263117D02*
X3261867D01*
G01X3261886Y398532D02*
X3263098D01*
G01X3257949D02*
X3259161D01*
G01X3254012D02*
X3255224D01*
G01X3255233Y398306D02*
X3254003D01*
G01X3259170D02*
X3257940D01*
G01X3263107D02*
X3261877D01*
G01X3261864Y397691D02*
X3263120D01*
G01X3257927D02*
X3259183D01*
G01X3253990D02*
X3255246D01*
G01X3255222Y397604D02*
X3254014D01*
G01X3259159D02*
X3257951D01*
G01X3263096D02*
X3261888D01*
G01X3255233Y397322D02*
X3254003D01*
G01X3259170D02*
X3257940D01*
G01X3263107D02*
X3261877D01*
G01X3267022Y392106D02*
X3267035Y392767D01*
G01X3267033Y393694D02*
X3267002Y392106D01*
G01X3265794D02*
X3265804Y392697D01*
G01X3265801Y393607D02*
X3265776Y392106D01*
G01X3267017Y386299D02*
Y387283D01*
G01X3265841D02*
Y386299D01*
G01X3267082Y392106D02*
X3267057Y393607D01*
G01X3267054Y392697D02*
X3267064Y392106D01*
G01X3265856D02*
X3265825Y393694D01*
G01X3265823Y392767D02*
X3265836Y392106D01*
G01X3265814Y393977D02*
X3267044D01*
G01X3265825Y393694D02*
X3267033D01*
G01X3267057Y393607D02*
X3265801D01*
G01X3265814Y392993D02*
X3267044D01*
G01X3267035Y392767D02*
X3265823D01*
G01X3265804Y392697D02*
X3267054D01*
G01X3265841Y387283D02*
X3267017D01*
G01Y386299D02*
X3265841D01*
G01X3266998Y385850D02*
X3265859D01*
G01X3265850Y385582D02*
X3267008D01*
G01X3265825Y397604D02*
X3265856Y399193D01*
G01X3265836D02*
X3265823Y398532D01*
G01X3267057Y397691D02*
X3267082Y399193D01*
G01X3267064D02*
X3267054Y398602D01*
G01X3265804D02*
X3265794Y399193D01*
G01X3265776D02*
X3265801Y397691D01*
G01X3267035Y398532D02*
X3267022Y399193D01*
G01X3267002D02*
X3267033Y397604D01*
G01X3267054Y398602D02*
X3265804D01*
G01X3265823Y398532D02*
X3267035D01*
G01X3267044Y398306D02*
X3265814D01*
G01X3265801Y397691D02*
X3267057D01*
G01X3267033Y397604D02*
X3265825D01*
G01X3267044Y397322D02*
X3265814D01*
G01X3263071Y403299D02*
X3263066Y401512D01*
G01X3263057Y401779D02*
X3263061Y403567D01*
G01X3257990Y407236D02*
X3257985Y405449D01*
G01X3257976Y405716D02*
X3257981Y407504D01*
G01X3255197Y403299D02*
X3255192Y401512D01*
G01X3255183Y401779D02*
X3255187Y403567D01*
G01X3263080Y405000D02*
Y404015D01*
G01X3262374Y415728D02*
Y410118D01*
G01X3261904Y404015D02*
Y405000D01*
G01X3259143Y404015D02*
Y405000D01*
G01X3258988Y408937D02*
Y407952D01*
G01X3258122D02*
Y408937D01*
G01X3257967Y405000D02*
Y404015D01*
G01X3255206Y405000D02*
Y404015D01*
G01X3254030D02*
Y405000D01*
G01X3261922Y403567D02*
X3261927Y401779D01*
G01X3261918Y401512D02*
X3261913Y403299D01*
G01X3259129Y407504D02*
X3259134Y405716D01*
G01X3259124Y405449D02*
X3259120Y407236D01*
G01X3254048Y403567D02*
X3254053Y401779D01*
G01X3254044Y401512D02*
X3254039Y403299D01*
G01X3259110Y408937D02*
X3258000D01*
G01X3259110Y407952D02*
X3258000D01*
G01X3257981Y407504D02*
X3259129D01*
G01X3259120Y407236D02*
X3257990D01*
G01X3259134Y405716D02*
X3257976D01*
G01X3257985Y405449D02*
X3259124D01*
G01X3255206Y405000D02*
X3254030D01*
G01X3259143D02*
X3257967D01*
G01X3263080D02*
X3261904D01*
G01X3255206Y404015D02*
X3254030D01*
G01X3259143D02*
X3257967D01*
G01X3263080D02*
X3261904D01*
G01X3255187Y403567D02*
X3254048D01*
G01X3263061D02*
X3261922D01*
G01X3261913Y403299D02*
X3263071D01*
G01X3254039D02*
X3255197D01*
G01X3261927Y401779D02*
X3263057D01*
G01X3254053D02*
X3255183D01*
G01X3255192Y401512D02*
X3254044D01*
G01X3263066D02*
X3261918D01*
G01X3265864Y407236D02*
X3265859Y405449D01*
G01X3265850Y405716D02*
X3265855Y407504D01*
G01X3267374Y415728D02*
Y410118D01*
G01X3267017Y405000D02*
Y404015D01*
G01X3266862Y408937D02*
Y407952D01*
G01X3265996D02*
Y408937D01*
G01X3265841Y404015D02*
Y405000D01*
G01X3267003Y407504D02*
X3267008Y405716D01*
G01X3266998Y405449D02*
X3266994Y407236D01*
G01X3266984Y408937D02*
X3265874D01*
G01X3266984Y407952D02*
X3265874D01*
G01X3265855Y407504D02*
X3267003D01*
G01X3266994Y407236D02*
X3265864D01*
G01X3267008Y405716D02*
X3265850D01*
G01X3265859Y405449D02*
X3266998D01*
G01X3267017Y405000D02*
X3265841D01*
G01X3267017Y404015D02*
X3265841D01*
G01X3283279Y415728D02*
X3267374D01*
G01X3274696Y446043D02*
G03I-6299J0D01*
G01X3264459Y463172D02*
Y457431D01*
G01X3263203D02*
Y463172D01*
G01X3259224Y456200D02*
Y457431D01*
G01X3264459D02*
X3269067D01*
G01X3259224D02*
X3263203D01*
G01X3269067Y456200D02*
X3259224D01*
G01X3264878Y466043D02*
Y469324D01*
G01X3263203D02*
Y466043D01*
G01X3262365D02*
Y469324D01*
G01X3259224Y463172D02*
Y464402D01*
G01X3263203Y466043D02*
X3262365D01*
G01X3265716D02*
X3264878D01*
G01X3259224Y464402D02*
X3269067D01*
G01X3263203Y463172D02*
X3259224D01*
G01X3269067D02*
X3264459D01*
G01X3265716Y469324D02*
Y466043D01*
G01X3259224Y474655D02*
X3259433Y473425D01*
G01X3260271Y474655D02*
X3260481Y473630D01*
G01X3261528Y477936D02*
X3260690Y477526D01*
G01X3262156Y477116D02*
X3260900Y476296D01*
G01X3260690Y477526D02*
X3260062Y476911D01*
G01X3260900Y476296D02*
X3260481Y475680D01*
G01X3260062Y476911D02*
X3259433Y475885D01*
G01X3260481Y475680D02*
X3260271Y474655D01*
G01X3259433Y475885D02*
X3259224Y474655D01*
G01X3259433Y473425D02*
X3260062Y472400D01*
G01X3260481Y473630D02*
X3260900Y473015D01*
G01X3260062Y472400D02*
X3260690Y471784D01*
G01X3260900Y473015D02*
X3262156Y472194D01*
G01X3260690Y471784D02*
X3261528Y471374D01*
G01D02*
X3262156Y471169D01*
G01D02*
X3263203Y470964D01*
G01X3266135Y477116D02*
X3264878Y477321D01*
G01X3262156Y472194D02*
X3263413Y471989D01*
G01X3264878Y477321D02*
X3263413D01*
G01Y471989D02*
X3264878D01*
G01X3263203Y470964D02*
X3265088D01*
G01X3264878Y469324D02*
X3265716D01*
G01X3262365D02*
X3263203D01*
G01X3263413Y477321D02*
X3262156Y477116D01*
G01X3264878Y471989D02*
X3266135Y472194D01*
G01X3263203Y482037D02*
X3263413Y481422D01*
G01X3262575D02*
X3262365Y482037D01*
G01X3262156Y478141D02*
X3261528Y477936D01*
G01X3264041Y483267D02*
X3263622Y483062D01*
G01D02*
X3263413Y482857D01*
G01D02*
X3263203Y482447D01*
G01X3262365Y482857D02*
X3262575Y483472D01*
G01X3263203Y482447D02*
Y482037D01*
G01X3262365D02*
Y482857D01*
G01Y479987D02*
Y481012D01*
G01X3263413Y481422D02*
X3263831Y481012D01*
G01X3262994D02*
X3262575Y481422D01*
G01X3269067Y483267D02*
X3264041D01*
G01X3262365Y481012D02*
X3262994D01*
G01X3263831D02*
X3269067D01*
G01Y479987D02*
X3262365D01*
G01X3265088Y478346D02*
X3263203D01*
G01D02*
X3262156Y478141D01*
G01X3268020Y474655D02*
X3267810Y475680D01*
G01D02*
X3267391Y476296D01*
G01X3266135Y471169D02*
X3266763Y471374D01*
G01D02*
X3267601Y471784D01*
G01X3266135Y472194D02*
X3267391Y473015D01*
G01X3267601Y471784D02*
X3268229Y472400D01*
G01X3267391Y473015D02*
X3267810Y473630D01*
G01D02*
X3268020Y474655D01*
G01X3268229Y476911D02*
X3267601Y477526D01*
G01X3267391Y476296D02*
X3266135Y477116D01*
G01X3267601Y477526D02*
X3266763Y477936D01*
G01X3265088Y470964D02*
X3266135Y471169D01*
G01X3266763Y477936D02*
X3266135Y478141D01*
G01D02*
X3265088Y478346D01*
G01X3262575Y493930D02*
X3262365Y494545D01*
G01X3263203Y491265D02*
X3263413Y490649D01*
G01X3262575D02*
X3262365Y491265D01*
G01X3262575Y484703D02*
X3262365Y485318D01*
G01X3263203Y494340D02*
X3263413Y493930D01*
G01X3263203Y485113D02*
X3263413Y484703D01*
G01Y493930D02*
X3263622Y493725D01*
G01X3263203Y493315D02*
X3262575Y493930D01*
G01X3262994Y487163D02*
X3264041Y487574D01*
G01Y486548D02*
X3263622Y486343D01*
G01X3264041Y492495D02*
X3263622Y492290D01*
G01X3262575Y483472D02*
X3263203Y484087D01*
G01X3263622Y486343D02*
X3263413Y486138D01*
G01X3262575Y486753D02*
X3262994Y487163D01*
G01X3263622Y492290D02*
X3263413Y492085D01*
G01X3262575Y492700D02*
X3263203Y493315D01*
G01X3263413Y486138D02*
X3263203Y485728D01*
G01X3263413Y492085D02*
X3263203Y491674D01*
G01X3262365Y486138D02*
X3262575Y486753D01*
G01X3262365Y492085D02*
X3262575Y492700D01*
G01X3263203Y485728D02*
Y485113D01*
G01Y491674D02*
Y491265D01*
G01X3262365D02*
Y492085D01*
G01Y489214D02*
Y490239D01*
G01Y485318D02*
Y486138D01*
G01X3263413Y490649D02*
X3263831Y490239D01*
G01X3262994D02*
X3262575Y490649D01*
G01X3263413Y484703D02*
X3263622Y484498D01*
G01X3263203Y484087D02*
X3262575Y484703D01*
G01X3263622Y493725D02*
X3264041Y493520D01*
G01X3263622Y484498D02*
X3264041Y484293D01*
G01Y493520D02*
X3269067D01*
G01Y492495D02*
X3264041D01*
G01X3262365Y490239D02*
X3262994D01*
G01X3263831D02*
X3269067D01*
G01Y489214D02*
X3262365D01*
G01X3264041Y487574D02*
X3269067D01*
G01Y486548D02*
X3264041D01*
G01Y484293D02*
X3269067D01*
G01X3274696Y503130D02*
G03I-6299J0D01*
G01X3262994Y496391D02*
X3264041Y496801D01*
G01Y495776D02*
X3263622Y495570D01*
G01D02*
X3263413Y495365D01*
G01X3262575Y495981D02*
X3262994Y496391D01*
G01X3263413Y495365D02*
X3263203Y494956D01*
G01X3262365Y495365D02*
X3262575Y495981D01*
G01X3263203Y494956D02*
Y494340D01*
G01X3262365Y494545D02*
Y495365D01*
G01X3264041Y496801D02*
X3269067D01*
G01Y495776D02*
X3264041D01*
G01X3266232Y552392D02*
X3257571D01*
X3259303Y551093D01*
G01X3266232D02*
Y553691D01*
G01Y561053D02*
X3266088Y561811D01*
X3265655Y562677D01*
X3264933Y563218D01*
X3263922Y563435D01*
X3262912Y563218D01*
X3262046Y562569D01*
X3261613Y561594D01*
Y560512D01*
X3261324Y559862D01*
X3260602Y559321D01*
X3259592Y559104D01*
X3258581Y559429D01*
X3257860Y560187D01*
X3257571Y561053D01*
X3257860Y561919D01*
X3258581Y562677D01*
X3259592Y563002D01*
X3260602Y562785D01*
X3261324Y562244D01*
X3261613Y561594D01*
Y560512D01*
X3262046Y559537D01*
X3262912Y558888D01*
X3263922Y558671D01*
X3264933Y558888D01*
X3265655Y559429D01*
X3266088Y560295D01*
X3266232Y561053D01*
G01Y569714D02*
X3266088Y570472D01*
X3265655Y571338D01*
X3264933Y571879D01*
X3263922Y572096D01*
X3262912Y571879D01*
X3262046Y571230D01*
X3261613Y570255D01*
Y569173D01*
X3261324Y568523D01*
X3260602Y567982D01*
X3259592Y567765D01*
X3258581Y568090D01*
X3257860Y568848D01*
X3257571Y569714D01*
X3257860Y570580D01*
X3258581Y571338D01*
X3259592Y571663D01*
X3260602Y571446D01*
X3261324Y570905D01*
X3261613Y570255D01*
Y569173D01*
X3262046Y568198D01*
X3262912Y567549D01*
X3263922Y567332D01*
X3264933Y567549D01*
X3265655Y568090D01*
X3266088Y568956D01*
X3266232Y569714D01*
G01X3266521Y578375D02*
X3266376Y578158D01*
X3266088D01*
X3265943Y578375D01*
X3266088Y578592D01*
X3266376D01*
X3266521Y578375D01*
G01X3265222Y585195D02*
X3265943Y585953D01*
X3266232Y586819D01*
X3265943Y587686D01*
X3265077Y588443D01*
X3263778Y588985D01*
X3262479Y589201D01*
X3260891D01*
X3259592Y588985D01*
X3258437Y588443D01*
X3257860Y587794D01*
X3257571Y587036D01*
X3257860Y586170D01*
X3258437Y585520D01*
X3259303Y585087D01*
X3260458Y584871D01*
X3261468Y585087D01*
X3262479Y585629D01*
X3263056Y586278D01*
X3263201Y587036D01*
X3262912Y587902D01*
X3262190Y588552D01*
X3260891Y589201D01*
G01X3264933Y593315D02*
X3265655Y593965D01*
X3266088Y594723D01*
X3266232Y595697D01*
X3265943Y596671D01*
X3265366Y597429D01*
X3264356Y597971D01*
X3263201Y598079D01*
X3262046Y597862D01*
X3261324Y597321D01*
X3260747Y596563D01*
X3260602Y595805D01*
X3260747Y595047D01*
X3261324Y594073D01*
X3257571Y594398D01*
Y597321D01*
G01X3257374Y1094074D02*
X3254618D01*
G01X3261311D02*
X3258555D01*
G01X3265248D02*
X3262492D01*
G01D02*
Y1110610D01*
G01X3261311D02*
Y1094074D01*
G01X3258555D02*
Y1110610D01*
G01X3257374D02*
Y1094074D01*
G01X3254618D02*
Y1110610D01*
G01X3253437D02*
Y1094074D01*
G01X3269185D02*
X3266429D01*
G01D02*
Y1110610D01*
G01X3265248D02*
Y1094074D01*
G01X3262492Y1110610D02*
X3265248D01*
G01X3258555D02*
X3261311D01*
G01X3254618D02*
X3257374D01*
G01X3266429D02*
X3269185D01*
G01X3269972Y1114153D02*
X3268004Y1116122D01*
G01X3271547Y1166181D02*
X3262886D01*
X3264618Y1164882D01*
G01X3271547D02*
Y1167480D01*
G01X3270537Y1173001D02*
X3271258Y1173759D01*
X3271547Y1174625D01*
X3271258Y1175492D01*
X3270392Y1176249D01*
X3269093Y1176791D01*
X3267794Y1177007D01*
X3266206D01*
X3264907Y1176791D01*
X3263752Y1176249D01*
X3263175Y1175600D01*
X3262886Y1174842D01*
X3263175Y1173976D01*
X3263752Y1173326D01*
X3264618Y1172893D01*
X3265773Y1172677D01*
X3266783Y1172893D01*
X3267794Y1173435D01*
X3268371Y1174084D01*
X3268516Y1174842D01*
X3268227Y1175708D01*
X3267505Y1176358D01*
X3266206Y1177007D01*
G01X3262886Y1183503D02*
X3263175Y1182637D01*
X3263896Y1181987D01*
X3264762Y1181554D01*
X3265917Y1181229D01*
X3267217Y1181121D01*
X3268516Y1181229D01*
X3269671Y1181554D01*
X3270537Y1181987D01*
X3271258Y1182637D01*
X3271547Y1183503D01*
X3271258Y1184369D01*
X3270537Y1185019D01*
X3269671Y1185452D01*
X3268516Y1185777D01*
X3267217Y1185885D01*
X3265917Y1185777D01*
X3264762Y1185452D01*
X3263896Y1185019D01*
X3263175Y1184369D01*
X3262886Y1183503D01*
G01X3271836Y1192164D02*
X3271691Y1191947D01*
X3271403D01*
X3271258Y1192164D01*
X3271403Y1192381D01*
X3271691D01*
X3271836Y1192164D01*
G01X3269815Y1198443D02*
X3270825Y1199093D01*
X3271403Y1199959D01*
X3271547Y1200933D01*
X3271403Y1201799D01*
X3270681Y1202666D01*
X3269815Y1203207D01*
X3268949Y1203315D01*
X3267938Y1203099D01*
X3267217Y1202341D01*
X3266928Y1201583D01*
Y1200608D01*
G01Y1201583D02*
X3266495Y1202232D01*
X3265773Y1202774D01*
X3264907Y1202990D01*
X3264041Y1202774D01*
X3263319Y1202232D01*
X3262886Y1201258D01*
X3263030Y1200284D01*
X3263608Y1199309D01*
G01X3262886Y1209486D02*
X3263175Y1208620D01*
X3263896Y1207970D01*
X3264762Y1207537D01*
X3265917Y1207212D01*
X3267217Y1207104D01*
X3268516Y1207212D01*
X3269671Y1207537D01*
X3270537Y1207970D01*
X3271258Y1208620D01*
X3271547Y1209486D01*
X3271258Y1210352D01*
X3270537Y1211002D01*
X3269671Y1211435D01*
X3268516Y1211760D01*
X3267217Y1211868D01*
X3265917Y1211760D01*
X3264762Y1211435D01*
X3263896Y1211002D01*
X3263175Y1210352D01*
X3262886Y1209486D01*
G01X3274839Y-919049D02*
Y-913275D01*
G01Y-914719D02*
X3275273Y-913997D01*
X3275922Y-913419D01*
X3276788Y-913275D01*
X3277546Y-913419D01*
X3278196Y-913997D01*
X3278521Y-915007D01*
Y-919049D01*
G01X3281205Y-901966D02*
X3281963Y-901822D01*
X3282829Y-901389D01*
X3283370Y-900667D01*
X3283587Y-899656D01*
X3283370Y-898646D01*
X3282721Y-897780D01*
X3281746Y-897347D01*
X3280664D01*
X3280014Y-897058D01*
X3279473Y-896336D01*
X3279256Y-895326D01*
X3279581Y-894315D01*
X3280339Y-893594D01*
X3281205Y-893305D01*
X3282071Y-893594D01*
X3282829Y-894315D01*
X3283154Y-895326D01*
X3282937Y-896336D01*
X3282396Y-897058D01*
X3281746Y-897347D01*
X3280664D01*
X3279689Y-897780D01*
X3279040Y-898646D01*
X3278823Y-899656D01*
X3279040Y-900667D01*
X3279581Y-901389D01*
X3280447Y-901822D01*
X3281205Y-901966D01*
G01X3289866Y-902255D02*
X3289649Y-902110D01*
Y-901822D01*
X3289866Y-901677D01*
X3290083Y-901822D01*
Y-902110D01*
X3289866Y-902255D01*
G01X3298527Y-893305D02*
X3297661Y-893594D01*
X3297011Y-894315D01*
X3296578Y-895181D01*
X3296253Y-896336D01*
X3296145Y-897636D01*
X3296253Y-898935D01*
X3296578Y-900090D01*
X3297011Y-900956D01*
X3297661Y-901677D01*
X3298527Y-901966D01*
X3299393Y-901677D01*
X3300043Y-900956D01*
X3300476Y-900090D01*
X3300801Y-898935D01*
X3300909Y-897636D01*
X3300801Y-896336D01*
X3300476Y-895181D01*
X3300043Y-894315D01*
X3299393Y-893594D01*
X3298527Y-893305D01*
G01X3307188D02*
X3306322Y-893594D01*
X3305672Y-894315D01*
X3305239Y-895181D01*
X3304914Y-896336D01*
X3304806Y-897636D01*
X3304914Y-898935D01*
X3305239Y-900090D01*
X3305672Y-900956D01*
X3306322Y-901677D01*
X3307188Y-901966D01*
X3308054Y-901677D01*
X3308704Y-900956D01*
X3309137Y-900090D01*
X3309462Y-898935D01*
X3309570Y-897636D01*
X3309462Y-896336D01*
X3309137Y-895181D01*
X3308704Y-894315D01*
X3308054Y-893594D01*
X3307188Y-893305D01*
G01X3274630Y-865504D02*
Y-859730D01*
G01Y-861174D02*
X3275064Y-860452D01*
X3275713Y-859874D01*
X3276579Y-859730D01*
X3277337Y-859874D01*
X3277987Y-860452D01*
X3278312Y-861462D01*
Y-865504D01*
G01X3276105Y-844373D02*
X3276863Y-844229D01*
X3277729Y-843796D01*
X3278270Y-843074D01*
X3278487Y-842063D01*
X3278270Y-841053D01*
X3277621Y-840187D01*
X3276646Y-839754D01*
X3275564D01*
X3274914Y-839465D01*
X3274373Y-838743D01*
X3274156Y-837733D01*
X3274481Y-836722D01*
X3275239Y-836001D01*
X3276105Y-835712D01*
X3276971Y-836001D01*
X3277729Y-836722D01*
X3278054Y-837733D01*
X3277837Y-838743D01*
X3277296Y-839465D01*
X3276646Y-839754D01*
X3275564D01*
X3274589Y-840187D01*
X3273940Y-841053D01*
X3273723Y-842063D01*
X3273940Y-843074D01*
X3274481Y-843796D01*
X3275347Y-844229D01*
X3276105Y-844373D01*
G01X3284766Y-844662D02*
X3284549Y-844517D01*
Y-844229D01*
X3284766Y-844084D01*
X3284983Y-844229D01*
Y-844517D01*
X3284766Y-844662D01*
G01X3293427Y-835712D02*
X3292561Y-836001D01*
X3291911Y-836722D01*
X3291478Y-837588D01*
X3291153Y-838743D01*
X3291045Y-840043D01*
X3291153Y-841342D01*
X3291478Y-842497D01*
X3291911Y-843363D01*
X3292561Y-844084D01*
X3293427Y-844373D01*
X3294293Y-844084D01*
X3294943Y-843363D01*
X3295376Y-842497D01*
X3295701Y-841342D01*
X3295809Y-840043D01*
X3295701Y-838743D01*
X3295376Y-837588D01*
X3294943Y-836722D01*
X3294293Y-836001D01*
X3293427Y-835712D01*
G01X3302088D02*
X3301222Y-836001D01*
X3300572Y-836722D01*
X3300139Y-837588D01*
X3299814Y-838743D01*
X3299706Y-840043D01*
X3299814Y-841342D01*
X3300139Y-842497D01*
X3300572Y-843363D01*
X3301222Y-844084D01*
X3302088Y-844373D01*
X3302954Y-844084D01*
X3303604Y-843363D01*
X3304037Y-842497D01*
X3304362Y-841342D01*
X3304470Y-840043D01*
X3304362Y-838743D01*
X3304037Y-837588D01*
X3303604Y-836722D01*
X3302954Y-836001D01*
X3302088Y-835712D01*
G01X3276673Y-291925D02*
X3279429D01*
G01X3268799D02*
X3271555D01*
G01X3272736D02*
X3275492D01*
G01X3276673Y-275389D02*
Y-291925D01*
G01X3275492D02*
Y-275389D01*
G01X3272736D02*
Y-291925D01*
G01X3271555D02*
Y-275389D01*
G01X3268799D02*
Y-291925D01*
G01X3284547Y-301374D02*
G03X3288484Y-305311I3937J0D01*
G01X3284547Y-301374D02*
Y-271846D01*
G01X3280610Y-291925D02*
X3283366D01*
G01D02*
Y-279326D01*
G01X3280610D02*
Y-291925D01*
G01X3279429D02*
Y-275389D01*
G01X3271555D02*
X3268799D01*
G01X3275492D02*
X3272736D01*
G01X3279429D02*
X3276673D01*
G01X3283366Y-279326D02*
X3280610D01*
G01X3274429Y-267830D02*
X3273444D01*
G01D02*
X3276069Y-259956D01*
G01X3275085Y-265820D02*
X3274429Y-267830D01*
G01X3276069Y-259956D02*
X3277381D01*
G01X3278201Y-265150D02*
X3275249D01*
G01X3278366Y-265820D02*
X3275085D01*
G01X3276725Y-260627D02*
X3278201Y-265150D01*
G01X3275249D02*
X3276725Y-260627D01*
G01X3280006Y-267830D02*
X3279022D01*
G01X3283287D02*
X3282303D01*
G01X3284547Y-271846D02*
X3282578Y-269878D01*
G01X3279022Y-267830D02*
X3278366Y-265820D01*
G01X3277381Y-259956D02*
X3280006Y-267830D01*
G01X3283287Y-259956D02*
Y-267830D01*
G01X3282303D02*
Y-261297D01*
G01Y-259956D02*
X3283287D01*
G01X3281318Y-262469D02*
Y-261129D01*
G01X3282303Y-261297D02*
X3281318Y-262469D01*
G01Y-261129D02*
X3282303Y-259956D01*
G01X3279726Y113833D02*
X3280464Y114085D01*
G01X3276527Y113079D02*
X3275789Y112828D01*
G01Y113833D02*
X3276527Y114085D01*
G01X3280218Y113079D02*
X3279726Y112828D01*
G01X3269145Y106294D02*
X3270376Y107048D01*
G01X3268899Y107551D02*
X3269637Y108054D01*
G01X3279726Y112828D02*
X3279480Y112577D01*
G01X3278988Y113079D02*
X3279726Y113833D01*
G01X3270376Y107048D02*
X3271114Y107802D01*
G01X3275789Y112828D02*
X3275297Y112326D01*
G01Y113331D02*
X3275789Y113833D01*
G01X3269637Y108054D02*
X3270622Y109561D01*
G01X3279480Y112577D02*
X3279234Y112074D01*
G01X3271114Y107802D02*
X3271606Y108807D01*
G01D02*
X3271852Y109561D01*
G01D02*
X3272098Y110818D01*
G01X3270622Y109561D02*
X3270868Y111069D01*
G01X3279234Y112074D02*
Y106043D01*
G01X3278004D02*
Y112074D01*
G01X3275297Y114085D02*
Y113331D01*
G01Y112326D02*
Y106043D01*
G01X3274067D02*
Y114085D01*
G01X3272098Y110818D02*
Y113079D01*
G01X3270868Y111069D02*
Y112828D01*
G01D02*
X3270622Y114336D01*
G01X3272098Y113079D02*
X3271852Y114336D01*
G01D02*
X3271606Y115090D01*
G01X3278004Y112074D02*
X3277757Y112577D01*
G01X3271606Y115090D02*
X3271114Y116095D01*
G01X3270622Y114336D02*
X3269637Y115844D01*
G01X3278250Y113833D02*
X3278988Y113079D01*
G01X3277757Y112577D02*
X3277511Y112828D01*
G01X3271114Y116095D02*
X3270376Y116849D01*
G01X3269637Y115844D02*
X3268899Y116346D01*
G01X3281448Y112828D02*
X3280956Y113079D01*
G01X3277511Y112828D02*
X3277019Y113079D01*
G01X3277511Y114085D02*
X3278250Y113833D01*
G01X3280464Y114085D02*
X3281448D01*
G01X3274067D02*
X3275297D01*
G01X3276527D02*
X3277511D01*
G01X3277019Y113079D02*
X3276527D01*
G01X3280956D02*
X3280218D01*
G01X3275297Y106043D02*
X3274067D01*
G01X3279234D02*
X3278004D01*
G01X3270376Y116849D02*
X3269145Y117603D01*
G01X3283171Y112074D02*
Y106043D01*
G01X3281941D02*
Y112074D01*
G01X3282679Y113331D02*
X3283171Y112074D01*
G01X3281941D02*
X3281695Y112577D01*
G01X3282187Y113833D02*
X3282679Y113331D01*
G01X3281695Y112577D02*
X3281448Y112828D01*
G01Y114085D02*
X3282187Y113833D01*
G01X3283171Y106043D02*
X3281941D01*
G01X3274882Y385582D02*
X3274877Y383795D01*
G01X3274868Y384063D02*
X3274872Y385850D01*
G01X3274736Y383346D02*
Y382362D01*
G01X3273870Y383346D02*
Y382362D01*
G01X3273733Y385850D02*
X3273738Y384063D01*
G01X3273729Y383795D02*
X3273724Y385582D01*
G01X3273738Y384063D02*
X3274868D01*
G01X3274877Y383795D02*
X3273729D01*
G01X3274858Y383346D02*
X3273748D01*
G01Y382362D02*
X3274858D01*
G01X3282756Y385582D02*
X3282751Y383795D01*
G01X3282742Y384063D02*
X3282746Y385850D01*
G01X3282610Y383346D02*
Y382362D01*
G01X3281744Y383346D02*
Y382362D01*
G01X3281607Y385850D02*
X3281612Y384063D01*
G01X3281603Y383795D02*
X3281598Y385582D01*
G01X3281612Y384063D02*
X3282742D01*
G01X3282751Y383795D02*
X3281603D01*
G01X3282732Y383346D02*
X3281622D01*
G01Y382362D02*
X3282732D01*
G01X3278833Y392106D02*
X3278846Y392767D01*
G01X3278844Y393694D02*
X3278813Y392106D01*
G01X3274896D02*
X3274909Y392767D01*
G01X3274907Y393694D02*
X3274876Y392106D01*
G01X3270959D02*
X3270972Y392767D01*
G01X3270970Y393694D02*
X3270939Y392106D01*
G01X3277605D02*
X3277615Y392697D01*
G01X3277612Y393607D02*
X3277587Y392106D01*
G01X3273668D02*
X3273678Y392697D01*
G01X3273675Y393607D02*
X3273650Y392106D01*
G01X3269731D02*
X3269741Y392697D01*
G01X3269738Y393607D02*
X3269713Y392106D01*
G01X3277675Y389519D02*
X3277670Y387732D01*
G01X3277661Y388000D02*
X3277666Y389787D01*
G01X3269801Y389519D02*
X3269796Y387732D01*
G01X3269787Y388000D02*
X3269792Y389787D01*
G01X3278828Y387283D02*
Y386299D01*
G01X3278673Y391220D02*
Y390236D01*
G01X3277807Y391220D02*
Y390236D01*
G01X3277652Y386299D02*
Y387283D01*
G01X3274891Y386299D02*
Y387283D01*
G01X3273715D02*
Y386299D01*
G01X3270954Y387283D02*
Y386299D01*
G01X3270799Y391220D02*
Y390236D01*
G01X3269933Y391220D02*
Y390236D01*
G01X3269778Y386299D02*
Y387283D01*
G01X3278814Y389787D02*
X3278819Y388000D01*
G01X3278809Y387732D02*
X3278805Y389519D01*
G01X3270940Y389787D02*
X3270945Y388000D01*
G01X3270935Y387732D02*
X3270931Y389519D01*
G01X3278893Y392106D02*
X3278868Y393607D01*
G01X3278865Y392697D02*
X3278875Y392106D01*
G01X3274956D02*
X3274931Y393607D01*
G01X3274928Y392697D02*
X3274938Y392106D01*
G01X3271019D02*
X3270994Y393607D01*
G01X3270991Y392697D02*
X3271001Y392106D01*
G01X3277667D02*
X3277636Y393694D01*
G01X3277634Y392767D02*
X3277647Y392106D01*
G01X3273730D02*
X3273699Y393694D01*
G01X3273697Y392767D02*
X3273710Y392106D01*
G01X3269793D02*
X3269762Y393694D01*
G01X3269760Y392767D02*
X3269773Y392106D01*
G01X3277625Y393977D02*
X3278855D01*
G01X3269751D02*
X3270981D01*
G01X3273688D02*
X3274918D01*
G01X3277636Y393694D02*
X3278844D01*
G01X3269762D02*
X3270970D01*
G01X3273699D02*
X3274907D01*
G01X3270994Y393607D02*
X3269738D01*
G01X3274931D02*
X3273675D01*
G01X3278868D02*
X3277612D01*
G01X3277625Y392993D02*
X3278855D01*
G01X3269751D02*
X3270981D01*
G01X3273688D02*
X3274918D01*
G01X3270972Y392767D02*
X3269760D01*
G01X3274909D02*
X3273697D01*
G01X3278846D02*
X3277634D01*
G01X3277615Y392697D02*
X3278865D01*
G01X3269741D02*
X3270991D01*
G01X3273678D02*
X3274928D01*
G01X3270921Y391220D02*
X3269811D01*
G01X3278795D02*
X3277685D01*
G01Y390236D02*
X3278795D01*
G01X3269811D02*
X3270921D01*
G01X3277666Y389787D02*
X3278814D01*
G01X3269792D02*
X3270940D01*
G01X3270931Y389519D02*
X3269801D01*
G01X3278805D02*
X3277675D01*
G01X3270945Y388000D02*
X3269787D01*
G01X3278819D02*
X3277661D01*
G01X3277670Y387732D02*
X3278809D01*
G01X3269796D02*
X3270935D01*
G01X3277652Y387283D02*
X3278828D01*
G01X3273715D02*
X3274891D01*
G01X3269778D02*
X3270954D01*
G01X3274891Y386299D02*
X3273715D01*
G01X3270954D02*
X3269778D01*
G01X3278828D02*
X3277652D01*
G01X3274872Y385850D02*
X3273733D01*
G01X3273724Y385582D02*
X3274882D01*
G01X3277636Y397604D02*
X3277667Y399193D01*
G01X3277647D02*
X3277634Y398532D01*
G01X3273699Y397604D02*
X3273730Y399193D01*
G01X3273710D02*
X3273697Y398532D01*
G01X3269762Y397604D02*
X3269793Y399193D01*
G01X3269773D02*
X3269760Y398532D01*
G01X3278868Y397691D02*
X3278893Y399193D01*
G01X3278875D02*
X3278865Y398602D01*
G01X3274931Y397691D02*
X3274956Y399193D01*
G01X3274938D02*
X3274928Y398602D01*
G01X3270994Y397691D02*
X3271019Y399193D01*
G01X3271001D02*
X3270991Y398602D01*
G01X3278673Y401063D02*
Y400078D01*
G01X3277807D02*
Y401063D01*
G01X3270799D02*
Y400078D01*
G01X3269933D02*
Y401063D01*
G01X3277615Y398602D02*
X3277605Y399193D01*
G01X3277587D02*
X3277612Y397691D01*
G01X3273678Y398602D02*
X3273668Y399193D01*
G01X3273650D02*
X3273675Y397691D01*
G01X3269741Y398602D02*
X3269731Y399193D01*
G01X3269713D02*
X3269738Y397691D01*
G01X3278846Y398532D02*
X3278833Y399193D01*
G01X3278813D02*
X3278844Y397604D01*
G01X3274909Y398532D02*
X3274896Y399193D01*
G01X3274876D02*
X3274907Y397604D01*
G01X3270972Y398532D02*
X3270959Y399193D01*
G01X3270939D02*
X3270970Y397604D01*
G01X3270921Y401063D02*
X3269811D01*
G01X3278795D02*
X3277685D01*
G01X3270921Y400078D02*
X3269811D01*
G01X3278795D02*
X3277685D01*
G01X3270991Y398602D02*
X3269741D01*
G01X3274928D02*
X3273678D01*
G01X3278865D02*
X3277615D01*
G01X3277634Y398532D02*
X3278846D01*
G01X3269760D02*
X3270972D01*
G01X3273697D02*
X3274909D01*
G01X3270981Y398306D02*
X3269751D01*
G01X3274918D02*
X3273688D01*
G01X3278855D02*
X3277625D01*
G01X3277612Y397691D02*
X3278868D01*
G01X3269738D02*
X3270994D01*
G01X3273675D02*
X3274931D01*
G01X3270970Y397604D02*
X3269762D01*
G01X3274907D02*
X3273699D01*
G01X3278844D02*
X3277636D01*
G01X3270981Y397322D02*
X3269751D01*
G01X3274918D02*
X3273688D01*
G01X3278855D02*
X3277625D01*
G01X3282770Y392106D02*
X3282783Y392767D01*
G01X3282781Y393694D02*
X3282750Y392106D01*
G01X3281542D02*
X3281552Y392697D01*
G01X3281549Y393607D02*
X3281524Y392106D01*
G01X3282765Y386299D02*
Y387283D01*
G01X3281589D02*
Y386299D01*
G01X3282830Y392106D02*
X3282805Y393607D01*
G01X3282802Y392697D02*
X3282812Y392106D01*
G01X3281604D02*
X3281573Y393694D01*
G01X3281571Y392767D02*
X3281584Y392106D01*
G01X3281562Y393977D02*
X3282792D01*
G01X3281573Y393694D02*
X3282781D01*
G01X3282805Y393607D02*
X3281549D01*
G01X3281562Y392993D02*
X3282792D01*
G01X3282783Y392767D02*
X3281571D01*
G01X3281552Y392697D02*
X3282802D01*
G01X3281589Y387283D02*
X3282765D01*
G01Y386299D02*
X3281589D01*
G01X3282746Y385850D02*
X3281607D01*
G01X3281598Y385582D02*
X3282756D01*
G01X3281573Y397604D02*
X3281604Y399193D01*
G01X3281584D02*
X3281571Y398532D01*
G01X3282805Y397691D02*
X3282830Y399193D01*
G01X3282812D02*
X3282802Y398602D01*
G01X3281552D02*
X3281542Y399193D01*
G01X3281524D02*
X3281549Y397691D01*
G01X3282783Y398532D02*
X3282770Y399193D01*
G01X3282750D02*
X3282781Y397604D01*
G01X3282802Y398602D02*
X3281552D01*
G01X3281571Y398532D02*
X3282783D01*
G01X3282792Y398306D02*
X3281562D01*
G01X3281549Y397691D02*
X3282805D01*
G01X3282781Y397604D02*
X3281573D01*
G01X3282792Y397322D02*
X3281562D01*
G01X3278819Y403299D02*
X3278814Y401512D01*
G01X3278805Y401779D02*
X3278809Y403567D01*
G01X3273738Y407236D02*
X3273733Y405449D01*
G01X3273724Y405716D02*
X3273729Y407504D01*
G01X3270945Y403299D02*
X3270940Y401512D01*
G01X3270931Y401779D02*
X3270935Y403567D01*
G01X3278828Y405000D02*
Y404015D01*
G01X3277652D02*
Y405000D01*
G01X3274891Y404015D02*
Y405000D01*
G01X3274736Y408937D02*
Y407952D01*
G01X3273870D02*
Y408937D01*
G01X3273715Y405000D02*
Y404015D01*
G01X3270954Y405000D02*
Y404015D01*
G01X3269778D02*
Y405000D01*
G01X3277670Y403567D02*
X3277675Y401779D01*
G01X3277666Y401512D02*
X3277661Y403299D01*
G01X3274877Y407504D02*
X3274882Y405716D01*
G01X3274872Y405449D02*
X3274868Y407236D01*
G01X3269796Y403567D02*
X3269801Y401779D01*
G01X3269792Y401512D02*
X3269787Y403299D01*
G01X3274858Y408937D02*
X3273748D01*
G01X3274858Y407952D02*
X3273748D01*
G01X3273729Y407504D02*
X3274877D01*
G01X3274868Y407236D02*
X3273738D01*
G01X3274882Y405716D02*
X3273724D01*
G01X3273733Y405449D02*
X3274872D01*
G01X3274891Y405000D02*
X3273715D01*
G01X3270954D02*
X3269778D01*
G01X3278828D02*
X3277652D01*
G01X3274891Y404015D02*
X3273715D01*
G01X3270954D02*
X3269778D01*
G01X3278828D02*
X3277652D01*
G01X3270935Y403567D02*
X3269796D01*
G01X3278809D02*
X3277670D01*
G01X3277661Y403299D02*
X3278819D01*
G01X3269787D02*
X3270945D01*
G01X3277675Y401779D02*
X3278805D01*
G01X3269801D02*
X3270931D01*
G01X3270940Y401512D02*
X3269792D01*
G01X3278814D02*
X3277666D01*
G01X3281612Y407236D02*
X3281607Y405449D01*
G01X3281598Y405716D02*
X3281603Y407504D01*
G01X3283279Y415728D02*
Y410118D01*
G01X3282765Y404015D02*
Y405000D01*
G01X3282610Y408937D02*
Y407952D01*
G01X3281744D02*
Y408937D01*
G01X3281589Y405000D02*
Y404015D01*
G01X3282751Y407504D02*
X3282756Y405716D01*
G01X3282746Y405449D02*
X3282742Y407236D01*
G01X3282732Y408937D02*
X3281622D01*
G01X3282732Y407952D02*
X3281622D01*
G01X3281603Y407504D02*
X3282751D01*
G01X3282742Y407236D02*
X3281612D01*
G01X3282756Y405716D02*
X3281598D01*
G01X3281607Y405449D02*
X3282746D01*
G01X3282765Y405000D02*
X3281589D01*
G01X3282765Y404015D02*
X3281589D01*
G01X3269067Y457431D02*
Y456200D01*
G01Y464402D02*
Y463172D01*
G01Y474655D02*
X3268857Y475885D01*
G01D02*
X3268229Y476911D01*
G01Y472400D02*
X3268857Y473425D01*
G01D02*
X3269067Y474655D01*
G01Y481012D02*
Y479987D01*
G01Y484293D02*
Y483267D01*
G01Y490239D02*
Y489214D01*
G01Y487574D02*
Y486548D01*
G01Y493520D02*
Y492495D01*
G01Y496801D02*
Y495776D01*
G01X3268397Y507067D02*
Y544813D01*
G01X3269972Y1086791D02*
G03X3277452I3740J0D01*
G01Y1114153D02*
Y1086791D01*
G01X3269972D02*
Y1114153D01*
G01X3273712Y1090728D02*
Y1158602D01*
G01X3280996Y1094074D02*
X3278240D01*
G01X3280996Y1110610D02*
Y1094074D01*
G01X3278240D02*
Y1110610D01*
G01X3269185D02*
Y1094074D01*
G01X3284933D02*
X3282177D01*
G01D02*
Y1110610D01*
G01X3319578Y1116122D02*
X3279421D01*
G01X3278240Y1110610D02*
X3280996D01*
G01X3321547D02*
X3277452D01*
G01X3279421Y1116122D02*
X3277452Y1114153D01*
G01X3282177Y1110610D02*
X3284933D01*
G01X3285847Y-917317D02*
X3286497Y-918327D01*
X3287363Y-918905D01*
X3288337Y-919049D01*
X3289203Y-918905D01*
X3290070Y-918183D01*
X3290611Y-917317D01*
X3290719Y-916451D01*
X3290503Y-915440D01*
X3289745Y-914719D01*
X3288987Y-914430D01*
X3288012D01*
G01X3288987D02*
X3289636Y-913997D01*
X3290178Y-913275D01*
X3290394Y-912409D01*
X3290178Y-911543D01*
X3289636Y-910821D01*
X3288662Y-910388D01*
X3287688Y-910532D01*
X3286713Y-911110D01*
G01X3296890Y-919338D02*
X3296673Y-919193D01*
Y-918905D01*
X3296890Y-918760D01*
X3297107Y-918905D01*
Y-919193D01*
X3296890Y-919338D01*
G01X3303494Y-911831D02*
X3304144Y-910966D01*
X3304901Y-910532D01*
X3305768Y-910388D01*
X3306850Y-910677D01*
X3307608Y-911398D01*
X3307825Y-912264D01*
X3307716Y-913131D01*
X3307283Y-913852D01*
X3305118Y-915296D01*
X3304144Y-916306D01*
X3303494Y-917750D01*
X3303277Y-919049D01*
X3307825D01*
G01X3314212Y-910388D02*
X3313346Y-910677D01*
X3312696Y-911398D01*
X3312263Y-912264D01*
X3311938Y-913419D01*
X3311830Y-914719D01*
X3311938Y-916018D01*
X3312263Y-917173D01*
X3312696Y-918039D01*
X3313346Y-918760D01*
X3314212Y-919049D01*
X3315078Y-918760D01*
X3315728Y-918039D01*
X3316161Y-917173D01*
X3316486Y-916018D01*
X3316594Y-914719D01*
X3316486Y-913419D01*
X3316161Y-912264D01*
X3315728Y-911398D01*
X3315078Y-910677D01*
X3314212Y-910388D01*
G01X3285638Y-863772D02*
X3286288Y-864782D01*
X3287154Y-865360D01*
X3288128Y-865504D01*
X3288994Y-865360D01*
X3289861Y-864638D01*
X3290402Y-863772D01*
X3290510Y-862906D01*
X3290294Y-861895D01*
X3289536Y-861174D01*
X3288778Y-860885D01*
X3287803D01*
G01X3288778D02*
X3289427Y-860452D01*
X3289969Y-859730D01*
X3290185Y-858864D01*
X3289969Y-857998D01*
X3289427Y-857276D01*
X3288453Y-856843D01*
X3287479Y-856987D01*
X3286504Y-857565D01*
G01X3296681Y-865793D02*
X3296464Y-865648D01*
Y-865360D01*
X3296681Y-865215D01*
X3296898Y-865360D01*
Y-865648D01*
X3296681Y-865793D01*
G01X3303285Y-858286D02*
X3303935Y-857421D01*
X3304692Y-856987D01*
X3305559Y-856843D01*
X3306641Y-857132D01*
X3307399Y-857853D01*
X3307616Y-858719D01*
X3307507Y-859586D01*
X3307074Y-860307D01*
X3304909Y-861751D01*
X3303935Y-862761D01*
X3303285Y-864205D01*
X3303068Y-865504D01*
X3307616D01*
G01X3314003Y-856843D02*
X3313137Y-857132D01*
X3312487Y-857853D01*
X3312054Y-858719D01*
X3311729Y-859874D01*
X3311621Y-861174D01*
X3311729Y-862473D01*
X3312054Y-863628D01*
X3312487Y-864494D01*
X3313137Y-865215D01*
X3314003Y-865504D01*
X3314869Y-865215D01*
X3315519Y-864494D01*
X3315952Y-863628D01*
X3316277Y-862473D01*
X3316385Y-861174D01*
X3316277Y-859874D01*
X3315952Y-858719D01*
X3315519Y-857853D01*
X3314869Y-857132D01*
X3314003Y-856843D01*
G01X3389665Y-305311D02*
X3288484D01*
G01X3290799Y113833D02*
X3291537Y114085D01*
G01X3287600Y113079D02*
X3286862Y112828D01*
G01Y113833D02*
X3287600Y114085D01*
G01X3291291Y113079D02*
X3290799Y112828D01*
G01D02*
X3290553Y112577D01*
G01X3290061Y113079D02*
X3290799Y113833D01*
G01X3286862Y112828D02*
X3286370Y112326D01*
G01Y113331D02*
X3286862Y113833D01*
G01X3290553Y112577D02*
X3290307Y112074D01*
G01X3294244D02*
Y106043D01*
G01X3293013D02*
Y112074D01*
G01X3290307D02*
Y106043D01*
G01X3289076D02*
Y112074D01*
G01X3286370Y114085D02*
Y113331D01*
G01Y112326D02*
Y106043D01*
G01X3285139D02*
Y114085D01*
G01X3293752Y113331D02*
X3294244Y112074D01*
G01X3293013D02*
X3292767Y112577D01*
G01X3289076Y112074D02*
X3288830Y112577D01*
G01X3293259Y113833D02*
X3293752Y113331D01*
G01X3292767Y112577D02*
X3292521Y112828D01*
G01X3289322Y113833D02*
X3290061Y113079D01*
G01X3288830Y112577D02*
X3288584Y112828D01*
G01X3292521D02*
X3292029Y113079D01*
G01X3288584Y112828D02*
X3288092Y113079D01*
G01X3292521Y114085D02*
X3293259Y113833D01*
G01X3288584Y114085D02*
X3289322Y113833D01*
G01X3291537Y114085D02*
X3292521D01*
G01X3285139D02*
X3286370D01*
G01X3287600D02*
X3288584D01*
G01X3288092Y113079D02*
X3287600D01*
G01X3292029D02*
X3291291D01*
G01X3286370Y106043D02*
X3285139D01*
G01X3290307D02*
X3289076D01*
G01X3294244D02*
X3293013D01*
G01X3297492Y383346D02*
Y382362D01*
G01X3297355Y385850D02*
X3297360Y384063D01*
G01X3297351Y383795D02*
X3297346Y385582D01*
G01X3290630D02*
X3290625Y383795D01*
G01X3290616Y384063D02*
X3290620Y385850D01*
G01X3290484Y383346D02*
Y382362D01*
G01X3289618Y383346D02*
Y382362D01*
G01X3289481Y385850D02*
X3289486Y384063D01*
G01X3289477Y383795D02*
X3289472Y385582D01*
G01X3297360Y384063D02*
X3298490D01*
G01X3289486D02*
X3290616D01*
G01X3290625Y383795D02*
X3289477D01*
G01X3298499D02*
X3297351D01*
G01X3290606Y383346D02*
X3289496D01*
G01X3298480D02*
X3297370D01*
G01Y382362D02*
X3298480D01*
G01X3289496D02*
X3290606D01*
G01X3298504Y385582D02*
X3298499Y383795D01*
G01X3298490Y384063D02*
X3298495Y385850D01*
G01X3298358Y383346D02*
Y382362D01*
G01X3294581Y392106D02*
X3294594Y392767D01*
G01X3294592Y393694D02*
X3294561Y392106D01*
G01X3297290D02*
X3297300Y392697D01*
G01X3297297Y393607D02*
X3297272Y392106D01*
G01X3293353D02*
X3293363Y392697D01*
G01X3293360Y393607D02*
X3293335Y392106D01*
G01X3297337Y387283D02*
Y386299D01*
G01X3294576D02*
Y387283D01*
G01X3297352Y392106D02*
X3297321Y393694D01*
G01X3297319Y392767D02*
X3297332Y392106D01*
G01X3290644D02*
X3290657Y392767D01*
G01X3290655Y393694D02*
X3290624Y392106D01*
G01X3286707D02*
X3286720Y392767D01*
G01X3286718Y393694D02*
X3286687Y392106D01*
G01X3289416D02*
X3289426Y392697D01*
G01X3289423Y393607D02*
X3289398Y392106D01*
G01X3285479D02*
X3285489Y392697D01*
G01X3285486Y393607D02*
X3285461Y392106D01*
G01X3293423Y389519D02*
X3293418Y387732D01*
G01X3293409Y388000D02*
X3293414Y389787D01*
G01X3285549Y389519D02*
X3285544Y387732D01*
G01X3285535Y388000D02*
X3285540Y389787D01*
G01X3294421Y391220D02*
Y390236D01*
G01X3293555Y391220D02*
Y390236D01*
G01X3293400Y387283D02*
Y386299D01*
G01X3290639D02*
Y387283D01*
G01X3289463D02*
Y386299D01*
G01X3286702Y387283D02*
Y386299D01*
G01X3286547Y391220D02*
Y390236D01*
G01X3285681Y391220D02*
Y390236D01*
G01X3285526Y386299D02*
Y387283D01*
G01X3294562Y389787D02*
X3294567Y388000D01*
G01X3294557Y387732D02*
X3294553Y389519D01*
G01X3286688Y389787D02*
X3286693Y388000D01*
G01X3286683Y387732D02*
X3286679Y389519D01*
G01X3294641Y392106D02*
X3294616Y393607D01*
G01X3294613Y392697D02*
X3294623Y392106D01*
G01X3290704D02*
X3290679Y393607D01*
G01X3290676Y392697D02*
X3290686Y392106D01*
G01X3286767D02*
X3286742Y393607D01*
G01X3286739Y392697D02*
X3286749Y392106D01*
G01X3293415D02*
X3293384Y393694D01*
G01X3293382Y392767D02*
X3293395Y392106D01*
G01X3289478D02*
X3289447Y393694D01*
G01X3289445Y392767D02*
X3289458Y392106D01*
G01X3285541D02*
X3285510Y393694D01*
G01X3285508Y392767D02*
X3285521Y392106D01*
G01X3297310Y393977D02*
X3298540D01*
G01X3293373D02*
X3294603D01*
G01X3289436D02*
X3290666D01*
G01X3285499D02*
X3286729D01*
G01X3297321Y393694D02*
X3298529D01*
G01X3293384D02*
X3294592D01*
G01X3289447D02*
X3290655D01*
G01X3285510D02*
X3286718D01*
G01X3286742Y393607D02*
X3285486D01*
G01X3290679D02*
X3289423D01*
G01X3298553D02*
X3297297D01*
G01X3294616D02*
X3293360D01*
G01X3297310Y392993D02*
X3298540D01*
G01X3293373D02*
X3294603D01*
G01X3289436D02*
X3290666D01*
G01X3285499D02*
X3286729D01*
G01X3286720Y392767D02*
X3285508D01*
G01X3290657D02*
X3289445D01*
G01X3298531D02*
X3297319D01*
G01X3294594D02*
X3293382D01*
G01X3297300Y392697D02*
X3298550D01*
G01X3293363D02*
X3294613D01*
G01X3289426D02*
X3290676D01*
G01X3285489D02*
X3286739D01*
G01X3286669Y391220D02*
X3285559D01*
G01X3294543D02*
X3293433D01*
G01Y390236D02*
X3294543D01*
G01X3285559D02*
X3286669D01*
G01X3293414Y389787D02*
X3294562D01*
G01X3285540D02*
X3286688D01*
G01X3286679Y389519D02*
X3285549D01*
G01X3294553D02*
X3293423D01*
G01X3286693Y388000D02*
X3285535D01*
G01X3294567D02*
X3293409D01*
G01X3293418Y387732D02*
X3294557D01*
G01X3285544D02*
X3286683D01*
G01X3297337Y387283D02*
X3298513D01*
G01X3293400D02*
X3294576D01*
G01X3289463D02*
X3290639D01*
G01X3285526D02*
X3286702D01*
G01Y386299D02*
X3285526D01*
G01X3290639D02*
X3289463D01*
G01X3294576D02*
X3293400D01*
G01X3298513D02*
X3297337D01*
G01X3290620Y385850D02*
X3289481D01*
G01X3298495D02*
X3297355D01*
G01X3297346Y385582D02*
X3298504D01*
G01X3289472D02*
X3290630D01*
G01X3297321Y397604D02*
X3297352Y399193D01*
G01X3297332D02*
X3297319Y398532D01*
G01X3293384Y397604D02*
X3293415Y399193D01*
G01X3293395D02*
X3293382Y398532D01*
G01X3294616Y397691D02*
X3294641Y399193D01*
G01X3294623D02*
X3294613Y398602D01*
G01X3297300D02*
X3297290Y399193D01*
G01X3297272D02*
X3297297Y397691D01*
G01X3289447Y397604D02*
X3289478Y399193D01*
G01X3289458D02*
X3289445Y398532D01*
G01X3285510Y397604D02*
X3285541Y399193D01*
G01X3285521D02*
X3285508Y398532D01*
G01X3290679Y397691D02*
X3290704Y399193D01*
G01X3290686D02*
X3290676Y398602D01*
G01X3286742Y397691D02*
X3286767Y399193D01*
G01X3286749D02*
X3286739Y398602D01*
G01X3294421Y401063D02*
Y400078D01*
G01X3293555D02*
Y401063D01*
G01X3286547D02*
Y400078D01*
G01X3285681D02*
Y401063D01*
G01X3293363Y398602D02*
X3293353Y399193D01*
G01X3293335D02*
X3293360Y397691D01*
G01X3289426Y398602D02*
X3289416Y399193D01*
G01X3289398D02*
X3289423Y397691D01*
G01X3285489Y398602D02*
X3285479Y399193D01*
G01X3285461D02*
X3285486Y397691D01*
G01X3294594Y398532D02*
X3294581Y399193D01*
G01X3294561D02*
X3294592Y397604D01*
G01X3290657Y398532D02*
X3290644Y399193D01*
G01X3290624D02*
X3290655Y397604D01*
G01X3286720Y398532D02*
X3286707Y399193D01*
G01X3286687D02*
X3286718Y397604D01*
G01X3286669Y401063D02*
X3285559D01*
G01X3294543D02*
X3293433D01*
G01X3286669Y400078D02*
X3285559D01*
G01X3294543D02*
X3293433D01*
G01X3286739Y398602D02*
X3285489D01*
G01X3290676D02*
X3289426D01*
G01X3294613D02*
X3293363D01*
G01X3298550D02*
X3297300D01*
G01X3293382Y398532D02*
X3294594D01*
G01X3297319D02*
X3298531D01*
G01X3289445D02*
X3290657D01*
G01X3285508D02*
X3286720D01*
G01X3286729Y398306D02*
X3285499D01*
G01X3290666D02*
X3289436D01*
G01X3294603D02*
X3293373D01*
G01X3298540D02*
X3297310D01*
G01X3293360Y397691D02*
X3294616D01*
G01X3297297D02*
X3298553D01*
G01X3289423D02*
X3290679D01*
G01X3285486D02*
X3286742D01*
G01X3286718Y397604D02*
X3285510D01*
G01X3290655D02*
X3289447D01*
G01X3294592D02*
X3293384D01*
G01X3298529D02*
X3297321D01*
G01X3286729Y397322D02*
X3285499D01*
G01X3290666D02*
X3289436D01*
G01X3294603D02*
X3293373D01*
G01X3298540D02*
X3297310D01*
G01X3298518Y392106D02*
X3298531Y392767D01*
G01X3298529Y393694D02*
X3298498Y392106D01*
G01X3298513Y386299D02*
Y387283D01*
G01X3298578Y392106D02*
X3298553Y393607D01*
G01X3298550Y392697D02*
X3298560Y392106D01*
G01X3298553Y397691D02*
X3298578Y399193D01*
G01X3298560D02*
X3298550Y398602D01*
G01X3298531Y398532D02*
X3298518Y399193D01*
G01X3298498D02*
X3298529Y397604D01*
G01X3297360Y407236D02*
X3297355Y405449D01*
G01X3297346Y405716D02*
X3297351Y407504D01*
G01X3294567Y403299D02*
X3294562Y401512D01*
G01X3294553Y401779D02*
X3294557Y403567D01*
G01X3297492Y407952D02*
Y408937D01*
G01X3297337Y405000D02*
Y404015D01*
G01X3294576Y405000D02*
Y404015D01*
G01X3289486Y407236D02*
X3289481Y405449D01*
G01X3289472Y405716D02*
X3289477Y407504D01*
G01X3286693Y403299D02*
X3286688Y401512D01*
G01X3286679Y401779D02*
X3286683Y403567D01*
G01X3293400Y404015D02*
Y405000D01*
G01X3290639Y404015D02*
Y405000D01*
G01X3290484Y408937D02*
Y407952D01*
G01X3289618D02*
Y408937D01*
G01X3289463Y405000D02*
Y404015D01*
G01X3288279Y415728D02*
Y410118D01*
G01X3286702Y405000D02*
Y404015D01*
G01X3285526D02*
Y405000D01*
G01X3293418Y403567D02*
X3293423Y401779D01*
G01X3293414Y401512D02*
X3293409Y403299D01*
G01X3290625Y407504D02*
X3290630Y405716D01*
G01X3290620Y405449D02*
X3290616Y407236D01*
G01X3285544Y403567D02*
X3285549Y401779D01*
G01X3285540Y401512D02*
X3285535Y403299D01*
G01X3290606Y408937D02*
X3289496D01*
G01X3298480D02*
X3297370D01*
G01X3290606Y407952D02*
X3289496D01*
G01X3298480D02*
X3297370D01*
G01X3297351Y407504D02*
X3298499D01*
G01X3289477D02*
X3290625D01*
G01X3290616Y407236D02*
X3289486D01*
G01X3298490D02*
X3297360D01*
G01X3290630Y405716D02*
X3289472D01*
G01X3298504D02*
X3297346D01*
G01X3297355Y405449D02*
X3298495D01*
G01X3289481D02*
X3290620D01*
G01X3286702Y405000D02*
X3285526D01*
G01X3290639D02*
X3289463D01*
G01X3294576D02*
X3293400D01*
G01X3298513D02*
X3297337D01*
G01X3286702Y404015D02*
X3285526D01*
G01X3290639D02*
X3289463D01*
G01X3294576D02*
X3293400D01*
G01X3298513D02*
X3297337D01*
G01X3286683Y403567D02*
X3285544D01*
G01X3294557D02*
X3293418D01*
G01X3293409Y403299D02*
X3294567D01*
G01X3285535D02*
X3286693D01*
G01X3293423Y401779D02*
X3294553D01*
G01X3285549D02*
X3286679D01*
G01X3286688Y401512D02*
X3285540D01*
G01X3294562D02*
X3293414D01*
G01X3294972Y416712D02*
Y521633D01*
G01X3304185Y415728D02*
X3288279D01*
G01X3298513Y404015D02*
Y405000D01*
G01X3298358Y408937D02*
Y407952D01*
G01X3298499Y407504D02*
X3298504Y405716D01*
G01X3298495Y405449D02*
X3298490Y407236D01*
G01X3296504Y481559D02*
X3309415Y566864D01*
G01X3288870Y1094074D02*
X3286114D01*
G01X3292807D02*
X3290051D01*
G01X3296744D02*
X3293988D01*
G01X3296744Y1110610D02*
Y1094074D01*
G01X3293988D02*
Y1110610D01*
G01X3292807D02*
Y1094074D01*
G01X3290051D02*
Y1110610D01*
G01X3288870D02*
Y1094074D01*
G01X3286114D02*
Y1110610D01*
G01X3284933D02*
Y1094074D01*
G01X3300681D02*
X3297925D01*
G01X3300681Y1110610D02*
Y1094074D01*
G01X3297925D02*
Y1110610D01*
G01X3293988D02*
X3296744D01*
G01X3290051D02*
X3292807D01*
G01X3286114D02*
X3288870D01*
G01X3297925D02*
X3300681D01*
G01X3318869Y-921936D02*
X3317786Y-920492D01*
X3317245Y-919049D01*
Y-913275D01*
X3317786Y-911831D01*
X3318869Y-910388D01*
G01X3325581Y-919049D02*
Y-910388D01*
X3330561Y-919049D01*
Y-910388D01*
G01X3334567Y-919049D02*
Y-910388D01*
X3337165D01*
X3338031Y-910821D01*
X3338681Y-911831D01*
X3338897Y-912986D01*
X3338681Y-914141D01*
X3338139Y-915007D01*
X3337165Y-915440D01*
X3334567D01*
G01X3345393Y-910388D02*
Y-919049D01*
G01X3342903Y-910388D02*
X3347883D01*
G01X3351780Y-919049D02*
Y-910388D01*
G01X3356328D02*
Y-919049D01*
G01Y-914719D02*
X3351780D01*
G01X3363256Y-921936D02*
X3364339Y-920492D01*
X3364880Y-919049D01*
Y-913275D01*
X3364339Y-911831D01*
X3363256Y-910388D01*
G01X3311845Y-904853D02*
X3310762Y-903409D01*
X3310221Y-901966D01*
Y-896192D01*
X3310762Y-894748D01*
X3311845Y-893305D01*
G01X3318882Y-901966D02*
Y-893305D01*
X3321480D01*
X3322346Y-893738D01*
X3322996Y-894748D01*
X3323212Y-895903D01*
X3322996Y-897058D01*
X3322454Y-897924D01*
X3321480Y-898357D01*
X3318882D01*
G01X3327001Y-901966D02*
X3329708Y-893305D01*
X3332415Y-901966D01*
G01X3331440Y-898935D02*
X3327976D01*
G01X3335987Y-901966D02*
Y-893305D01*
X3338152D01*
X3339019Y-893738D01*
X3339668Y-894315D01*
X3340210Y-895181D01*
X3340643Y-896192D01*
X3340751Y-897636D01*
X3340643Y-899079D01*
X3340210Y-900090D01*
X3339668Y-900956D01*
X3339019Y-901533D01*
X3338152Y-901966D01*
X3335987D01*
G01X3347571Y-904853D02*
X3348654Y-903409D01*
X3349195Y-901966D01*
Y-896192D01*
X3348654Y-894748D01*
X3347571Y-893305D01*
G01X3318660Y-868391D02*
X3317577Y-866947D01*
X3317036Y-865504D01*
Y-859730D01*
X3317577Y-858286D01*
X3318660Y-856843D01*
G01X3325372Y-865504D02*
Y-856843D01*
X3330352Y-865504D01*
Y-856843D01*
G01X3334358Y-865504D02*
Y-856843D01*
X3336956D01*
X3337822Y-857276D01*
X3338472Y-858286D01*
X3338688Y-859441D01*
X3338472Y-860596D01*
X3337930Y-861462D01*
X3336956Y-861895D01*
X3334358D01*
G01X3345184Y-856843D02*
Y-865504D01*
G01X3342694Y-856843D02*
X3347674D01*
G01X3351571Y-865504D02*
Y-856843D01*
G01X3356119D02*
Y-865504D01*
G01Y-861174D02*
X3351571D01*
G01X3363047Y-868391D02*
X3364130Y-866947D01*
X3364671Y-865504D01*
Y-859730D01*
X3364130Y-858286D01*
X3363047Y-856843D01*
G01X3306745Y-847260D02*
X3305662Y-845816D01*
X3305121Y-844373D01*
Y-838599D01*
X3305662Y-837155D01*
X3306745Y-835712D01*
G01X3313782Y-844373D02*
Y-835712D01*
X3316380D01*
X3317246Y-836145D01*
X3317896Y-837155D01*
X3318112Y-838310D01*
X3317896Y-839465D01*
X3317354Y-840331D01*
X3316380Y-840764D01*
X3313782D01*
G01X3321901Y-844373D02*
X3324608Y-835712D01*
X3327315Y-844373D01*
G01X3326340Y-841342D02*
X3322876D01*
G01X3330887Y-844373D02*
Y-835712D01*
X3333052D01*
X3333919Y-836145D01*
X3334568Y-836722D01*
X3335110Y-837588D01*
X3335543Y-838599D01*
X3335651Y-840043D01*
X3335543Y-841486D01*
X3335110Y-842497D01*
X3334568Y-843363D01*
X3333919Y-843940D01*
X3333052Y-844373D01*
X3330887D01*
G01X3342471Y-847260D02*
X3343554Y-845816D01*
X3344095Y-844373D01*
Y-838599D01*
X3343554Y-837155D01*
X3342471Y-835712D01*
G01X3314252Y385582D02*
X3314247Y383795D01*
G01X3314238Y384063D02*
X3314243Y385850D01*
G01X3306378Y385582D02*
X3306373Y383795D01*
G01X3306364Y384063D02*
X3306369Y385850D01*
G01X3314106Y383346D02*
Y382362D01*
G01X3313240Y383346D02*
Y382362D01*
G01X3306232Y383346D02*
Y382362D01*
G01X3305366Y383346D02*
Y382362D01*
G01X3313103Y385850D02*
X3313108Y384063D01*
G01X3313099Y383795D02*
X3313094Y385582D01*
G01X3305229Y385850D02*
X3305234Y384063D01*
G01X3305225Y383795D02*
X3305220Y385582D01*
G01X3313108Y384063D02*
X3314238D01*
G01X3305234D02*
X3306364D01*
G01X3306373Y383795D02*
X3305225D01*
G01X3314247D02*
X3313099D01*
G01X3306354Y383346D02*
X3305244D01*
G01X3314228D02*
X3313118D01*
G01Y382362D02*
X3314228D01*
G01X3305244D02*
X3306354D01*
G01X3314266Y392106D02*
X3314279Y392767D01*
G01X3314277Y393694D02*
X3314246Y392106D01*
G01X3310329D02*
X3310342Y392767D01*
G01X3310340Y393694D02*
X3310309Y392106D01*
G01X3306392D02*
X3306405Y392767D01*
G01X3306403Y393694D02*
X3306372Y392106D01*
G01X3302455D02*
X3302468Y392767D01*
G01X3302466Y393694D02*
X3302435Y392106D01*
G01X3313038D02*
X3313048Y392697D01*
G01X3313045Y393607D02*
X3313020Y392106D01*
G01X3309101D02*
X3309111Y392697D01*
G01X3309108Y393607D02*
X3309083Y392106D01*
G01X3305164D02*
X3305174Y392697D01*
G01X3305171Y393607D02*
X3305146Y392106D01*
G01X3301227D02*
X3301237Y392697D01*
G01X3301234Y393607D02*
X3301209Y392106D01*
G01X3309171Y389519D02*
X3309166Y387732D01*
G01X3309157Y388000D02*
X3309162Y389787D01*
G01X3301297Y389519D02*
X3301292Y387732D01*
G01X3301283Y388000D02*
X3301288Y389787D01*
G01X3314261Y386299D02*
Y387283D01*
G01X3313085D02*
Y386299D01*
G01X3310324Y387283D02*
Y386299D01*
G01X3310169Y391220D02*
Y390236D01*
G01X3309303Y391220D02*
Y390236D01*
G01X3309148Y386299D02*
Y387283D01*
G01X3306387Y386299D02*
Y387283D01*
G01X3305211D02*
Y386299D01*
G01X3302450Y387283D02*
Y386299D01*
G01X3302295Y391220D02*
Y390236D01*
G01X3301429Y391220D02*
Y390236D01*
G01X3301274Y386299D02*
Y387283D01*
G01X3310310Y389787D02*
X3310315Y388000D01*
G01X3310306Y387732D02*
X3310301Y389519D01*
G01X3302436Y389787D02*
X3302441Y388000D01*
G01X3302432Y387732D02*
X3302427Y389519D01*
G01X3310389Y392106D02*
X3310364Y393607D01*
G01X3310361Y392697D02*
X3310371Y392106D01*
G01X3306452D02*
X3306427Y393607D01*
G01X3306424Y392697D02*
X3306434Y392106D01*
G01X3302515D02*
X3302490Y393607D01*
G01X3302487Y392697D02*
X3302497Y392106D01*
G01X3313100D02*
X3313069Y393694D01*
G01X3313067Y392767D02*
X3313080Y392106D01*
G01X3309163D02*
X3309132Y393694D01*
G01X3309130Y392767D02*
X3309143Y392106D01*
G01X3305226D02*
X3305195Y393694D01*
G01X3305193Y392767D02*
X3305206Y392106D01*
G01X3301289D02*
X3301258Y393694D01*
G01X3301256Y392767D02*
X3301269Y392106D01*
G01X3313058Y393977D02*
X3314288D01*
G01X3309121D02*
X3310351D01*
G01X3305184D02*
X3306414D01*
G01X3301247D02*
X3302477D01*
G01X3313069Y393694D02*
X3314277D01*
G01X3309132D02*
X3310340D01*
G01X3305195D02*
X3306403D01*
G01X3301258D02*
X3302466D01*
G01X3302490Y393607D02*
X3301234D01*
G01X3306427D02*
X3305171D01*
G01X3310364D02*
X3309108D01*
G01X3314301D02*
X3313045D01*
G01X3313058Y392993D02*
X3314288D01*
G01X3309121D02*
X3310351D01*
G01X3305184D02*
X3306414D01*
G01X3301247D02*
X3302477D01*
G01X3302468Y392767D02*
X3301256D01*
G01X3306405D02*
X3305193D01*
G01X3310342D02*
X3309130D01*
G01X3314279D02*
X3313067D01*
G01X3313048Y392697D02*
X3314298D01*
G01X3309111D02*
X3310361D01*
G01X3305174D02*
X3306424D01*
G01X3301237D02*
X3302487D01*
G01X3302417Y391220D02*
X3301307D01*
G01X3310291D02*
X3309181D01*
G01Y390236D02*
X3310291D01*
G01X3301307D02*
X3302417D01*
G01X3309162Y389787D02*
X3310310D01*
G01X3301288D02*
X3302436D01*
G01X3302427Y389519D02*
X3301297D01*
G01X3310301D02*
X3309171D01*
G01X3302441Y388000D02*
X3301283D01*
G01X3310315D02*
X3309157D01*
G01X3309166Y387732D02*
X3310306D01*
G01X3301292D02*
X3302432D01*
G01X3313085Y387283D02*
X3314261D01*
G01X3309148D02*
X3310324D01*
G01X3305211D02*
X3306387D01*
G01X3301274D02*
X3302450D01*
G01Y386299D02*
X3301274D01*
G01X3306387D02*
X3305211D01*
G01X3310324D02*
X3309148D01*
G01X3314261D02*
X3313085D01*
G01X3306369Y385850D02*
X3305229D01*
G01X3314243D02*
X3313103D01*
G01X3313094Y385582D02*
X3314252D01*
G01X3305220D02*
X3306378D01*
G01X3313069Y397604D02*
X3313100Y399193D01*
G01X3313080D02*
X3313067Y398532D01*
G01X3309132Y397604D02*
X3309163Y399193D01*
G01X3309143D02*
X3309130Y398532D01*
G01X3305195Y397604D02*
X3305226Y399193D01*
G01X3305206D02*
X3305193Y398532D01*
G01X3301258Y397604D02*
X3301289Y399193D01*
G01X3301269D02*
X3301256Y398532D01*
G01X3310364Y397691D02*
X3310389Y399193D01*
G01X3310371D02*
X3310361Y398602D01*
G01X3306427Y397691D02*
X3306452Y399193D01*
G01X3306434D02*
X3306424Y398602D01*
G01X3302490Y397691D02*
X3302515Y399193D01*
G01X3302497D02*
X3302487Y398602D01*
G01X3310169Y401063D02*
Y400078D01*
G01X3309303D02*
Y401063D01*
G01X3302295D02*
Y400078D01*
G01X3301429D02*
Y401063D01*
G01X3313048Y398602D02*
X3313038Y399193D01*
G01X3313020D02*
X3313045Y397691D01*
G01X3309111Y398602D02*
X3309101Y399193D01*
G01X3309083D02*
X3309108Y397691D01*
G01X3305174Y398602D02*
X3305164Y399193D01*
G01X3305146D02*
X3305171Y397691D01*
G01X3301237Y398602D02*
X3301227Y399193D01*
G01X3301209D02*
X3301234Y397691D01*
G01X3314279Y398532D02*
X3314266Y399193D01*
G01X3314246D02*
X3314277Y397604D01*
G01X3310342Y398532D02*
X3310329Y399193D01*
G01X3310309D02*
X3310340Y397604D01*
G01X3306405Y398532D02*
X3306392Y399193D01*
G01X3306372D02*
X3306403Y397604D01*
G01X3302468Y398532D02*
X3302455Y399193D01*
G01X3302435D02*
X3302466Y397604D01*
G01X3302417Y401063D02*
X3301307D01*
G01X3310291D02*
X3309181D01*
G01X3302417Y400078D02*
X3301307D01*
G01X3310291D02*
X3309181D01*
G01X3302487Y398602D02*
X3301237D01*
G01X3306424D02*
X3305174D01*
G01X3310361D02*
X3309111D01*
G01X3314298D02*
X3313048D01*
G01X3313067Y398532D02*
X3314279D01*
G01X3309130D02*
X3310342D01*
G01X3305193D02*
X3306405D01*
G01X3301256D02*
X3302468D01*
G01X3302477Y398306D02*
X3301247D01*
G01X3306414D02*
X3305184D01*
G01X3310351D02*
X3309121D01*
G01X3314288D02*
X3313058D01*
G01X3313045Y397691D02*
X3314301D01*
G01X3309108D02*
X3310364D01*
G01X3305171D02*
X3306427D01*
G01X3301234D02*
X3302490D01*
G01X3302466Y397604D02*
X3301258D01*
G01X3306403D02*
X3305195D01*
G01X3310340D02*
X3309132D01*
G01X3314277D02*
X3313069D01*
G01X3302477Y397322D02*
X3301247D01*
G01X3306414D02*
X3305184D01*
G01X3310351D02*
X3309121D01*
G01X3314288D02*
X3313058D01*
G01X3316975Y392106D02*
X3316985Y392697D01*
G01X3316982Y393607D02*
X3316957Y392106D01*
G01X3317045Y389519D02*
X3317040Y387732D01*
G01X3317031Y388000D02*
X3317036Y389787D01*
G01X3317177Y391220D02*
Y390236D01*
G01X3317022Y386299D02*
Y387283D01*
G01X3314326Y392106D02*
X3314301Y393607D01*
G01X3314298Y392697D02*
X3314308Y392106D01*
G01X3317037D02*
X3317006Y393694D01*
G01X3317004Y392767D02*
X3317017Y392106D01*
G01X3316995Y393977D02*
X3318225D01*
G01X3317006Y393694D02*
X3318214D01*
G01X3318238Y393607D02*
X3316982D01*
G01X3316995Y392993D02*
X3318225D01*
G01X3318216Y392767D02*
X3317004D01*
G01X3316985Y392697D02*
X3318235D01*
G01X3318165Y391220D02*
X3317055D01*
G01Y390236D02*
X3318165D01*
G01X3317036Y389787D02*
X3318184D01*
G01X3318175Y389519D02*
X3317045D01*
G01X3318189Y388000D02*
X3317031D01*
G01X3317040Y387732D02*
X3318180D01*
G01X3317022Y387283D02*
X3318198D01*
G01Y386299D02*
X3317022D01*
G01X3317006Y397604D02*
X3317037Y399193D01*
G01X3317017D02*
X3317004Y398532D01*
G01X3314301Y397691D02*
X3314326Y399193D01*
G01X3314308D02*
X3314298Y398602D01*
G01X3317177Y400078D02*
Y401063D01*
G01X3316985Y398602D02*
X3316975Y399193D01*
G01X3316957D02*
X3316982Y397691D01*
G01X3318165Y401063D02*
X3317055D01*
G01X3318165Y400078D02*
X3317055D01*
G01X3318235Y398602D02*
X3316985D01*
G01X3317004Y398532D02*
X3318216D01*
G01X3318225Y398306D02*
X3316995D01*
G01X3316982Y397691D02*
X3318238D01*
G01X3318214Y397604D02*
X3317006D01*
G01X3318225Y397322D02*
X3316995D01*
G01X3313108Y407236D02*
X3313103Y405449D01*
G01X3313094Y405716D02*
X3313099Y407504D01*
G01X3310315Y403299D02*
X3310310Y401512D01*
G01X3310301Y401779D02*
X3310306Y403567D01*
G01X3305234Y407236D02*
X3305229Y405449D01*
G01X3305220Y405716D02*
X3305225Y407504D01*
G01X3302441Y403299D02*
X3302436Y401512D01*
G01X3302427Y401779D02*
X3302432Y403567D01*
G01X3314261Y404015D02*
Y405000D01*
G01X3314106Y408937D02*
Y407952D01*
G01X3313240D02*
Y408937D01*
G01X3313085Y405000D02*
Y404015D01*
G01X3310324Y405000D02*
Y404015D01*
G01X3309185Y415728D02*
Y410118D01*
G01X3309148Y404015D02*
Y405000D01*
G01X3306387Y404015D02*
Y405000D01*
G01X3306232Y408937D02*
Y407952D01*
G01X3305366D02*
Y408937D01*
G01X3305211Y405000D02*
Y404015D01*
G01X3304185Y415728D02*
Y410118D01*
G01X3302450Y405000D02*
Y404015D01*
G01X3301274D02*
Y405000D01*
G01X3314247Y407504D02*
X3314252Y405716D01*
G01X3314243Y405449D02*
X3314238Y407236D01*
G01X3309166Y403567D02*
X3309171Y401779D01*
G01X3309162Y401512D02*
X3309157Y403299D01*
G01X3306373Y407504D02*
X3306378Y405716D01*
G01X3306369Y405449D02*
X3306364Y407236D01*
G01X3301292Y403567D02*
X3301297Y401779D01*
G01X3301288Y401512D02*
X3301283Y403299D01*
G01X3306354Y408937D02*
X3305244D01*
G01X3314228D02*
X3313118D01*
G01X3306354Y407952D02*
X3305244D01*
G01X3314228D02*
X3313118D01*
G01X3313099Y407504D02*
X3314247D01*
G01X3305225D02*
X3306373D01*
G01X3306364Y407236D02*
X3305234D01*
G01X3314238D02*
X3313108D01*
G01X3306378Y405716D02*
X3305220D01*
G01X3314252D02*
X3313094D01*
G01X3313103Y405449D02*
X3314243D01*
G01X3305229D02*
X3306369D01*
G01X3302450Y405000D02*
X3301274D01*
G01X3306387D02*
X3305211D01*
G01X3310324D02*
X3309148D01*
G01X3314261D02*
X3313085D01*
G01X3302450Y404015D02*
X3301274D01*
G01X3306387D02*
X3305211D01*
G01X3310324D02*
X3309148D01*
G01X3314261D02*
X3313085D01*
G01X3302432Y403567D02*
X3301292D01*
G01X3310306D02*
X3309166D01*
G01X3309157Y403299D02*
X3310315D01*
G01X3301283D02*
X3302441D01*
G01X3309171Y401779D02*
X3310301D01*
G01X3301297D02*
X3302427D01*
G01X3302436Y401512D02*
X3301288D01*
G01X3310310D02*
X3309162D01*
G01X3325090Y415728D02*
X3309185D01*
G01X3317022Y405000D02*
Y404015D01*
G01X3317040Y403567D02*
X3317045Y401779D01*
G01X3317036Y401512D02*
X3317031Y403299D01*
G01X3318198Y405000D02*
X3317022D01*
G01X3318198Y404015D02*
X3317022D01*
G01X3318180Y403567D02*
X3317040D01*
G01X3317031Y403299D02*
X3318189D01*
G01X3317045Y401779D02*
X3318175D01*
G01X3318184Y401512D02*
X3317036D01*
G01X3309415Y566864D02*
X3321226D01*
G01X3304618Y1094074D02*
X3301862D01*
G01X3308555D02*
X3305799D01*
G01X3312492D02*
X3309736D01*
G01X3316429D02*
X3313673D01*
G01D02*
Y1110610D01*
G01X3312492D02*
Y1094074D01*
G01X3309736D02*
Y1110610D01*
G01X3308555D02*
Y1094074D01*
G01X3305799D02*
Y1110610D01*
G01X3304618D02*
Y1094074D01*
G01X3301862D02*
Y1110610D01*
G01X3316429D02*
Y1094074D01*
G01X3313673Y1110610D02*
X3316429D01*
G01X3309736D02*
X3312492D01*
G01X3305799D02*
X3308555D01*
G01X3301862D02*
X3304618D01*
G01X3319263Y1118759D02*
X3316862D01*
G01D02*
Y1123563D01*
G01D02*
X3319263D01*
G01X3330000Y385582D02*
X3329995Y383795D01*
G01X3329986Y384063D02*
X3329991Y385850D01*
G01X3322126Y385582D02*
X3322121Y383795D01*
G01X3322112Y384063D02*
X3322117Y385850D01*
G01X3329854Y383346D02*
Y382362D01*
G01X3328988Y383346D02*
Y382362D01*
G01X3321980Y383346D02*
Y382362D01*
G01X3321114Y383346D02*
Y382362D01*
G01X3328851Y385850D02*
X3328856Y384063D01*
G01X3328847Y383795D02*
X3328842Y385582D01*
G01X3320977Y385850D02*
X3320982Y384063D01*
G01X3320973Y383795D02*
X3320968Y385582D01*
G01X3328856Y384063D02*
X3329986D01*
G01X3320982D02*
X3322112D01*
G01X3322121Y383795D02*
X3320973D01*
G01X3329995D02*
X3328847D01*
G01X3322102Y383346D02*
X3320992D01*
G01X3329976D02*
X3328866D01*
G01Y382362D02*
X3329976D01*
G01X3320992D02*
X3322102D01*
G01X3330014Y392106D02*
X3330027Y392767D01*
G01X3330025Y393694D02*
X3329994Y392106D01*
G01X3326077D02*
X3326090Y392767D01*
G01X3326088Y393694D02*
X3326057Y392106D01*
G01X3322140D02*
X3322153Y392767D01*
G01X3322151Y393694D02*
X3322120Y392106D01*
G01X3318203D02*
X3318216Y392767D01*
G01X3318214Y393694D02*
X3318183Y392106D01*
G01X3328786D02*
X3328796Y392697D01*
G01X3328793Y393607D02*
X3328768Y392106D01*
G01X3324849D02*
X3324859Y392697D01*
G01X3324856Y393607D02*
X3324831Y392106D01*
G01X3320912D02*
X3320922Y392697D01*
G01X3320919Y393607D02*
X3320894Y392106D01*
G01X3324919Y389519D02*
X3324914Y387732D01*
G01X3324905Y388000D02*
X3324910Y389787D01*
G01X3330009Y386299D02*
Y387283D01*
G01X3328833D02*
Y386299D01*
G01X3326072Y387283D02*
Y386299D01*
G01X3325917Y391220D02*
Y390236D01*
G01X3325051Y391220D02*
Y390236D01*
G01X3324896Y386299D02*
Y387283D01*
G01X3322135Y386299D02*
Y387283D01*
G01X3320959D02*
Y386299D01*
G01X3318198Y387283D02*
Y386299D01*
G01X3318043Y391220D02*
Y390236D01*
G01X3326058Y389787D02*
X3326063Y388000D01*
G01X3326054Y387732D02*
X3326049Y389519D01*
G01X3318184Y389787D02*
X3318189Y388000D01*
G01X3318180Y387732D02*
X3318175Y389519D01*
G01X3330074Y392106D02*
X3330049Y393607D01*
G01X3330046Y392697D02*
X3330056Y392106D01*
G01X3326137D02*
X3326112Y393607D01*
G01X3326109Y392697D02*
X3326119Y392106D01*
G01X3322200D02*
X3322175Y393607D01*
G01X3322172Y392697D02*
X3322182Y392106D01*
G01X3318263D02*
X3318238Y393607D01*
G01X3318235Y392697D02*
X3318245Y392106D01*
G01X3328848D02*
X3328817Y393694D01*
G01X3328815Y392767D02*
X3328828Y392106D01*
G01X3324911D02*
X3324880Y393694D01*
G01X3324878Y392767D02*
X3324891Y392106D01*
G01X3320974D02*
X3320943Y393694D01*
G01X3320941Y392767D02*
X3320954Y392106D01*
G01X3328806Y393977D02*
X3330036D01*
G01X3324869D02*
X3326099D01*
G01X3320932D02*
X3322162D01*
G01X3328817Y393694D02*
X3330025D01*
G01X3324880D02*
X3326088D01*
G01X3320943D02*
X3322151D01*
G01X3326112Y393607D02*
X3324856D01*
G01X3322175D02*
X3320919D01*
G01X3330049D02*
X3328793D01*
G01X3328806Y392993D02*
X3330036D01*
G01X3324869D02*
X3326099D01*
G01X3320932D02*
X3322162D01*
G01X3326090Y392767D02*
X3324878D01*
G01X3322153D02*
X3320941D01*
G01X3330027D02*
X3328815D01*
G01X3328796Y392697D02*
X3330046D01*
G01X3324859D02*
X3326109D01*
G01X3320922D02*
X3322172D01*
G01X3326039Y391220D02*
X3324929D01*
G01Y390236D02*
X3326039D01*
G01X3324910Y389787D02*
X3326058D01*
G01X3326049Y389519D02*
X3324919D01*
G01X3326063Y388000D02*
X3324905D01*
G01X3324914Y387732D02*
X3326054D01*
G01X3328833Y387283D02*
X3330009D01*
G01X3324896D02*
X3326072D01*
G01X3320959D02*
X3322135D01*
G01X3326072Y386299D02*
X3324896D01*
G01X3322135D02*
X3320959D01*
G01X3330009D02*
X3328833D01*
G01X3322117Y385850D02*
X3320977D01*
G01X3329991D02*
X3328851D01*
G01X3328842Y385582D02*
X3330000D01*
G01X3320968D02*
X3322126D01*
G01X3328817Y397604D02*
X3328848Y399193D01*
G01X3328828D02*
X3328815Y398532D01*
G01X3324880Y397604D02*
X3324911Y399193D01*
G01X3324891D02*
X3324878Y398532D01*
G01X3320943Y397604D02*
X3320974Y399193D01*
G01X3320954D02*
X3320941Y398532D01*
G01X3330049Y397691D02*
X3330074Y399193D01*
G01X3330056D02*
X3330046Y398602D01*
G01X3326112Y397691D02*
X3326137Y399193D01*
G01X3326119D02*
X3326109Y398602D01*
G01X3322175Y397691D02*
X3322200Y399193D01*
G01X3322182D02*
X3322172Y398602D01*
G01X3318238Y397691D02*
X3318263Y399193D01*
G01X3318245D02*
X3318235Y398602D01*
G01X3325917Y401063D02*
Y400078D01*
G01X3325051D02*
Y401063D01*
G01X3318043D02*
Y400078D01*
G01X3328796Y398602D02*
X3328786Y399193D01*
G01X3328768D02*
X3328793Y397691D01*
G01X3324859Y398602D02*
X3324849Y399193D01*
G01X3324831D02*
X3324856Y397691D01*
G01X3320922Y398602D02*
X3320912Y399193D01*
G01X3320894D02*
X3320919Y397691D01*
G01X3330027Y398532D02*
X3330014Y399193D01*
G01X3329994D02*
X3330025Y397604D01*
G01X3326090Y398532D02*
X3326077Y399193D01*
G01X3326057D02*
X3326088Y397604D01*
G01X3322153Y398532D02*
X3322140Y399193D01*
G01X3322120D02*
X3322151Y397604D01*
G01X3318216Y398532D02*
X3318203Y399193D01*
G01X3318183D02*
X3318214Y397604D01*
G01X3326039Y401063D02*
X3324929D01*
G01X3326039Y400078D02*
X3324929D01*
G01X3326109Y398602D02*
X3324859D01*
G01X3322172D02*
X3320922D01*
G01X3330046D02*
X3328796D01*
G01X3328815Y398532D02*
X3330027D01*
G01X3324878D02*
X3326090D01*
G01X3320941D02*
X3322153D01*
G01X3326099Y398306D02*
X3324869D01*
G01X3322162D02*
X3320932D01*
G01X3330036D02*
X3328806D01*
G01X3328793Y397691D02*
X3330049D01*
G01X3324856D02*
X3326112D01*
G01X3320919D02*
X3322175D01*
G01X3326088Y397604D02*
X3324880D01*
G01X3322151D02*
X3320943D01*
G01X3330025D02*
X3328817D01*
G01X3326099Y397322D02*
X3324869D01*
G01X3322162D02*
X3320932D01*
G01X3330036D02*
X3328806D01*
G01X3332723Y392106D02*
X3332733Y392697D01*
G01X3332730Y393607D02*
X3332705Y392106D01*
G01X3332793Y389519D02*
X3332788Y387732D01*
G01X3332779Y388000D02*
X3332784Y389787D01*
G01X3333791Y391220D02*
Y390236D01*
G01X3332925Y391220D02*
Y390236D01*
G01X3332770Y386299D02*
Y387283D01*
G01X3332785Y392106D02*
X3332754Y393694D01*
G01X3332752Y392767D02*
X3332765Y392106D01*
G01X3332743Y393977D02*
X3333973D01*
G01X3332754Y393694D02*
X3333962D01*
G01X3333986Y393607D02*
X3332730D01*
G01X3332743Y392993D02*
X3333973D01*
G01X3333964Y392767D02*
X3332752D01*
G01X3332733Y392697D02*
X3333983D01*
G01X3333913Y391220D02*
X3332803D01*
G01Y390236D02*
X3333913D01*
G01X3332784Y389787D02*
X3333932D01*
G01X3333923Y389519D02*
X3332793D01*
G01X3333937Y388000D02*
X3332779D01*
G01X3332788Y387732D02*
X3333928D01*
G01X3332770Y387283D02*
X3333946D01*
G01Y386299D02*
X3332770D01*
G01X3332754Y397604D02*
X3332785Y399193D01*
G01X3332765D02*
X3332752Y398532D01*
G01X3333791Y401063D02*
Y400078D01*
G01X3332925D02*
Y401063D01*
G01X3332733Y398602D02*
X3332723Y399193D01*
G01X3332705D02*
X3332730Y397691D01*
G01X3333913Y401063D02*
X3332803D01*
G01X3333913Y400078D02*
X3332803D01*
G01X3333983Y398602D02*
X3332733D01*
G01X3332752Y398532D02*
X3333964D01*
G01X3333973Y398306D02*
X3332743D01*
G01X3332730Y397691D02*
X3333986D01*
G01X3333962Y397604D02*
X3332754D01*
G01X3333973Y397322D02*
X3332743D01*
G01X3328856Y407236D02*
X3328851Y405449D01*
G01X3328842Y405716D02*
X3328847Y407504D01*
G01X3326063Y403299D02*
X3326058Y401512D01*
G01X3326049Y401779D02*
X3326054Y403567D01*
G01X3320982Y407236D02*
X3320977Y405449D01*
G01X3320968Y405716D02*
X3320973Y407504D01*
G01X3318189Y403299D02*
X3318184Y401512D01*
G01X3318175Y401779D02*
X3318180Y403567D01*
G01X3330090Y415728D02*
Y410118D01*
G01X3330009Y405000D02*
Y404015D01*
G01X3329854Y408937D02*
Y407952D01*
G01X3328988D02*
Y408937D01*
G01X3328833Y404015D02*
Y405000D01*
G01X3326072D02*
Y404015D01*
G01X3325090Y415728D02*
Y410118D01*
G01X3324896Y404015D02*
Y405000D01*
G01X3322135Y404015D02*
Y405000D01*
G01X3321980Y408937D02*
Y407952D01*
G01X3321114D02*
Y408937D01*
G01X3320959Y405000D02*
Y404015D01*
G01X3318198D02*
Y405000D01*
G01X3329995Y407504D02*
X3330000Y405716D01*
G01X3329991Y405449D02*
X3329986Y407236D01*
G01X3324914Y403567D02*
X3324919Y401779D01*
G01X3324910Y401512D02*
X3324905Y403299D01*
G01X3322121Y407504D02*
X3322126Y405716D01*
G01X3322117Y405449D02*
X3322112Y407236D01*
G01X3322102Y408937D02*
X3320992D01*
G01X3329976D02*
X3328866D01*
G01X3322102Y407952D02*
X3320992D01*
G01X3329976D02*
X3328866D01*
G01X3328847Y407504D02*
X3329995D01*
G01X3320973D02*
X3322121D01*
G01X3322112Y407236D02*
X3320982D01*
G01X3329986D02*
X3328856D01*
G01X3322126Y405716D02*
X3320968D01*
G01X3330000D02*
X3328842D01*
G01X3328851Y405449D02*
X3329991D01*
G01X3320977D02*
X3322117D01*
G01X3326072Y405000D02*
X3324896D01*
G01X3322135D02*
X3320959D01*
G01X3330009D02*
X3328833D01*
G01X3326072Y404015D02*
X3324896D01*
G01X3322135D02*
X3320959D01*
G01X3330009D02*
X3328833D01*
G01X3326054Y403567D02*
X3324914D01*
G01X3324905Y403299D02*
X3326063D01*
G01X3324919Y401779D02*
X3326049D01*
G01X3326058Y401512D02*
X3324910D01*
G01X3345996Y415728D02*
X3330090D01*
G01X3332770Y404015D02*
Y405000D01*
G01X3332788Y403567D02*
X3332793Y401779D01*
G01X3332784Y401512D02*
X3332779Y403299D01*
G01X3333946Y405000D02*
X3332770D01*
G01X3333946Y404015D02*
X3332770D01*
G01X3333928Y403567D02*
X3332788D01*
G01X3332779Y403299D02*
X3333937D01*
G01X3332793Y401779D02*
X3333923D01*
G01X3333932Y401512D02*
X3332784D01*
G01X3329487Y455531D02*
Y462313D01*
G01X3321035D02*
Y455531D01*
G01X3319224D02*
Y470019D01*
G01X3321035Y455531D02*
X3319224D01*
G01X3331298D02*
X3329487D01*
G01Y464163D02*
Y470019D01*
G01X3321035D02*
Y464163D01*
G01D02*
X3329487D01*
G01Y462313D02*
X3321035D01*
G01X3333712Y460463D02*
Y461696D01*
G01X3331298Y470019D02*
Y455531D01*
G01X3338542Y460463D02*
X3333712D01*
G01Y464163D02*
Y465395D01*
G01D02*
X3338542D01*
G01Y464163D02*
X3333712D01*
G01Y461696D02*
X3338542D01*
G01X3329487Y470019D02*
X3331298D01*
G01X3319224D02*
X3321035D01*
G01X3321984Y562533D02*
Y571194D01*
X3326964Y562533D01*
Y571194D01*
G01X3333135Y562533D02*
X3332485Y562677D01*
X3331836Y563255D01*
X3331403Y564265D01*
X3331186Y565420D01*
X3331403Y566575D01*
X3331836Y567585D01*
X3332485Y568163D01*
X3333135Y568307D01*
X3333785Y568163D01*
X3334434Y567585D01*
X3334867Y566575D01*
X3334976Y565420D01*
X3334867Y564265D01*
X3334434Y563255D01*
X3333785Y562677D01*
X3333135Y562533D01*
G01X3350457Y571194D02*
Y562533D01*
G01X3348941Y568307D02*
X3351973D01*
G01X3357602Y562533D02*
Y568307D01*
G01Y567152D02*
X3358144Y567730D01*
X3358685Y568163D01*
X3359443Y568307D01*
X3359984Y568163D01*
X3360634Y567730D01*
G01X3369728Y562533D02*
Y568307D01*
G01Y567297D02*
X3369295Y567874D01*
X3368645Y568163D01*
X3367887Y568307D01*
X3367129Y568018D01*
X3366480Y567441D01*
X3366047Y566575D01*
X3365830Y565420D01*
X3366047Y564265D01*
X3366480Y563399D01*
X3367129Y562822D01*
X3367887Y562533D01*
X3368645Y562677D01*
X3369295Y563110D01*
X3369728Y563688D01*
G01X3378172Y567585D02*
X3377414Y568163D01*
X3376765Y568307D01*
X3375899Y568018D01*
X3375249Y567441D01*
X3374816Y566430D01*
X3374708Y565420D01*
X3374816Y564409D01*
X3375249Y563543D01*
X3375899Y562822D01*
X3376765Y562533D01*
X3377523Y562822D01*
X3378172Y563399D01*
G01X3383477Y566430D02*
X3386942D01*
X3386617Y567441D01*
X3386075Y568018D01*
X3385318Y568307D01*
X3384560Y568163D01*
X3383910Y567730D01*
X3383477Y566719D01*
X3383260Y565853D01*
Y564987D01*
X3383477Y564121D01*
X3384018Y563255D01*
X3384668Y562677D01*
X3385426Y562533D01*
X3386184Y562822D01*
X3386942Y563688D01*
G01X3404372Y562533D02*
Y568307D01*
G01Y567297D02*
X3403939Y567874D01*
X3403289Y568163D01*
X3402531Y568307D01*
X3401773Y568018D01*
X3401124Y567441D01*
X3400691Y566575D01*
X3400474Y565420D01*
X3400691Y564265D01*
X3401124Y563399D01*
X3401773Y562822D01*
X3402531Y562533D01*
X3403289Y562677D01*
X3403939Y563110D01*
X3404372Y563688D01*
G01X3411084Y571194D02*
Y562533D01*
G01X3409568Y568307D02*
X3412600D01*
G01X3426782Y563543D02*
X3427323Y562966D01*
X3428081Y562533D01*
X3428731D01*
X3429380Y562822D01*
X3429813Y563255D01*
X3430030Y563832D01*
X3429922Y564698D01*
X3429489Y565131D01*
X3427540Y565997D01*
X3427107Y567008D01*
X3427323Y567730D01*
X3427756Y568163D01*
X3428406Y568307D01*
X3429056Y568163D01*
X3429705Y567730D01*
G01X3435226Y568307D02*
Y564265D01*
X3435660Y563255D01*
X3436309Y562677D01*
X3437067Y562533D01*
X3437825Y562677D01*
X3438474Y563255D01*
X3438908Y564265D01*
G01Y562533D02*
Y568307D01*
G01X3444212Y562533D02*
Y568307D01*
G01Y567152D02*
X3444754Y567730D01*
X3445295Y568163D01*
X3446053Y568307D01*
X3446594Y568163D01*
X3447244Y567730D01*
G01X3453739Y562533D02*
Y569895D01*
X3453956Y570616D01*
X3454389Y571050D01*
X3455039Y571194D01*
X3455688Y570905D01*
X3456013Y570184D01*
G01X3454714Y567730D02*
X3452548D01*
G01X3464999Y562533D02*
Y568307D01*
G01Y567297D02*
X3464566Y567874D01*
X3463916Y568163D01*
X3463158Y568307D01*
X3462400Y568018D01*
X3461751Y567441D01*
X3461318Y566575D01*
X3461101Y565420D01*
X3461318Y564265D01*
X3461751Y563399D01*
X3462400Y562822D01*
X3463158Y562533D01*
X3463916Y562677D01*
X3464566Y563110D01*
X3464999Y563688D01*
G01X3473443Y567585D02*
X3472685Y568163D01*
X3472036Y568307D01*
X3471170Y568018D01*
X3470520Y567441D01*
X3470087Y566430D01*
X3469979Y565420D01*
X3470087Y564409D01*
X3470520Y563543D01*
X3471170Y562822D01*
X3472036Y562533D01*
X3472794Y562822D01*
X3473443Y563399D01*
G01X3478748Y566430D02*
X3482213D01*
X3481888Y567441D01*
X3481346Y568018D01*
X3480589Y568307D01*
X3479831Y568163D01*
X3479181Y567730D01*
X3478748Y566719D01*
X3478531Y565853D01*
Y564987D01*
X3478748Y564121D01*
X3479289Y563255D01*
X3479939Y562677D01*
X3480697Y562533D01*
X3481455Y562822D01*
X3482213Y563688D01*
G01X3321547Y1084626D02*
G03X3325484Y1080689I3937J0D01*
G01X3426665D02*
X3325484D01*
G01X3321547Y1084626D02*
Y1114153D01*
G01X3320366Y1094074D02*
X3317610D01*
G01X3320366Y1110610D02*
Y1094074D01*
G01X3317610D02*
Y1110610D01*
G01D02*
X3320366D01*
G01X3321547Y1114153D02*
X3319578Y1116122D01*
G01X3319964Y1121212D02*
X3320164Y1121110D01*
G01X3319664Y1122847D02*
X3319363Y1122950D01*
G01Y1120906D02*
X3319664Y1120804D01*
G01X3319263Y1123563D02*
X3319764Y1123461D01*
G01X3319363Y1122950D02*
X3317462D01*
G01Y1121519D02*
X3319363D01*
G01X3317462Y1120906D02*
X3319363D01*
G01Y1119373D02*
X3317462D01*
G01X3322566Y1118759D02*
X3321965D01*
G01X3319764Y1118862D02*
X3319263Y1118759D01*
G01X3319764Y1123461D02*
X3320164Y1123154D01*
G01X3319864Y1122643D02*
X3319664Y1122847D01*
G01Y1120804D02*
X3319864Y1120599D01*
G01X3320164Y1123154D02*
X3320464Y1122745D01*
G01X3320164Y1121110D02*
X3320464Y1120701D01*
G01Y1122745D02*
X3320564Y1122439D01*
G01X3319964Y1122336D02*
X3319864Y1122643D01*
G01X3320464Y1120701D02*
X3320564Y1120394D01*
G01X3319864Y1120599D02*
X3319964Y1120293D01*
G01X3322566Y1123563D02*
Y1118759D01*
G01X3321965D02*
Y1122745D01*
G01X3321365Y1122030D02*
Y1122847D01*
G01X3320564Y1120394D02*
Y1119883D01*
G01Y1122439D02*
Y1122030D01*
G01X3319964Y1122132D02*
Y1122336D01*
G01Y1120293D02*
Y1119986D01*
G01X3317462Y1119373D02*
Y1120906D01*
G01Y1122950D02*
Y1121519D01*
G01X3320564Y1119883D02*
X3320464Y1119577D01*
G01X3319964Y1119986D02*
X3319864Y1119679D01*
G01X3320564Y1122030D02*
X3320464Y1121723D01*
G01X3319864Y1121825D02*
X3319964Y1122132D01*
G01X3320464Y1119577D02*
X3320164Y1119168D01*
G01X3320464Y1121723D02*
X3320164Y1121315D01*
G01X3319864Y1119679D02*
X3319664Y1119475D01*
G01Y1121621D02*
X3319864Y1121825D01*
G01X3321965Y1122745D02*
X3321365Y1122030D01*
G01Y1122847D02*
X3321965Y1123563D01*
G01X3320164Y1119168D02*
X3319764Y1118862D01*
G01X3319664Y1119475D02*
X3319363Y1119373D01*
G01Y1121519D02*
X3319664Y1121621D01*
G01X3320164Y1121315D02*
X3319964Y1121212D01*
G01X3321965Y1123563D02*
X3322566D01*
G01X3348431Y-1837784D02*
Y-1856796D01*
G01X3345748Y385582D02*
X3345743Y383795D01*
G01X3345734Y384063D02*
X3345739Y385850D01*
G01X3337874Y385582D02*
X3337869Y383795D01*
G01X3337860Y384063D02*
X3337865Y385850D01*
G01X3346153Y382657D02*
Y382854D01*
G01X3345602Y383346D02*
Y382362D01*
G01X3344736Y383346D02*
Y382362D01*
G01X3338771Y382657D02*
Y382854D01*
G01X3337728Y383346D02*
Y382362D01*
G01X3337295Y382854D02*
Y382657D01*
G01X3336862Y383346D02*
Y382362D01*
G01X3344599Y385850D02*
X3344604Y384063D01*
G01X3344595Y383795D02*
X3344590Y385582D01*
G01X3336725Y385850D02*
X3336730Y384063D01*
G01X3336721Y383795D02*
X3336716Y385582D01*
G01X3344604Y384063D02*
X3345734D01*
G01X3336730D02*
X3337860D01*
G01X3337869Y383795D02*
X3336721D01*
G01X3345743D02*
X3344595D01*
G01X3337850Y383346D02*
X3336740D01*
G01X3345724D02*
X3344614D01*
G01X3346153Y382657D02*
X3337295D01*
G01X3344614Y382362D02*
X3345724D01*
G01X3336740D02*
X3337850D01*
G01X3349844Y382854D02*
Y382657D01*
G01X3349598Y382854D02*
Y382657D01*
G01X3348860D02*
Y382854D01*
G01X3348368Y382657D02*
Y382854D01*
G01X3348122Y382657D02*
Y382854D01*
G01X3357964Y382657D02*
X3348122D01*
G01X3345762Y392106D02*
X3345775Y392767D01*
G01X3345773Y393694D02*
X3345742Y392106D01*
G01X3341825D02*
X3341838Y392767D01*
G01X3341836Y393694D02*
X3341805Y392106D01*
G01X3337888D02*
X3337901Y392767D01*
G01X3337899Y393694D02*
X3337868Y392106D01*
G01X3333951D02*
X3333964Y392767D01*
G01X3333962Y393694D02*
X3333931Y392106D01*
G01X3344534D02*
X3344544Y392697D01*
G01X3344541Y393607D02*
X3344516Y392106D01*
G01X3340597D02*
X3340607Y392697D01*
G01X3340604Y393607D02*
X3340579Y392106D01*
G01X3336660D02*
X3336670Y392697D01*
G01X3336667Y393607D02*
X3336642Y392106D01*
G01X3340667Y389519D02*
X3340662Y387732D01*
G01X3340653Y388000D02*
X3340658Y389787D01*
G01X3345757Y386299D02*
Y387283D01*
G01X3344581D02*
Y386299D01*
G01X3341820Y387283D02*
Y386299D01*
G01X3341665Y391220D02*
Y390236D01*
G01X3340799Y391220D02*
Y390236D01*
G01X3340644Y386299D02*
Y387283D01*
G01X3337883Y386299D02*
Y387283D01*
G01X3336707D02*
Y386299D01*
G01X3333946Y387283D02*
Y386299D01*
G01X3341806Y389787D02*
X3341811Y388000D01*
G01X3341802Y387732D02*
X3341797Y389519D01*
G01X3333932Y389787D02*
X3333937Y388000D01*
G01X3333928Y387732D02*
X3333923Y389519D01*
G01X3345822Y392106D02*
X3345797Y393607D01*
G01X3345794Y392697D02*
X3345804Y392106D01*
G01X3341885D02*
X3341860Y393607D01*
G01X3341857Y392697D02*
X3341867Y392106D01*
G01X3337948D02*
X3337923Y393607D01*
G01X3337920Y392697D02*
X3337930Y392106D01*
G01X3334011D02*
X3333986Y393607D01*
G01X3333983Y392697D02*
X3333993Y392106D01*
G01X3344596D02*
X3344565Y393694D01*
G01X3344563Y392767D02*
X3344576Y392106D01*
G01X3340659D02*
X3340628Y393694D01*
G01X3340626Y392767D02*
X3340639Y392106D01*
G01X3336722D02*
X3336691Y393694D01*
G01X3336689Y392767D02*
X3336702Y392106D01*
G01X3344554Y393977D02*
X3345784D01*
G01X3340617D02*
X3341847D01*
G01X3336680D02*
X3337910D01*
G01X3344565Y393694D02*
X3345773D01*
G01X3340628D02*
X3341836D01*
G01X3336691D02*
X3337899D01*
G01X3337923Y393607D02*
X3336667D01*
G01X3341860D02*
X3340604D01*
G01X3345797D02*
X3344541D01*
G01X3344554Y392993D02*
X3345784D01*
G01X3340617D02*
X3341847D01*
G01X3336680D02*
X3337910D01*
G01X3337901Y392767D02*
X3336689D01*
G01X3341838D02*
X3340626D01*
G01X3345775D02*
X3344563D01*
G01X3344544Y392697D02*
X3345794D01*
G01X3340607D02*
X3341857D01*
G01X3336670D02*
X3337920D01*
G01X3341787Y391220D02*
X3340677D01*
G01Y390236D02*
X3341787D01*
G01X3340658Y389787D02*
X3341806D01*
G01X3341797Y389519D02*
X3340667D01*
G01X3341811Y388000D02*
X3340653D01*
G01X3340662Y387732D02*
X3341802D01*
G01X3344581Y387283D02*
X3345757D01*
G01X3340644D02*
X3341820D01*
G01X3336707D02*
X3337883D01*
G01Y386299D02*
X3336707D01*
G01X3341820D02*
X3340644D01*
G01X3345757D02*
X3344581D01*
G01X3337865Y385850D02*
X3336725D01*
G01X3345739D02*
X3344599D01*
G01X3344590Y385582D02*
X3345748D01*
G01X3336716D02*
X3337874D01*
G01X3344565Y397604D02*
X3344596Y399193D01*
G01X3344576D02*
X3344563Y398532D01*
G01X3340628Y397604D02*
X3340659Y399193D01*
G01X3340639D02*
X3340626Y398532D01*
G01X3336691Y397604D02*
X3336722Y399193D01*
G01X3336702D02*
X3336689Y398532D01*
G01X3345797Y397691D02*
X3345822Y399193D01*
G01X3345804D02*
X3345794Y398602D01*
G01X3341860Y397691D02*
X3341885Y399193D01*
G01X3341867D02*
X3341857Y398602D01*
G01X3337923Y397691D02*
X3337948Y399193D01*
G01X3337930D02*
X3337920Y398602D01*
G01X3333986Y397691D02*
X3334011Y399193D01*
G01X3333993D02*
X3333983Y398602D01*
G01X3341665Y401063D02*
Y400078D01*
G01X3340799D02*
Y401063D01*
G01X3344544Y398602D02*
X3344534Y399193D01*
G01X3344516D02*
X3344541Y397691D01*
G01X3340607Y398602D02*
X3340597Y399193D01*
G01X3340579D02*
X3340604Y397691D01*
G01X3336670Y398602D02*
X3336660Y399193D01*
G01X3336642D02*
X3336667Y397691D01*
G01X3345775Y398532D02*
X3345762Y399193D01*
G01X3345742D02*
X3345773Y397604D01*
G01X3341838Y398532D02*
X3341825Y399193D01*
G01X3341805D02*
X3341836Y397604D01*
G01X3337901Y398532D02*
X3337888Y399193D01*
G01X3337868D02*
X3337899Y397604D01*
G01X3333964Y398532D02*
X3333951Y399193D01*
G01X3333931D02*
X3333962Y397604D01*
G01X3341787Y401063D02*
X3340677D01*
G01X3341787Y400078D02*
X3340677D01*
G01X3337920Y398602D02*
X3336670D01*
G01X3341857D02*
X3340607D01*
G01X3345794D02*
X3344544D01*
G01X3344563Y398532D02*
X3345775D01*
G01X3340626D02*
X3341838D01*
G01X3336689D02*
X3337901D01*
G01X3337910Y398306D02*
X3336680D01*
G01X3341847D02*
X3340617D01*
G01X3345784D02*
X3344554D01*
G01X3344541Y397691D02*
X3345797D01*
G01X3340604D02*
X3341860D01*
G01X3336667D02*
X3337923D01*
G01X3337899Y397604D02*
X3336691D01*
G01X3341836D02*
X3340628D01*
G01X3345773D02*
X3344565D01*
G01X3337910Y397322D02*
X3336680D01*
G01X3341847D02*
X3340617D01*
G01X3345784D02*
X3344554D01*
G01X3347925Y394176D02*
G03Y397123I2559J1473D01*
G01Y392403D02*
G03X3354224Y393889I2559J3246D01*
G01X3347925Y392034D02*
G03X3354224Y393277I2559J3615D01*
G01X3348128Y392106D02*
Y390531D01*
G01X3347925Y399264D02*
Y392034D01*
G01X3347531Y399193D02*
Y392106D01*
G01X3354224Y397410D02*
G03X3347925Y398896I-3740J-1761D01*
G01X3354224Y398022D02*
G03X3347925Y399264I-3740J-2373D01*
G01X3348128Y400767D02*
Y399193D01*
G01X3344604Y407236D02*
X3344599Y405449D01*
G01X3344590Y405716D02*
X3344595Y407504D01*
G01X3341811Y403299D02*
X3341806Y401512D01*
G01X3341797Y401779D02*
X3341802Y403567D01*
G01X3336730Y407236D02*
X3336725Y405449D01*
G01X3336716Y405716D02*
X3336721Y407504D01*
G01X3333937Y403299D02*
X3333932Y401512D01*
G01X3333923Y401779D02*
X3333928Y403567D01*
G01X3346891Y408248D02*
Y408444D01*
G01X3346645Y408248D02*
Y408444D01*
G01X3346153Y408248D02*
Y408444D01*
G01X3345996Y415728D02*
Y410118D01*
G01X3345907Y408248D02*
Y408444D01*
G01X3345757Y404015D02*
Y405000D01*
G01X3345661Y408248D02*
Y408444D01*
G01X3345602Y408937D02*
Y407952D01*
G01X3345415Y408248D02*
Y408444D01*
G01X3345169Y408248D02*
Y408444D01*
G01X3344736Y407952D02*
Y408937D01*
G01X3344677Y408248D02*
Y408444D01*
G01X3344581Y405000D02*
Y404015D01*
G01X3344431Y408248D02*
Y408444D01*
G01X3344185Y408248D02*
Y408444D01*
G01X3343693Y408248D02*
Y408444D01*
G01X3342462Y408248D02*
Y408444D01*
G01X3342216Y408248D02*
Y408444D01*
G01X3341820Y405000D02*
Y404015D01*
G01X3341478Y408248D02*
Y408444D01*
G01X3341232Y408248D02*
Y408444D01*
G01X3340986Y408248D02*
Y408444D01*
G01X3340740D02*
Y408248D01*
G01X3340644Y404015D02*
Y405000D01*
G01X3340494Y408248D02*
Y408444D01*
G01X3340248Y408248D02*
Y408444D01*
G01X3340002Y408248D02*
Y408444D01*
G01X3339509Y408248D02*
Y408444D01*
G01X3339263Y408248D02*
Y408444D01*
G01X3339017Y408248D02*
Y408444D01*
G01X3338525Y408248D02*
Y408444D01*
G01X3337883Y404015D02*
Y405000D01*
G01X3337728Y408937D02*
Y407952D01*
G01X3336862D02*
Y408937D01*
G01X3336707Y405000D02*
Y404015D01*
G01X3333946Y405000D02*
Y404015D01*
G01X3345743Y407504D02*
X3345748Y405716D01*
G01X3345739Y405449D02*
X3345734Y407236D01*
G01X3340662Y403567D02*
X3340667Y401779D01*
G01X3340658Y401512D02*
X3340653Y403299D01*
G01X3337869Y407504D02*
X3337874Y405716D01*
G01X3337865Y405449D02*
X3337860Y407236D01*
G01X3337850Y408937D02*
X3336740D01*
G01X3345724D02*
X3344614D01*
G01X3347630Y408248D02*
X3338525D01*
G01X3337850Y407952D02*
X3336740D01*
G01X3345724D02*
X3344614D01*
G01X3344595Y407504D02*
X3345743D01*
G01X3336721D02*
X3337869D01*
G01X3337860Y407236D02*
X3336730D01*
G01X3345734D02*
X3344604D01*
G01X3337874Y405716D02*
X3336716D01*
G01X3345748D02*
X3344590D01*
G01X3344599Y405449D02*
X3345739D01*
G01X3336725D02*
X3337865D01*
G01X3337883Y405000D02*
X3336707D01*
G01X3341820D02*
X3340644D01*
G01X3345757D02*
X3344581D01*
G01X3337883Y404015D02*
X3336707D01*
G01X3341820D02*
X3340644D01*
G01X3345757D02*
X3344581D01*
G01X3341802Y403567D02*
X3340662D01*
G01X3340653Y403299D02*
X3341811D01*
G01X3340667Y401779D02*
X3341797D01*
G01X3341806Y401512D02*
X3340658D01*
G01X3349598Y408444D02*
Y408248D01*
G01X3347630D02*
Y408444D01*
G01X3347383Y408248D02*
Y408444D01*
G01X3358456Y408248D02*
X3349598D01*
G01X3346993Y457072D02*
X3355445Y464779D01*
G01X3346993Y455531D02*
Y457072D01*
G01X3344578Y470019D02*
Y455531D01*
G01X3342767D02*
Y467553D01*
G01X3338542Y461696D02*
Y460463D01*
G01X3344578Y455531D02*
X3342767D01*
G01X3357859D02*
X3346993D01*
G01X3342767Y467553D02*
X3340956Y465395D01*
G01D02*
Y467861D01*
G01X3338542Y465395D02*
Y464163D01*
G01X3356954Y463854D02*
X3349408Y457072D01*
G01D02*
X3357859D01*
G01X3349408Y467553D02*
X3348804Y466628D01*
G01X3347295D02*
X3347597Y467861D01*
G01X3348804Y466628D02*
X3347295D01*
G01X3340956Y467861D02*
X3342767Y470019D01*
G01D02*
X3344578D01*
G01X3348804Y469094D02*
X3350011Y469711D01*
G01X3350313Y468170D02*
X3349408Y467553D01*
G01X3347597Y467861D02*
X3348804Y469094D01*
G01X3350011Y469711D02*
X3352124Y470019D01*
G01X3348431Y1453929D02*
Y1434916D01*
G01X3361496Y385582D02*
X3361491Y383795D01*
G01X3361482Y384063D02*
X3361487Y385850D01*
G01X3361350Y383346D02*
Y382362D01*
G01X3360484Y383346D02*
Y382362D01*
G01X3359933Y382657D02*
Y382854D01*
G01X3357964Y382657D02*
Y382854D01*
G01X3357718Y382657D02*
Y382854D01*
G01X3357226Y382657D02*
Y382854D01*
G01X3356488D02*
Y382657D01*
G01X3356242Y382854D02*
Y382657D01*
G01X3360347Y385850D02*
X3360352Y384063D01*
G01X3360343Y383795D02*
X3360338Y385582D01*
G01X3355750Y382854D02*
Y382657D01*
G01X3355257D02*
Y382854D01*
G01X3355011D02*
Y382657D01*
G01X3354027Y382854D02*
Y382657D01*
G01X3352059Y382854D02*
Y382657D01*
G01X3351074Y382854D02*
Y382657D01*
G01X3350828D02*
Y382854D01*
G01X3350336D02*
Y382657D01*
G01X3360352Y384063D02*
X3361482D01*
G01X3361491Y383795D02*
X3360343D01*
G01X3361472Y383346D02*
X3360362D01*
G01X3359933Y382657D02*
X3369283D01*
G01X3360362Y382362D02*
X3361472D01*
G01X3365346Y382657D02*
Y382854D01*
G01X3363870Y382657D02*
Y382854D01*
G01X3361510Y392106D02*
X3361523Y392767D01*
G01X3361521Y393694D02*
X3361490Y392106D01*
G01X3357573D02*
X3357586Y392767D01*
G01X3357584Y393694D02*
X3357553Y392106D01*
G01X3360282D02*
X3360292Y392697D01*
G01X3360289Y393607D02*
X3360264Y392106D01*
G01X3356345D02*
X3356355Y392697D01*
G01X3356352Y393607D02*
X3356327Y392106D01*
G01X3356415Y389519D02*
X3356410Y387732D01*
G01X3356401Y388000D02*
X3356406Y389787D01*
G01X3361506Y387283D02*
Y386299D01*
G01X3360329D02*
Y387283D01*
G01X3357569D02*
Y386299D01*
G01X3357413Y391220D02*
Y390236D01*
G01X3356547Y391220D02*
Y390236D01*
G01X3356392Y386299D02*
Y387283D01*
G01X3357554Y389787D02*
X3357559Y388000D01*
G01X3357550Y387732D02*
X3357545Y389519D01*
G01X3361570Y392106D02*
X3361545Y393607D01*
G01X3361542Y392697D02*
X3361552Y392106D01*
G01X3360344D02*
X3360313Y393694D01*
G01X3360311Y392767D02*
X3360324Y392106D01*
G01X3354618D02*
Y399193D01*
G01X3354224Y398022D02*
Y393277D01*
G01X3354021Y390531D02*
Y392106D01*
G01X3357633D02*
X3357608Y393607D01*
G01X3357605Y392697D02*
X3357615Y392106D01*
G01X3356407D02*
X3356376Y393694D01*
G01X3356374Y392767D02*
X3356387Y392106D01*
G01X3360302Y393977D02*
X3361532D01*
G01X3356365D02*
X3357595D01*
G01X3360313Y393694D02*
X3361521D01*
G01X3356376D02*
X3357584D01*
G01X3357608Y393607D02*
X3356352D01*
G01X3361545D02*
X3360289D01*
G01X3360302Y392993D02*
X3361532D01*
G01X3356365D02*
X3357595D01*
G01X3357586Y392767D02*
X3356374D01*
G01X3361523D02*
X3360311D01*
G01X3360292Y392697D02*
X3361542D01*
G01X3356355D02*
X3357605D01*
G01X3357535Y391220D02*
X3356425D01*
G01X3354021Y390531D02*
X3402059D01*
G01X3356425Y390236D02*
X3357535D01*
G01X3356406Y389787D02*
X3357554D01*
G01X3357545Y389519D02*
X3356415D01*
G01X3357559Y388000D02*
X3356401D01*
G01X3356410Y387732D02*
X3357550D01*
G01X3360329Y387283D02*
X3361506D01*
G01X3356392D02*
X3357569D01*
G01Y386299D02*
X3356392D01*
G01X3361506D02*
X3360329D01*
G01X3361487Y385850D02*
X3360347D01*
G01X3360338Y385582D02*
X3361496D01*
G01X3360313Y397604D02*
X3360344Y399193D01*
G01X3360324D02*
X3360311Y398532D01*
G01X3356376Y397604D02*
X3356407Y399193D01*
G01X3356387D02*
X3356374Y398532D01*
G01X3361545Y397691D02*
X3361570Y399193D01*
G01X3361552D02*
X3361542Y398602D01*
G01X3357608Y397691D02*
X3357633Y399193D01*
G01X3357615D02*
X3357605Y398602D01*
G01X3357413Y401063D02*
Y400078D01*
G01X3356547D02*
Y401063D01*
G01X3360292Y398602D02*
X3360282Y399193D01*
G01X3360264D02*
X3360289Y397691D01*
G01X3361523Y398532D02*
X3361510Y399193D01*
G01X3361490D02*
X3361521Y397604D01*
G01X3354021Y399193D02*
Y400767D01*
G01X3356355Y398602D02*
X3356345Y399193D01*
G01X3356327D02*
X3356352Y397691D01*
G01X3357586Y398532D02*
X3357573Y399193D01*
G01X3357553D02*
X3357584Y397604D01*
G01X3357535Y401063D02*
X3356425D01*
G01X3402059Y400767D02*
X3354021D01*
G01X3357535Y400078D02*
X3356425D01*
G01X3357605Y398602D02*
X3356355D01*
G01X3361542D02*
X3360292D01*
G01X3360311Y398532D02*
X3361523D01*
G01X3356374D02*
X3357586D01*
G01X3357595Y398306D02*
X3356365D01*
G01X3361532D02*
X3360302D01*
G01X3360289Y397691D02*
X3361545D01*
G01X3356352D02*
X3357608D01*
G01X3357584Y397604D02*
X3356376D01*
G01X3361521D02*
X3360313D01*
G01X3357595Y397322D02*
X3356365D01*
G01X3361532D02*
X3360302D01*
G01X3365447Y392106D02*
X3365460Y392767D01*
G01X3365458Y393694D02*
X3365427Y392106D01*
G01X3364219D02*
X3364229Y392697D01*
G01X3364226Y393607D02*
X3364201Y392106D01*
G01X3364289Y389519D02*
X3364284Y387732D01*
G01X3364275Y388000D02*
X3364280Y389787D01*
G01X3365443Y387283D02*
Y386299D01*
G01X3365287Y391220D02*
Y390236D01*
G01X3364421Y391220D02*
Y390236D01*
G01X3364266Y386299D02*
Y387283D01*
G01X3365428Y389787D02*
X3365433Y388000D01*
G01X3365424Y387732D02*
X3365419Y389519D01*
G01X3365507Y392106D02*
X3365482Y393607D01*
G01X3365479Y392697D02*
X3365489Y392106D01*
G01X3364281D02*
X3364250Y393694D01*
G01X3364248Y392767D02*
X3364261Y392106D01*
G01X3364239Y393977D02*
X3365469D01*
G01X3364250Y393694D02*
X3365458D01*
G01X3365482Y393607D02*
X3364226D01*
G01X3364239Y392993D02*
X3365469D01*
G01X3365460Y392767D02*
X3364248D01*
G01X3364229Y392697D02*
X3365479D01*
G01X3365409Y391220D02*
X3364299D01*
G01Y390236D02*
X3365409D01*
G01X3364280Y389787D02*
X3365428D01*
G01X3365419Y389519D02*
X3364289D01*
G01X3365433Y388000D02*
X3364275D01*
G01X3364284Y387732D02*
X3365424D01*
G01X3364266Y387283D02*
X3365443D01*
G01Y386299D02*
X3364266D01*
G01X3364250Y397604D02*
X3364281Y399193D01*
G01X3364261D02*
X3364248Y398532D01*
G01X3365482Y397691D02*
X3365507Y399193D01*
G01X3365489D02*
X3365479Y398602D01*
G01X3365287Y401063D02*
Y400078D01*
G01X3364421D02*
Y401063D01*
G01X3364229Y398602D02*
X3364219Y399193D01*
G01X3364201D02*
X3364226Y397691D01*
G01X3365460Y398532D02*
X3365447Y399193D01*
G01X3365427D02*
X3365458Y397604D01*
G01X3365409Y401063D02*
X3364299D01*
G01X3365409Y400078D02*
X3364299D01*
G01X3365479Y398602D02*
X3364229D01*
G01X3364248Y398532D02*
X3365460D01*
G01X3365469Y398306D02*
X3364239D01*
G01X3364226Y397691D02*
X3365482D01*
G01X3365458Y397604D02*
X3364250D01*
G01X3365469Y397322D02*
X3364239D01*
G01X3360352Y407236D02*
X3360347Y405449D01*
G01X3360338Y405716D02*
X3360343Y407504D01*
G01X3357559Y403299D02*
X3357554Y401512D01*
G01X3357545Y401779D02*
X3357550Y403567D01*
G01X3361506Y404015D02*
Y405000D01*
G01X3361350Y408937D02*
Y407952D01*
G01X3360484D02*
Y408937D01*
G01X3360425Y408444D02*
Y408248D01*
G01X3360329Y405000D02*
Y404015D01*
G01X3358456Y408248D02*
Y408444D01*
G01X3357569Y405000D02*
Y404015D01*
G01X3356980Y408248D02*
Y408444D01*
G01X3356392Y404015D02*
Y405000D01*
G01X3361491Y407504D02*
X3361496Y405716D01*
G01X3361487Y405449D02*
X3361482Y407236D01*
G01X3350996Y415728D02*
Y410118D01*
G01X3350582Y408248D02*
Y408444D01*
G01X3356410Y403567D02*
X3356415Y401779D01*
G01X3356406Y401512D02*
X3356401Y403299D01*
G01X3361472Y408937D02*
X3360362D01*
G01X3369775Y408248D02*
X3360425D01*
G01X3361472Y407952D02*
X3360362D01*
G01X3360343Y407504D02*
X3361491D01*
G01X3361482Y407236D02*
X3360352D01*
G01X3361496Y405716D02*
X3360338D01*
G01X3360347Y405449D02*
X3361487D01*
G01X3357569Y405000D02*
X3356392D01*
G01X3361506D02*
X3360329D01*
G01X3357569Y404015D02*
X3356392D01*
G01X3361506D02*
X3360329D01*
G01X3357550Y403567D02*
X3356410D01*
G01X3356401Y403299D02*
X3357559D01*
G01X3356415Y401779D02*
X3357545D01*
G01X3357554Y401512D02*
X3356406D01*
G01X3366901Y415728D02*
X3350996D01*
G01X3365433Y403299D02*
X3365428Y401512D01*
G01X3365419Y401779D02*
X3365424Y403567D01*
G01X3365838Y408248D02*
Y408444D01*
G01X3365443Y405000D02*
Y404015D01*
G01X3364362Y408248D02*
Y408444D01*
G01X3364266Y404015D02*
Y405000D01*
G01X3364284Y403567D02*
X3364289Y401779D01*
G01X3364280Y401512D02*
X3364275Y403299D01*
G01X3365443Y405000D02*
X3364266D01*
G01X3365443Y404015D02*
X3364266D01*
G01X3365424Y403567D02*
X3364284D01*
G01X3364275Y403299D02*
X3365433D01*
G01X3364289Y401779D02*
X3365419D01*
G01X3365428Y401512D02*
X3364280D01*
G01X3361783Y463238D02*
Y455531D01*
G01X3360274D02*
Y465395D01*
G01X3357859Y457072D02*
Y455531D01*
G01X3361783D02*
X3360274D01*
G01X3362387Y463854D02*
X3361783Y463238D01*
G01Y464471D02*
X3362387Y465087D01*
G01X3357557Y464779D02*
X3356954Y463854D01*
G01X3355445Y464779D02*
X3356048Y466012D01*
G01X3357859D02*
X3357557Y464779D01*
G01X3361783Y465395D02*
Y464471D01*
G01X3357859Y466628D02*
Y466012D01*
G01X3357557Y467861D02*
X3357859Y466628D01*
G01X3356048D02*
X3355445Y467553D01*
G01X3363293Y464163D02*
X3362387Y463854D01*
G01Y465087D02*
X3363293Y465395D01*
G01X3356048Y466012D02*
Y466628D01*
G01X3363293Y465395D02*
X3364500D01*
G01X3360274D02*
X3361783D01*
G01X3363896Y464163D02*
X3363293D01*
G01X3366613Y462930D02*
Y455531D01*
G01X3365104D02*
Y462930D01*
G01X3366613Y455531D02*
X3365104D01*
G01X3366311Y464163D02*
X3367216Y465087D01*
G01X3366915Y463546D02*
X3366613Y462930D01*
G01X3365104D02*
X3364802Y463546D01*
G01X3365405Y465087D02*
X3366311Y464163D01*
G01X3364802Y463546D02*
X3364500Y463854D01*
G01D02*
X3363896Y464163D01*
G01X3364500Y465395D02*
X3365405Y465087D01*
G01X3356350Y469094D02*
X3357557Y467861D01*
G01X3355445Y467553D02*
X3354539Y468170D01*
G01X3355143Y469711D02*
X3356350Y469094D01*
G01X3354539Y468170D02*
X3353030Y468478D01*
G01X3353332Y470019D02*
X3355143Y469711D01*
G01X3352124Y470019D02*
X3353332D01*
G01X3353030Y468478D02*
X3351822D01*
G01D02*
X3350313Y468170D01*
G01X3379893Y186279D02*
Y198090D01*
G01X3381370Y186279D02*
X3379893D01*
G01X3381370Y191808D02*
Y186279D01*
G01X3379893Y198090D02*
X3381370D01*
G01D02*
Y193315D01*
G01D02*
X3388259D01*
G01Y191808D02*
X3381370D01*
G01X3377244Y385582D02*
X3377239Y383795D01*
G01X3377230Y384063D02*
X3377235Y385850D01*
G01X3369370Y385582D02*
X3369365Y383795D01*
G01X3369356Y384063D02*
X3369361Y385850D01*
G01X3379126Y382657D02*
Y382854D01*
G01X3377098Y383346D02*
Y382362D01*
G01X3376232Y383346D02*
Y382362D01*
G01X3372728Y382657D02*
Y382854D01*
G01X3371252Y382657D02*
Y382854D01*
G01X3369283D02*
Y382657D01*
G01X3369224Y383346D02*
Y382362D01*
G01X3368358Y383346D02*
Y382362D01*
G01X3376095Y385850D02*
X3376100Y384063D01*
G01X3376091Y383795D02*
X3376086Y385582D01*
G01X3368221Y385850D02*
X3368226Y384063D01*
G01X3368217Y383795D02*
X3368212Y385582D01*
G01X3376100Y384063D02*
X3377230D01*
G01X3368226D02*
X3369356D01*
G01X3369365Y383795D02*
X3368217D01*
G01X3377239D02*
X3376091D01*
G01X3369346Y383346D02*
X3368236D01*
G01X3377220D02*
X3376110D01*
G01X3380110Y382657D02*
X3371252D01*
G01X3376110Y382362D02*
X3376232D01*
G01X3376110D02*
X3377220D01*
G01X3368236D02*
X3369346D01*
G01X3377098D02*
X3377220D01*
G01X3383063Y382657D02*
Y382854D01*
G01X3382817Y382657D02*
Y382854D01*
G01X3382324Y382657D02*
Y382854D01*
G01X3382078Y382657D02*
Y382854D01*
G01X3380110D02*
Y382657D01*
G01X3382078D02*
X3391183D01*
G01X3377258Y392106D02*
X3377271Y392767D01*
G01X3377269Y393694D02*
X3377238Y392106D01*
G01X3373321D02*
X3373334Y392767D01*
G01X3373332Y393694D02*
X3373301Y392106D01*
G01X3369384D02*
X3369397Y392767D01*
G01X3369395Y393694D02*
X3369364Y392106D01*
G01X3379974Y393607D02*
X3379949Y392106D01*
G01X3376030D02*
X3376040Y392697D01*
G01X3376037Y393607D02*
X3376012Y392106D01*
G01X3372093D02*
X3372103Y392697D01*
G01X3372100Y393607D02*
X3372075Y392106D01*
G01X3368156D02*
X3368166Y392697D01*
G01X3368163Y393607D02*
X3368138Y392106D01*
G01X3372163Y389519D02*
X3372158Y387732D01*
G01X3372149Y388000D02*
X3372154Y389787D01*
G01X3377254Y386299D02*
Y387283D01*
G01X3376077D02*
Y386299D01*
G01X3373317Y387283D02*
Y386299D01*
G01X3373161Y391220D02*
Y390236D01*
G01X3372295Y391220D02*
Y390236D01*
G01X3372140Y386299D02*
Y387283D01*
G01X3369380Y386299D02*
Y387283D01*
G01X3368203D02*
Y386299D01*
G01X3373302Y389787D02*
X3373307Y388000D01*
G01X3373298Y387732D02*
X3373293Y389519D01*
G01X3377318Y392106D02*
X3377293Y393607D01*
G01X3377290Y392697D02*
X3377300Y392106D01*
G01X3373381D02*
X3373356Y393607D01*
G01X3373353Y392697D02*
X3373363Y392106D01*
G01X3369444D02*
X3369419Y393607D01*
G01X3369416Y392697D02*
X3369426Y392106D01*
G01X3376092D02*
X3376061Y393694D01*
G01X3376059Y392767D02*
X3376072Y392106D01*
G01X3372155D02*
X3372124Y393694D01*
G01X3372122Y392767D02*
X3372135Y392106D01*
G01X3368218D02*
X3368187Y393694D01*
G01X3368185Y392767D02*
X3368198Y392106D01*
G01X3376050Y393977D02*
X3377280D01*
G01X3372113D02*
X3373343D01*
G01X3368176D02*
X3369406D01*
G01X3376061Y393694D02*
X3377269D01*
G01X3372124D02*
X3373332D01*
G01X3368187D02*
X3369395D01*
G01X3373356Y393607D02*
X3372100D01*
G01X3369419D02*
X3368163D01*
G01X3377293D02*
X3376037D01*
G01X3376050Y392993D02*
X3377280D01*
G01X3372113D02*
X3373343D01*
G01X3368176D02*
X3369406D01*
G01X3373334Y392767D02*
X3372122D01*
G01X3369397D02*
X3368185D01*
G01X3377271D02*
X3376059D01*
G01X3376040Y392697D02*
X3377290D01*
G01X3372103D02*
X3373353D01*
G01X3368166D02*
X3369416D01*
G01X3373283Y391220D02*
X3373161D01*
G01X3373283D02*
X3372173D01*
G01X3372295D02*
X3372173D01*
G01Y390236D02*
X3373283D01*
G01X3372154Y389787D02*
X3373302D01*
G01X3373293Y389519D02*
X3372163D01*
G01X3373307Y388000D02*
X3372149D01*
G01X3372158Y387732D02*
X3373298D01*
G01X3376077Y387283D02*
X3377254D01*
G01X3368203D02*
X3369380D01*
G01X3372140D02*
X3373317D01*
G01X3369380Y386299D02*
X3368203D01*
G01X3373317D02*
X3372140D01*
G01X3377254D02*
X3376077D01*
G01X3369361Y385850D02*
X3368221D01*
G01X3377235D02*
X3376095D01*
G01X3376086Y385582D02*
X3377244D01*
G01X3368212D02*
X3369370D01*
G01X3376061Y397604D02*
X3376092Y399193D01*
G01X3376072D02*
X3376059Y398532D01*
G01X3372124Y397604D02*
X3372155Y399193D01*
G01X3372135D02*
X3372122Y398532D01*
G01X3368187Y397604D02*
X3368218Y399193D01*
G01X3368198D02*
X3368185Y398532D01*
G01X3377293Y397691D02*
X3377318Y399193D01*
G01X3377300D02*
X3377290Y398602D01*
G01X3373356Y397691D02*
X3373381Y399193D01*
G01X3373363D02*
X3373353Y398602D01*
G01X3369419Y397691D02*
X3369444Y399193D01*
G01X3369426D02*
X3369416Y398602D01*
G01X3373161Y401063D02*
Y400078D01*
G01X3372295D02*
Y401063D01*
G01X3379949Y399193D02*
X3379974Y397691D01*
G01X3376040Y398602D02*
X3376030Y399193D01*
G01X3376012D02*
X3376037Y397691D01*
G01X3372103Y398602D02*
X3372093Y399193D01*
G01X3372075D02*
X3372100Y397691D01*
G01X3368166Y398602D02*
X3368156Y399193D01*
G01X3368138D02*
X3368163Y397691D01*
G01X3377271Y398532D02*
X3377258Y399193D01*
G01X3377238D02*
X3377269Y397604D01*
G01X3373334Y398532D02*
X3373321Y399193D01*
G01X3373301D02*
X3373332Y397604D01*
G01X3369397Y398532D02*
X3369384Y399193D01*
G01X3369364D02*
X3369395Y397604D01*
G01X3373283Y401063D02*
X3372173D01*
G01X3373283Y400078D02*
X3372173D01*
G01X3373161D02*
X3373283D01*
G01X3369416Y398602D02*
X3368166D01*
G01X3373353D02*
X3372103D01*
G01X3377290D02*
X3376040D01*
G01X3376059Y398532D02*
X3377271D01*
G01X3368185D02*
X3369397D01*
G01X3372122D02*
X3373334D01*
G01X3369406Y398306D02*
X3368176D01*
G01X3373343D02*
X3372113D01*
G01X3377280D02*
X3376050D01*
G01X3376037Y397691D02*
X3377293D01*
G01X3368163D02*
X3369419D01*
G01X3372100D02*
X3373356D01*
G01X3369395Y397604D02*
X3368187D01*
G01X3373332D02*
X3372124D01*
G01X3377269D02*
X3376061D01*
G01X3369406Y397322D02*
X3368176D01*
G01X3373343D02*
X3372113D01*
G01X3377280D02*
X3376050D01*
G01X3381195Y392106D02*
X3381208Y392767D01*
G01X3381206Y393694D02*
X3381175Y392106D01*
G01X3379967D02*
X3379977Y392697D01*
G01X3380037Y389519D02*
X3380032Y387732D01*
G01X3380023Y388000D02*
X3380028Y389787D01*
G01X3381191Y387283D02*
Y386299D01*
G01X3381035Y391220D02*
Y390236D01*
G01X3380169Y391220D02*
Y390236D01*
G01X3380014Y386299D02*
Y387283D01*
G01X3381176Y389787D02*
X3381181Y388000D01*
G01X3381172Y387732D02*
X3381167Y389519D01*
G01X3381255Y392106D02*
X3381230Y393607D01*
G01X3381227Y392697D02*
X3381237Y392106D01*
G01X3380029D02*
X3379998Y393694D01*
G01X3379996Y392767D02*
X3380009Y392106D01*
G01X3379987Y393977D02*
X3381217D01*
G01X3379998Y393694D02*
X3381206D01*
G01X3381230Y393607D02*
X3379974D01*
G01X3379987Y392993D02*
X3381217D01*
G01X3381208Y392767D02*
X3379996D01*
G01X3379977Y392697D02*
X3381227D01*
G01X3381157Y391220D02*
X3381035D01*
G01X3381157D02*
X3380047D01*
G01X3380169D02*
X3380047D01*
G01Y390236D02*
X3381157D01*
G01X3380028Y389787D02*
X3381176D01*
G01X3381167Y389519D02*
X3380037D01*
G01X3381181Y388000D02*
X3380023D01*
G01X3380032Y387732D02*
X3381172D01*
G01X3380014Y387283D02*
X3381191D01*
G01Y386299D02*
X3380014D01*
G01X3379998Y397604D02*
X3380029Y399193D01*
G01X3380009D02*
X3379996Y398532D01*
G01X3381230Y397691D02*
X3381255Y399193D01*
G01X3381237D02*
X3381227Y398602D01*
G01X3381035Y401063D02*
Y400078D01*
G01X3380169D02*
Y401063D01*
G01X3379977Y398602D02*
X3379967Y399193D01*
G01X3381208Y398532D02*
X3381195Y399193D01*
G01X3381175D02*
X3381206Y397604D01*
G01X3381157Y401063D02*
X3380047D01*
G01Y400078D02*
X3380169D01*
G01X3381157D02*
X3380047D01*
G01X3381035D02*
X3381157D01*
G01X3381227Y398602D02*
X3379977D01*
G01X3379996Y398532D02*
X3381208D01*
G01X3381217Y398306D02*
X3379987D01*
G01X3379974Y397691D02*
X3381230D01*
G01X3381206Y397604D02*
X3379998D01*
G01X3381217Y397322D02*
X3379987D01*
G01X3376100Y407236D02*
X3376095Y405449D01*
G01X3376086Y405716D02*
X3376091Y407504D01*
G01X3373307Y403299D02*
X3373302Y401512D01*
G01X3373293Y401779D02*
X3373298Y403567D01*
G01X3368226Y407236D02*
X3368221Y405449D01*
G01X3368212Y405716D02*
X3368217Y407504D01*
G01X3379864Y408444D02*
Y408248D01*
G01X3379372Y408444D02*
Y408248D01*
G01X3378880D02*
Y408444D01*
G01X3378633D02*
Y408248D01*
G01X3377649Y408444D02*
Y408248D01*
G01X3377254Y404015D02*
Y405000D01*
G01X3377098Y408937D02*
Y407952D01*
G01X3376232D02*
Y408937D01*
G01X3376077Y405000D02*
Y404015D01*
G01X3375681Y408444D02*
Y408248D01*
G01X3374696Y408444D02*
Y408248D01*
G01X3374450D02*
Y408444D01*
G01X3373958D02*
Y408248D01*
G01X3373466Y408444D02*
Y408248D01*
G01X3373317Y404015D02*
Y405000D01*
G01X3373220Y408444D02*
Y408248D01*
G01X3372482D02*
Y408444D01*
G01X3372140Y405000D02*
Y404015D01*
G01X3371990Y408248D02*
Y408444D01*
G01X3371901Y415728D02*
Y410118D01*
G01X3371744Y408248D02*
Y408444D01*
G01X3369775Y408248D02*
Y408444D01*
G01X3369380Y404015D02*
Y405000D01*
G01X3369224Y408937D02*
Y407952D01*
G01X3368358D02*
Y408937D01*
G01X3368203Y405000D02*
Y404015D01*
G01X3366901Y415728D02*
Y410118D01*
G01X3377239Y407504D02*
X3377244Y405716D01*
G01X3377235Y405449D02*
X3377230Y407236D01*
G01X3372158Y403567D02*
X3372163Y401779D01*
G01X3372154Y401512D02*
X3372149Y403299D01*
G01X3369365Y407504D02*
X3369370Y405716D01*
G01X3369361Y405449D02*
X3369356Y407236D01*
G01X3377220Y408937D02*
X3377098D01*
G01X3369346D02*
X3368236D01*
G01X3377220D02*
X3376110D01*
G01X3376232D02*
X3376110D01*
G01X3381586Y408248D02*
X3371744D01*
G01X3369346Y407952D02*
X3368236D01*
G01X3377220D02*
X3376110D01*
G01X3376091Y407504D02*
X3377239D01*
G01X3368217D02*
X3369365D01*
G01X3369356Y407236D02*
X3368226D01*
G01X3377230D02*
X3376100D01*
G01X3369370Y405716D02*
X3368212D01*
G01X3377244D02*
X3376086D01*
G01X3376095Y405449D02*
X3377235D01*
G01X3368221D02*
X3369361D01*
G01X3369380Y405000D02*
X3368203D01*
G01X3373317D02*
X3372140D01*
G01X3377254D02*
X3376077D01*
G01X3369380Y404015D02*
X3368203D01*
G01X3373317D02*
X3372140D01*
G01X3377254D02*
X3376077D01*
G01X3373298Y403567D02*
X3372158D01*
G01X3372149Y403299D02*
X3373307D01*
G01X3372163Y401779D02*
X3373293D01*
G01X3373302Y401512D02*
X3372154D01*
G01X3387807Y415728D02*
X3371901D01*
G01X3381181Y403299D02*
X3381176Y401512D01*
G01X3381167Y401779D02*
X3381172Y403567D01*
G01X3381586Y408248D02*
Y408444D01*
G01X3381340Y408248D02*
Y408444D01*
G01X3381191Y405000D02*
Y404015D01*
G01X3380848Y408248D02*
Y408444D01*
G01X3380110D02*
Y408248D01*
G01X3380014Y404015D02*
Y405000D01*
G01X3380032Y403567D02*
X3380037Y401779D01*
G01X3380028Y401512D02*
X3380023Y403299D01*
G01X3381191Y405000D02*
X3380014D01*
G01X3381191Y404015D02*
X3380014D01*
G01X3381172Y403567D02*
X3380032D01*
G01X3380023Y403299D02*
X3381181D01*
G01X3380037Y401779D02*
X3381167D01*
G01X3381176Y401512D02*
X3380028D01*
G01X3378686Y455531D02*
Y462930D01*
G01X3375366Y463238D02*
Y455531D01*
G01X3373857D02*
Y465395D01*
G01X3371442Y462930D02*
Y455531D01*
G01X3369933D02*
Y462930D01*
G01X3371442Y455531D02*
X3369933D01*
G01X3375366D02*
X3373857D01*
G01X3380195D02*
X3378686D01*
G01X3379893Y464163D02*
X3380799Y465087D01*
G01X3375970Y463854D02*
X3375366Y463238D01*
G01Y464471D02*
X3375970Y465087D01*
G01X3367216Y463854D02*
X3366915Y463546D01*
G01X3375366Y465395D02*
Y464471D01*
G01X3370838D02*
X3371442Y462930D01*
G01X3378686D02*
X3378384Y463546D01*
G01X3369933Y462930D02*
X3369631Y463546D01*
G01X3378988Y465087D02*
X3379893Y464163D01*
G01X3378384Y463546D02*
X3378082Y463854D01*
G01X3376875Y464163D02*
X3375970Y463854D01*
G01Y465087D02*
X3376875Y465395D01*
G01X3367216Y465087D02*
X3368122Y465395D01*
G01X3367820Y464163D02*
X3367216Y463854D01*
G01X3370235Y465087D02*
X3370838Y464471D01*
G01X3369631Y463546D02*
X3369329Y463854D01*
G01X3378082D02*
X3377479Y464163D01*
G01X3369329Y463854D02*
X3368726Y464163D01*
G01X3378082Y465395D02*
X3378988Y465087D01*
G01X3369329Y465395D02*
X3370235Y465087D01*
G01X3373857Y465395D02*
X3375366D01*
G01X3376875D02*
X3378082D01*
G01X3368122D02*
X3369329D01*
G01X3368726Y464163D02*
X3367820D01*
G01X3377479D02*
X3376875D01*
G01X3380195Y462930D02*
Y455531D01*
G01X3380799Y463854D02*
X3380497Y463546D01*
G01D02*
X3380195Y462930D01*
G01X3383214Y463546D02*
X3382912Y463854D01*
G01X3380799Y465087D02*
X3381704Y465395D01*
G01X3381403Y464163D02*
X3380799Y463854D01*
G01X3382912D02*
X3382308Y464163D01*
G01X3382912Y465395D02*
X3383817Y465087D01*
G01X3381704Y465395D02*
X3382912D01*
G01X3382308Y464163D02*
X3381403D01*
G01X3409350Y-324996D02*
G03X3389665Y-305311I-19685J0D01*
G01X3389736Y198090D02*
Y186279D01*
G01X3388259D02*
Y191808D01*
G01X3389736Y186279D02*
X3388259D01*
G01X3399086D02*
Y196080D01*
G01X3400563Y186279D02*
X3399086D01*
G01X3395641Y191305D02*
Y190300D01*
G01Y194321D02*
Y193315D01*
G01X3391704Y190300D02*
Y191305D01*
G01Y193315D02*
Y194321D01*
G01X3388259Y193315D02*
Y198090D01*
G01D02*
X3389736D01*
G01X3391704Y194321D02*
X3395641D01*
G01Y193315D02*
X3391704D01*
G01Y191305D02*
X3395641D01*
G01Y190300D02*
X3391704D01*
G01X3399086Y196080D02*
X3397610Y194321D01*
G01Y196331D02*
X3399086Y198090D01*
G01X3397610Y194321D02*
Y196331D01*
G01X3399086Y198090D02*
X3400563D01*
G01X3392992Y385582D02*
X3392987Y383795D01*
G01X3392978Y384063D02*
X3392983Y385850D01*
G01X3385118Y385582D02*
X3385113Y383795D01*
G01X3385104Y384063D02*
X3385109Y385850D01*
G01X3392846Y383346D02*
Y382362D01*
G01X3391980Y383346D02*
Y382362D01*
G01X3391183Y382657D02*
Y382854D01*
G01X3390691Y382657D02*
Y382854D01*
G01X3390445Y382657D02*
Y382854D01*
G01X3390198Y382657D02*
Y382854D01*
G01X3389706Y382657D02*
Y382854D01*
G01X3389460Y382657D02*
Y382854D01*
G01X3389214Y382657D02*
Y382854D01*
G01X3388968D02*
Y382657D01*
G01X3388722D02*
Y382854D01*
G01X3388476Y382657D02*
Y382854D01*
G01X3388230Y382657D02*
Y382854D01*
G01X3387492Y382657D02*
Y382854D01*
G01X3387246Y382657D02*
Y382854D01*
G01X3386015Y382657D02*
Y382854D01*
G01X3385523Y382657D02*
Y382854D01*
G01X3385277Y382657D02*
Y382854D01*
G01X3385031Y382657D02*
Y382854D01*
G01X3384972Y383346D02*
Y382362D01*
G01X3384539Y382657D02*
Y382854D01*
G01X3384293Y382657D02*
Y382854D01*
G01X3384106Y383346D02*
Y382362D01*
G01X3384047Y382657D02*
Y382854D01*
G01X3383801Y382657D02*
Y382854D01*
G01X3383555Y382657D02*
Y382854D01*
G01X3391843Y385850D02*
X3391848Y384063D01*
G01X3391839Y383795D02*
X3391834Y385582D01*
G01X3383969Y385850D02*
X3383974Y384063D01*
G01X3383965Y383795D02*
X3383960Y385582D01*
G01X3391848Y384063D02*
X3392978D01*
G01X3383974D02*
X3385104D01*
G01X3385113Y383795D02*
X3383965D01*
G01X3392987D02*
X3391839D01*
G01X3385095Y383346D02*
X3383984D01*
G01X3392969D02*
X3391858D01*
G01Y382362D02*
X3391980D01*
G01X3383984D02*
X3384106D01*
G01X3391858D02*
X3392969D01*
G01X3383984D02*
X3385095D01*
G01X3384972D02*
X3385095D01*
G01X3392846D02*
X3392969D01*
G01X3397482Y390728D02*
G03I-1132J0D01*
G01X3393006Y392106D02*
X3393019Y392767D01*
G01X3393017Y393694D02*
X3392986Y392106D01*
G01X3389069D02*
X3389082Y392767D01*
G01X3389080Y393694D02*
X3389049Y392106D01*
G01X3385132D02*
X3385145Y392767D01*
G01X3385143Y393694D02*
X3385112Y392106D01*
G01X3395715D02*
X3395725Y392697D01*
G01X3395722Y393607D02*
X3395697Y392106D01*
G01X3391778D02*
X3391788Y392697D01*
G01X3391785Y393607D02*
X3391760Y392106D01*
G01X3387841D02*
X3387851Y392697D01*
G01X3387848Y393607D02*
X3387823Y392106D01*
G01X3383904D02*
X3383914Y392697D01*
G01X3383911Y393607D02*
X3383886Y392106D01*
G01X3395785Y389519D02*
X3395780Y387732D01*
G01X3395771Y388000D02*
X3395776Y389787D01*
G01X3387911Y389519D02*
X3387906Y387732D01*
G01X3387897Y388000D02*
X3387902Y389787D01*
G01X3395917Y391220D02*
Y390236D01*
G01X3395762Y386299D02*
Y387283D01*
G01X3393002Y386299D02*
Y387283D01*
G01X3391825D02*
Y386299D01*
G01X3389065Y387283D02*
Y386299D01*
G01X3388909Y391220D02*
Y390236D01*
G01X3388043Y391220D02*
Y390236D01*
G01X3387888Y386299D02*
Y387283D01*
G01X3385128Y386299D02*
Y387283D01*
G01X3383951D02*
Y386299D01*
G01X3389050Y389787D02*
X3389055Y388000D01*
G01X3389046Y387732D02*
X3389041Y389519D01*
G01X3393066Y392106D02*
X3393041Y393607D01*
G01X3393038Y392697D02*
X3393048Y392106D01*
G01X3389129D02*
X3389104Y393607D01*
G01X3389101Y392697D02*
X3389111Y392106D01*
G01X3385192D02*
X3385167Y393607D01*
G01X3385164Y392697D02*
X3385174Y392106D01*
G01X3395777D02*
X3395746Y393694D01*
G01X3395744Y392767D02*
X3395757Y392106D01*
G01X3391840D02*
X3391809Y393694D01*
G01X3391807Y392767D02*
X3391820Y392106D01*
G01X3387903D02*
X3387872Y393694D01*
G01X3387870Y392767D02*
X3387883Y392106D01*
G01X3383966D02*
X3383935Y393694D01*
G01X3383933Y392767D02*
X3383946Y392106D01*
G01X3395735Y393977D02*
X3396965D01*
G01X3391798D02*
X3393028D01*
G01X3387861D02*
X3389091D01*
G01X3383924D02*
X3385154D01*
G01X3395746Y393694D02*
X3396954D01*
G01X3391809D02*
X3393017D01*
G01X3387872D02*
X3389080D01*
G01X3383935D02*
X3385143D01*
G01X3385167Y393607D02*
X3383911D01*
G01X3389104D02*
X3387848D01*
G01X3393041D02*
X3391785D01*
G01X3396978D02*
X3395722D01*
G01X3395735Y392993D02*
X3396965D01*
G01X3391798D02*
X3393028D01*
G01X3387861D02*
X3389091D01*
G01X3383924D02*
X3385154D01*
G01X3385145Y392767D02*
X3383933D01*
G01X3389082D02*
X3387870D01*
G01X3393019D02*
X3391807D01*
G01X3396956D02*
X3395744D01*
G01X3395725Y392697D02*
X3396975D01*
G01X3391788D02*
X3393038D01*
G01X3387851D02*
X3389101D01*
G01X3383914D02*
X3385164D01*
G01X3389032Y391220D02*
X3388909D01*
G01X3389032D02*
X3387921D01*
G01X3396906D02*
X3395795D01*
G01X3388043D02*
X3387921D01*
G01X3395917D02*
X3395795D01*
G01Y390236D02*
X3396906D01*
G01X3387921D02*
X3389032D01*
G01X3395776Y389787D02*
X3396924D01*
G01X3387902D02*
X3389050D01*
G01X3389041Y389519D02*
X3387911D01*
G01X3396915D02*
X3395785D01*
G01X3389055Y388000D02*
X3387897D01*
G01X3396929D02*
X3395771D01*
G01X3395780Y387732D02*
X3396920D01*
G01X3387906D02*
X3389046D01*
G01X3395762Y387283D02*
X3396939D01*
G01X3391825D02*
X3393002D01*
G01X3387888D02*
X3389065D01*
G01X3383951D02*
X3385128D01*
G01Y386299D02*
X3383951D01*
G01X3389065D02*
X3387888D01*
G01X3393002D02*
X3391825D01*
G01X3396939D02*
X3395762D01*
G01X3385109Y385850D02*
X3383969D01*
G01X3392983D02*
X3391843D01*
G01X3391834Y385582D02*
X3392992D01*
G01X3383960D02*
X3385118D01*
G01X3395746Y397604D02*
X3395777Y399193D01*
G01X3395757D02*
X3395744Y398532D01*
G01X3391809Y397604D02*
X3391840Y399193D01*
G01X3391820D02*
X3391807Y398532D01*
G01X3387872Y397604D02*
X3387903Y399193D01*
G01X3387883D02*
X3387870Y398532D01*
G01X3383935Y397604D02*
X3383966Y399193D01*
G01X3383946D02*
X3383933Y398532D01*
G01X3393041Y397691D02*
X3393066Y399193D01*
G01X3393048D02*
X3393038Y398602D01*
G01X3389104Y397691D02*
X3389129Y399193D01*
G01X3389111D02*
X3389101Y398602D01*
G01X3385167Y397691D02*
X3385192Y399193D01*
G01X3385174D02*
X3385164Y398602D01*
G01X3395917Y400078D02*
Y401063D01*
G01X3388909D02*
Y400078D01*
G01X3388043D02*
Y401063D01*
G01X3395725Y398602D02*
X3395715Y399193D01*
G01X3395697D02*
X3395722Y397691D01*
G01X3391788Y398602D02*
X3391778Y399193D01*
G01X3391760D02*
X3391785Y397691D01*
G01X3387851Y398602D02*
X3387841Y399193D01*
G01X3387823D02*
X3387848Y397691D01*
G01X3383914Y398602D02*
X3383904Y399193D01*
G01X3383886D02*
X3383911Y397691D01*
G01X3393019Y398532D02*
X3393006Y399193D01*
G01X3392986D02*
X3393017Y397604D01*
G01X3389082Y398532D02*
X3389069Y399193D01*
G01X3389049D02*
X3389080Y397604D01*
G01X3385145Y398532D02*
X3385132Y399193D01*
G01X3385112D02*
X3385143Y397604D01*
G01X3389032Y401063D02*
X3387921D01*
G01X3396906D02*
X3395795D01*
G01Y400078D02*
X3395917D01*
G01X3387921D02*
X3388043D01*
G01X3389032D02*
X3387921D01*
G01X3396906D02*
X3395795D01*
G01X3388909D02*
X3389032D01*
G01X3385164Y398602D02*
X3383914D01*
G01X3389101D02*
X3387851D01*
G01X3393038D02*
X3391788D01*
G01X3396975D02*
X3395725D01*
G01X3395744Y398532D02*
X3396956D01*
G01X3391807D02*
X3393019D01*
G01X3387870D02*
X3389082D01*
G01X3383933D02*
X3385145D01*
G01X3385154Y398306D02*
X3383924D01*
G01X3389091D02*
X3387861D01*
G01X3393028D02*
X3391798D01*
G01X3396965D02*
X3395735D01*
G01X3395722Y397691D02*
X3396978D01*
G01X3391785D02*
X3393041D01*
G01X3387848D02*
X3389104D01*
G01X3383911D02*
X3385167D01*
G01X3385143Y397604D02*
X3383935D01*
G01X3389080D02*
X3387872D01*
G01X3393017D02*
X3391809D01*
G01X3396954D02*
X3395746D01*
G01X3385154Y397322D02*
X3383924D01*
G01X3389091D02*
X3387861D01*
G01X3393028D02*
X3391798D01*
G01X3396965D02*
X3395735D01*
G01X3398220Y390065D02*
X3397984Y389783D01*
G01Y390105D02*
X3398220Y390386D01*
G01X3400110Y391673D02*
X3399480Y389783D01*
G01X3399677Y391030D02*
X3399323Y389944D01*
G01X3396943Y392106D02*
X3396956Y392767D01*
G01X3396954Y393694D02*
X3396923Y392106D01*
G01X3398220Y390386D02*
Y390065D01*
G01X3397984Y391673D02*
Y390105D01*
G01X3397748Y389783D02*
Y391673D01*
G01X3396939Y387283D02*
Y386299D01*
G01X3396783Y391220D02*
Y390236D01*
G01X3396924Y389787D02*
X3396929Y388000D01*
G01X3396920Y387732D02*
X3396915Y389519D01*
G01X3397003Y392106D02*
X3396978Y393607D01*
G01X3396975Y392697D02*
X3396985Y392106D01*
G01X3398772Y391673D02*
X3398929Y391191D01*
G01X3399323Y389944D02*
X3398969Y391030D01*
G01X3399165Y389783D02*
X3398535Y391673D01*
G01X3397748D02*
X3397984D01*
G01X3398535D02*
X3398772D01*
G01X3396906Y391220D02*
X3396783D01*
G01X3398929Y391191D02*
X3399717D01*
G01X3398969Y391030D02*
X3399677D01*
G01X3397984Y389783D02*
X3397748D01*
G01X3399480D02*
X3399165D01*
G01X3396978Y397691D02*
X3397003Y399193D01*
G01X3396985D02*
X3396975Y398602D01*
G01X3396783Y401063D02*
Y400078D01*
G01X3396956Y398532D02*
X3396943Y399193D01*
G01X3396923D02*
X3396954Y397604D01*
G01X3396783Y400078D02*
X3396906D01*
G01X3391848Y407236D02*
X3391843Y405449D01*
G01X3391834Y405716D02*
X3391839Y407504D01*
G01X3389055Y403299D02*
X3389050Y401512D01*
G01X3389041Y401779D02*
X3389046Y403567D01*
G01X3383974Y407236D02*
X3383969Y405449D01*
G01X3383960Y405716D02*
X3383965Y407504D01*
G01X3395762Y404015D02*
Y405000D01*
G01X3393002Y404015D02*
Y405000D01*
G01X3392846Y408937D02*
Y407952D01*
G01X3392807Y415728D02*
Y410118D01*
G01X3392413Y408444D02*
Y408248D01*
G01X3391980Y407952D02*
Y408937D01*
G01X3391825Y405000D02*
Y404015D01*
G01X3390937Y408248D02*
Y408444D01*
G01X3389065Y405000D02*
Y404015D01*
G01X3387888D02*
Y405000D01*
G01X3387807Y415728D02*
Y410118D01*
G01X3385128Y404015D02*
Y405000D01*
G01X3384972Y408937D02*
Y407952D01*
G01X3384106D02*
Y408937D01*
G01X3383951Y405000D02*
Y404015D01*
G01X3383555Y408248D02*
Y408444D01*
G01X3395780Y403567D02*
X3395785Y401779D01*
G01X3395776Y401512D02*
X3395771Y403299D01*
G01X3392987Y407504D02*
X3392992Y405716D01*
G01X3392983Y405449D02*
X3392978Y407236D01*
G01X3387906Y403567D02*
X3387911Y401779D01*
G01X3387902Y401512D02*
X3387897Y403299D01*
G01X3385113Y407504D02*
X3385118Y405716D01*
G01X3385109Y405449D02*
X3385104Y407236D01*
G01X3392969Y408937D02*
X3392846D01*
G01X3385095D02*
X3384972D01*
G01X3385095D02*
X3383984D01*
G01X3392969D02*
X3391858D01*
G01X3384106D02*
X3383984D01*
G01X3391980D02*
X3391858D01*
G01X3383555Y408248D02*
X3392413D01*
G01X3385095Y407952D02*
X3383984D01*
G01X3392969D02*
X3391858D01*
G01X3391839Y407504D02*
X3392987D01*
G01X3383965D02*
X3385113D01*
G01X3385104Y407236D02*
X3383974D01*
G01X3392978D02*
X3391848D01*
G01X3385118Y405716D02*
X3383960D01*
G01X3392992D02*
X3391834D01*
G01X3391843Y405449D02*
X3392983D01*
G01X3383969D02*
X3385109D01*
G01X3385128Y405000D02*
X3383951D01*
G01X3389065D02*
X3387888D01*
G01X3393002D02*
X3391825D01*
G01X3396939D02*
X3395762D01*
G01X3385128Y404015D02*
X3383951D01*
G01X3389065D02*
X3387888D01*
G01X3393002D02*
X3391825D01*
G01X3396939D02*
X3395762D01*
G01X3389046Y403567D02*
X3387906D01*
G01X3396920D02*
X3395780D01*
G01X3395771Y403299D02*
X3396929D01*
G01X3387897D02*
X3389055D01*
G01X3395785Y401779D02*
X3396915D01*
G01X3387911D02*
X3389041D01*
G01X3389050Y401512D02*
X3387902D01*
G01X3396924D02*
X3395776D01*
G01X3408161Y415728D02*
X3392807D01*
G01X3396929Y403299D02*
X3396924Y401512D01*
G01X3396915Y401779D02*
X3396920Y403567D01*
G01X3396939Y405000D02*
Y404015D01*
G01X3385025Y462930D02*
Y455531D01*
G01X3383515D02*
Y462930D01*
G01X3385025Y455531D02*
X3383515D01*
G01X3384421Y464471D02*
X3385025Y462930D01*
G01X3383515D02*
X3383214Y463546D01*
G01X3383817Y465087D02*
X3384421Y464471D01*
G01X3421551Y-870846D02*
X3422561Y-870196D01*
X3423139Y-869330D01*
X3423283Y-868356D01*
X3423139Y-867490D01*
X3422417Y-866623D01*
X3421551Y-866082D01*
X3420685Y-865974D01*
X3419674Y-866190D01*
X3418953Y-866948D01*
X3418664Y-867706D01*
Y-868681D01*
G01Y-867706D02*
X3418231Y-867057D01*
X3417509Y-866515D01*
X3416643Y-866299D01*
X3415777Y-866515D01*
X3415055Y-867057D01*
X3414622Y-868031D01*
X3414766Y-869005D01*
X3415344Y-869980D01*
G01X3423572Y-859803D02*
X3423427Y-860020D01*
X3423139D01*
X3422994Y-859803D01*
X3423139Y-859586D01*
X3423427D01*
X3423572Y-859803D01*
G01X3416065Y-853199D02*
X3415200Y-852549D01*
X3414766Y-851792D01*
X3414622Y-850925D01*
X3414911Y-849843D01*
X3415632Y-849085D01*
X3416498Y-848868D01*
X3417365Y-848977D01*
X3418086Y-849410D01*
X3419530Y-851575D01*
X3420540Y-852549D01*
X3421984Y-853199D01*
X3423283Y-853416D01*
Y-848868D01*
G01X3414622Y-842481D02*
X3414911Y-843347D01*
X3415632Y-843997D01*
X3416498Y-844430D01*
X3417653Y-844755D01*
X3418953Y-844863D01*
X3420252Y-844755D01*
X3421407Y-844430D01*
X3422273Y-843997D01*
X3422994Y-843347D01*
X3423283Y-842481D01*
X3422994Y-841615D01*
X3422273Y-840965D01*
X3421407Y-840532D01*
X3420252Y-840207D01*
X3418953Y-840099D01*
X3417653Y-840207D01*
X3416498Y-840532D01*
X3415632Y-840965D01*
X3414911Y-841615D01*
X3414622Y-842481D01*
G01X3409350Y-517909D02*
G03X3413287Y-521846I3937J0D01*
G01D02*
X3472342D01*
G01X3409350Y-324996D02*
Y-517909D01*
G01X3412128Y186530D02*
X3413358Y187284D01*
G01X3403761Y187536D02*
Y186279D01*
G01X3402531D02*
Y187536D01*
G01X3400563Y198090D02*
Y186279D01*
G01X3406222Y188290D02*
X3406960Y187284D01*
G01D02*
X3408191Y186530D01*
G01X3409421Y187536D02*
X3408437Y187787D01*
G01X3408191Y186530D02*
X3409421Y186279D01*
G01X3402531Y187536D02*
X3403761D01*
G01X3410897D02*
X3409421D01*
G01Y186279D02*
X3410897D01*
G01X3403761D02*
X3402531D01*
G01X3410897D02*
X3412128Y186530D01*
G01X3411882Y187787D02*
X3410897Y187536D01*
G01X3413358Y187284D02*
X3414096Y188290D01*
G01X3408191Y193567D02*
X3406960Y192813D01*
G01X3412620Y188290D02*
X3411882Y187787D01*
G01X3407452Y191556D02*
X3408437Y192310D01*
G01X3413112Y189043D02*
X3412620Y188290D01*
G01X3406960Y192813D02*
Y196834D01*
G01X3405730Y198090D02*
Y191556D01*
G01X3407698Y188290D02*
X3407206Y189295D01*
G01X3405730D02*
X3406222Y188290D01*
G01X3412620Y191808D02*
X3413112Y191054D01*
G01X3411882Y192310D02*
X3412620Y191808D01*
G01X3408437Y187787D02*
X3407698Y188290D01*
G01X3413358Y192813D02*
X3412128Y193567D01*
G01X3410897Y192562D02*
X3411882Y192310D01*
G01X3412128Y193567D02*
X3410897Y193818D01*
G01X3414096Y198090D02*
X3405730D01*
G01X3406960Y196834D02*
X3414096D01*
G01X3410897Y193818D02*
X3409421D01*
G01Y192562D02*
X3410897D01*
G01X3405730Y191556D02*
X3407452D01*
G01X3407206Y189295D02*
X3405730D01*
G01X3409421Y193818D02*
X3408191Y193567D01*
G01X3408437Y192310D02*
X3409421Y192562D01*
G01X3414096Y188290D02*
X3414588Y189546D01*
G01X3413358Y189797D02*
X3413112Y189043D01*
G01X3414588Y189546D02*
Y190551D01*
G01X3414096Y196834D02*
Y198090D01*
G01X3413358Y190300D02*
Y189797D01*
G01X3413112Y191054D02*
X3413358Y190300D01*
G01X3414588Y190551D02*
X3414096Y191808D01*
G01D02*
X3413358Y192813D01*
G01X3409145Y320846D02*
Y1080689D01*
G01X3454421Y320846D02*
X3409145D01*
G01X3408161Y415728D02*
Y381181D01*
G01X3404618Y384330D02*
Y388661D01*
G01X3400287Y385118D02*
Y381181D01*
G01X3399815Y388661D02*
Y384330D01*
G01X3404618D02*
X3399815D01*
G01X3400484Y392106D02*
X3402059Y390531D01*
G01X3399717Y391191D02*
X3399874Y391673D01*
G01X3402059Y390531D02*
Y400767D01*
G01X3400681Y388661D02*
Y386299D01*
G01X3400484Y399193D02*
Y392106D01*
G01X3399874Y391673D02*
X3400110D01*
G01X3399815Y388661D02*
X3404618D01*
G01X3400681Y386299D02*
X3404618D01*
G01X3408161Y385118D02*
X3400287D01*
G01X3400484Y399193D02*
X3402059Y400767D01*
G01X3404618Y406968D02*
Y402637D01*
G01X3400681D02*
Y405000D01*
G01X3400287Y410137D02*
Y406181D01*
G01X3399815Y406968D02*
Y402637D01*
G01X3408161Y410137D02*
X3400287D01*
G01X3404618Y406968D02*
X3399815D01*
G01X3400287Y406181D02*
X3408161D01*
G01X3404618Y405000D02*
X3400681D01*
G01X3404618Y402637D02*
X3399815D01*
G01X3403289Y506082D02*
Y514743D01*
X3401990Y513011D01*
G01Y506082D02*
X3404588D01*
G01X3411950Y514743D02*
X3411084Y514454D01*
X3410434Y513733D01*
X3410001Y512867D01*
X3409676Y511712D01*
X3409568Y510412D01*
X3409676Y509113D01*
X3410001Y507958D01*
X3410434Y507092D01*
X3411084Y506371D01*
X3411950Y506082D01*
X3412816Y506371D01*
X3413466Y507092D01*
X3413899Y507958D01*
X3414224Y509113D01*
X3414332Y510412D01*
X3414224Y511712D01*
X3413899Y512867D01*
X3413466Y513733D01*
X3412816Y514454D01*
X3411950Y514743D01*
G01X3421910Y506082D02*
Y514743D01*
X3417904Y508536D01*
X3423318D01*
G01X3429272Y505793D02*
X3429055Y505938D01*
Y506226D01*
X3429272Y506371D01*
X3429489Y506226D01*
Y505938D01*
X3429272Y505793D01*
G01X3435551Y507381D02*
X3436201Y506659D01*
X3436959Y506226D01*
X3437933Y506082D01*
X3438907Y506371D01*
X3439665Y506948D01*
X3440207Y507958D01*
X3440315Y509113D01*
X3440098Y510268D01*
X3439557Y510990D01*
X3438799Y511567D01*
X3438041Y511712D01*
X3437283Y511567D01*
X3436309Y510990D01*
X3436634Y514743D01*
X3439557D01*
G01X3446594D02*
X3445728Y514454D01*
X3445078Y513733D01*
X3444645Y512867D01*
X3444320Y511712D01*
X3444212Y510412D01*
X3444320Y509113D01*
X3444645Y507958D01*
X3445078Y507092D01*
X3445728Y506371D01*
X3446594Y506082D01*
X3447460Y506371D01*
X3448110Y507092D01*
X3448543Y507958D01*
X3448868Y509113D01*
X3448976Y510412D01*
X3448868Y511712D01*
X3448543Y512867D01*
X3448110Y513733D01*
X3447460Y514454D01*
X3446594Y514743D01*
G01X3409961Y1038676D02*
X3402644Y1043310D01*
X3404092Y1045596D01*
X3404922Y1046096D01*
X3405699Y1046245D01*
X3406791Y1045810D01*
X3407650Y1045009D01*
X3407913Y1044074D01*
X3407873Y1043202D01*
X3406425Y1040915D01*
G01X3407873Y1043202D02*
X3412278Y1042334D01*
G01X3437197Y1077634D02*
X3410864Y1036054D01*
G01X3412224Y1044676D02*
X3413181Y1044838D01*
X3413953Y1045247D01*
X3414596Y1045993D01*
X3414873Y1046971D01*
X3414791Y1047920D01*
X3414227Y1048918D01*
X3413309Y1049627D01*
X3412218Y1050062D01*
X3411318Y1049991D01*
X3410425Y1049659D01*
X3409898Y1049097D01*
X3409614Y1048379D01*
X3409581Y1047247D01*
X3406584Y1049529D01*
X3408148Y1051999D01*
G01X3419474Y1053155D02*
X3419236Y1053050D01*
X3418992Y1053204D01*
X3418986Y1053464D01*
X3419224Y1053570D01*
X3419468Y1053416D01*
X3419474Y1053155D01*
G01X3416547Y1065261D02*
X3416327Y1064375D01*
X3416590Y1063440D01*
X3417089Y1062611D01*
X3417891Y1061718D01*
X3418931Y1060932D01*
X3420086Y1060328D01*
X3421236Y1059984D01*
X3422199Y1059887D01*
X3423156Y1060050D01*
X3423864Y1060627D01*
X3424083Y1061513D01*
X3423821Y1062448D01*
X3423321Y1063277D01*
X3422519Y1064170D01*
X3421480Y1064956D01*
X3420324Y1065560D01*
X3419175Y1065904D01*
X3418211Y1066001D01*
X3417254Y1065838D01*
X3416547Y1065261D01*
G01X3421181Y1072578D02*
X3420961Y1071692D01*
X3421224Y1070757D01*
X3421723Y1069928D01*
X3422525Y1069035D01*
X3423565Y1068249D01*
X3424720Y1067645D01*
X3425870Y1067301D01*
X3426833Y1067204D01*
X3427790Y1067367D01*
X3428498Y1067944D01*
X3428717Y1068830D01*
X3428455Y1069765D01*
X3427955Y1070594D01*
X3427153Y1071487D01*
X3426114Y1072273D01*
X3424958Y1072877D01*
X3423809Y1073221D01*
X3422845Y1073318D01*
X3421888Y1073155D01*
X3421181Y1072578D01*
G01X3431425Y-914248D02*
Y-905587D01*
X3427419Y-911794D01*
X3432833D01*
G01X3437380Y-911361D02*
X3440194D01*
G01X3444958Y-914248D02*
Y-905587D01*
X3449938Y-914248D01*
Y-905587D01*
G01X3453944Y-914248D02*
Y-905587D01*
X3456542D01*
X3457408Y-906020D01*
X3458058Y-907030D01*
X3458274Y-908185D01*
X3458058Y-909340D01*
X3457516Y-910206D01*
X3456542Y-910639D01*
X3453944D01*
G01X3464770Y-905587D02*
Y-914248D01*
G01X3462280Y-905587D02*
X3467260D01*
G01X3471157Y-914248D02*
Y-905587D01*
G01X3475705D02*
Y-914248D01*
G01Y-909918D02*
X3471157D01*
G01X3425448Y-908066D02*
Y-882082D01*
G01Y-888381D02*
Y-908066D01*
G01X3488681Y-888381D02*
X3421511D01*
G01X3425448Y-840531D02*
Y-882082D01*
G01X3488681Y-875783D02*
X3421511D01*
G01X3425448D02*
Y-840531D01*
G01X3428860Y192562D02*
Y186279D01*
G01X3427630D02*
Y194321D01*
G01X3425661Y192310D02*
Y186279D01*
G01X3424431D02*
Y192310D01*
G01X3421724D02*
Y186279D01*
G01X3420494D02*
Y192310D01*
G01X3417787Y192562D02*
Y186279D01*
G01X3416557D02*
Y194321D01*
G01X3417787Y186279D02*
X3416557D01*
G01X3421724D02*
X3420494D01*
G01X3428860D02*
X3427630D01*
G01X3425661D02*
X3424431D01*
G01X3431567D02*
Y192310D01*
G01X3432797Y186279D02*
X3431567D01*
G01X3422708Y193315D02*
X3422216Y193064D01*
G01Y194069D02*
X3422954Y194321D01*
G01X3419017Y193315D02*
X3418279Y193064D01*
G01Y194069D02*
X3419017Y194321D01*
G01X3429352Y193064D02*
X3428860Y192562D01*
G01Y193567D02*
X3429352Y194069D01*
G01X3422216Y193064D02*
X3421970Y192813D01*
G01X3421478Y193315D02*
X3422216Y194069D01*
G01X3418279Y193064D02*
X3417787Y192562D01*
G01Y193567D02*
X3418279Y194069D01*
G01X3421970Y192813D02*
X3421724Y192310D01*
G01X3428860Y194321D02*
Y193567D01*
G01X3417787Y194321D02*
Y193567D01*
G01X3425169D02*
X3425661Y192310D01*
G01X3424431D02*
X3424185Y192813D01*
G01X3420494Y192310D02*
X3420248Y192813D01*
G01X3424677Y194069D02*
X3425169Y193567D01*
G01X3424185Y192813D02*
X3423939Y193064D01*
G01X3420740Y194069D02*
X3421478Y193315D01*
G01X3420248Y192813D02*
X3420002Y193064D01*
G01X3423939D02*
X3423446Y193315D01*
G01X3420002Y193064D02*
X3419509Y193315D01*
G01X3423939Y194321D02*
X3424677Y194069D01*
G01X3420002Y194321D02*
X3420740Y194069D01*
G01X3427630Y194321D02*
X3428860D01*
G01X3422954D02*
X3423939D01*
G01X3416557D02*
X3417787D01*
G01X3419017D02*
X3420002D01*
G01X3419509Y193315D02*
X3419017D01*
G01X3423446D02*
X3422708D01*
G01X3430090D02*
X3429352Y193064D01*
G01Y194069D02*
X3430090Y194321D01*
G01X3431567Y192310D02*
X3431320Y192813D01*
G01X3431813Y194069D02*
X3432551Y193315D01*
G01X3431320Y192813D02*
X3431074Y193064D01*
G01D02*
X3430582Y193315D01*
G01X3431074Y194321D02*
X3431813Y194069D01*
G01X3430090Y194321D02*
X3431074D01*
G01X3430582Y193315D02*
X3430090D01*
G01X3427523Y342368D02*
X3428281Y343378D01*
X3428930Y343956D01*
X3429797Y344244D01*
X3430554Y343956D01*
X3431096Y343378D01*
X3431529Y342512D01*
X3431637Y341502D01*
X3431529Y340635D01*
X3431096Y339769D01*
X3430446Y339048D01*
X3429688Y338759D01*
X3428822Y339048D01*
X3428064Y339914D01*
X3427631Y341213D01*
X3427523Y342656D01*
X3427739Y344533D01*
X3428064Y345544D01*
X3428606Y346554D01*
X3429363Y347276D01*
X3430121Y347420D01*
X3430879Y347131D01*
X3431421Y346410D01*
G01X3436184Y345977D02*
X3436834Y346842D01*
X3437591Y347276D01*
X3438458Y347420D01*
X3439540Y347131D01*
X3440298Y346410D01*
X3440515Y345544D01*
X3440406Y344677D01*
X3439973Y343956D01*
X3437808Y342512D01*
X3436834Y341502D01*
X3436184Y340058D01*
X3435967Y338759D01*
X3440515D01*
G01X3446902Y338470D02*
X3446685Y338615D01*
Y338903D01*
X3446902Y339048D01*
X3447119Y338903D01*
Y338615D01*
X3446902Y338470D01*
G01X3455563Y347420D02*
X3454697Y347131D01*
X3454047Y346410D01*
X3453614Y345544D01*
X3453289Y344389D01*
X3453181Y343089D01*
X3453289Y341790D01*
X3453614Y340635D01*
X3454047Y339769D01*
X3454697Y339048D01*
X3455563Y338759D01*
X3456429Y339048D01*
X3457079Y339769D01*
X3457512Y340635D01*
X3457837Y341790D01*
X3457945Y343089D01*
X3457837Y344389D01*
X3457512Y345544D01*
X3457079Y346410D01*
X3456429Y347131D01*
X3455563Y347420D01*
G01X3464224D02*
X3463358Y347131D01*
X3462708Y346410D01*
X3462275Y345544D01*
X3461950Y344389D01*
X3461842Y343089D01*
X3461950Y341790D01*
X3462275Y340635D01*
X3462708Y339769D01*
X3463358Y339048D01*
X3464224Y338759D01*
X3465090Y339048D01*
X3465740Y339769D01*
X3466173Y340635D01*
X3466498Y341790D01*
X3466606Y343089D01*
X3466498Y344389D01*
X3466173Y345544D01*
X3465740Y346410D01*
X3465090Y347131D01*
X3464224Y347420D01*
G01X3428712Y567618D02*
Y569429D01*
G01D02*
X3434569D01*
G01X3443200Y567618D02*
X3428712D01*
G01Y577880D02*
Y579691D01*
G01D02*
X3443200D01*
G01X3434569Y577880D02*
X3428712D01*
G01X3429020Y592972D02*
X3429945Y591463D01*
G01X3428712Y594783D02*
X3429020Y592972D01*
G01X3429945Y598103D02*
X3429020Y596594D01*
G01D02*
X3428712Y594783D01*
G01X3430562Y593274D02*
X3431178Y592368D01*
G01X3429945Y591463D02*
X3430870Y590557D01*
G01X3431178Y592368D02*
X3433028Y591161D01*
G01X3430870Y590557D02*
X3432103Y589954D01*
G01D02*
X3433028Y589652D01*
G01X3430254Y594783D02*
X3430562Y593274D01*
G01Y596292D02*
X3430254Y594783D01*
G01X3430870Y599009D02*
X3429945Y598103D01*
G01X3431178Y597198D02*
X3430562Y596292D01*
G01X3433028Y598405D02*
X3431178Y597198D01*
G01X3432103Y599613D02*
X3430870Y599009D01*
G01X3433028Y599914D02*
X3432103Y599613D01*
G01X3446350Y1061004D02*
G03X3426665Y1080689I-19685J0D01*
G01X3445716Y-1777616D02*
Y-1837784D01*
G01D02*
X4197816D01*
G01X3445716Y-1777616D02*
Y-1732490D01*
G01X4235421Y-1777616D02*
X3445716D01*
G01Y-1732490D02*
Y-1687364D01*
G01Y-1732490D02*
X3821766D01*
G01X3445716Y-1687364D02*
Y-1582095D01*
G01Y-1687364D02*
X4235421D01*
G01X3445716Y-1642238D02*
X4235421D01*
G01X3445716Y-1582095D02*
X4235421D01*
G01X3440473Y-852641D02*
Y-843980D01*
X3436467Y-850187D01*
X3441881D01*
G01X3447835Y-852930D02*
X3447618Y-852785D01*
Y-852497D01*
X3447835Y-852352D01*
X3448052Y-852497D01*
Y-852785D01*
X3447835Y-852930D01*
G01X3456496Y-852641D02*
X3457254Y-852497D01*
X3458120Y-852064D01*
X3458661Y-851342D01*
X3458878Y-850331D01*
X3458661Y-849321D01*
X3458012Y-848455D01*
X3457037Y-848022D01*
X3455955D01*
X3455305Y-847733D01*
X3454764Y-847011D01*
X3454547Y-846001D01*
X3454872Y-844990D01*
X3455630Y-844269D01*
X3456496Y-843980D01*
X3457362Y-844269D01*
X3458120Y-844990D01*
X3458445Y-846001D01*
X3458228Y-847011D01*
X3457687Y-847733D01*
X3457037Y-848022D01*
X3455955D01*
X3454980Y-848455D01*
X3454331Y-849321D01*
X3454114Y-850331D01*
X3454331Y-851342D01*
X3454872Y-852064D01*
X3455738Y-852497D01*
X3456496Y-852641D01*
G01X3465157Y-843980D02*
X3464291Y-844269D01*
X3463641Y-844990D01*
X3463208Y-845856D01*
X3462883Y-847011D01*
X3462775Y-848311D01*
X3462883Y-849610D01*
X3463208Y-850765D01*
X3463641Y-851631D01*
X3464291Y-852352D01*
X3465157Y-852641D01*
X3466023Y-852352D01*
X3466673Y-851631D01*
X3467106Y-850765D01*
X3467431Y-849610D01*
X3467539Y-848311D01*
X3467431Y-847011D01*
X3467106Y-845856D01*
X3466673Y-844990D01*
X3466023Y-844269D01*
X3465157Y-843980D01*
G01X3437224Y-854806D02*
X3495767D01*
G01X3486318D02*
X3437224D01*
G01X3436734Y192310D02*
Y186279D01*
G01X3435504D02*
Y192310D01*
G01X3432797D02*
Y186279D01*
G01X3436734D02*
X3435504D01*
G01X3433781Y193315D02*
X3433289Y193064D01*
G01Y194069D02*
X3434027Y194321D01*
G01X3433289Y193064D02*
X3433043Y192813D01*
G01X3432551Y193315D02*
X3433289Y194069D01*
G01X3433043Y192813D02*
X3432797Y192310D01*
G01X3436242Y193567D02*
X3436734Y192310D01*
G01X3435504D02*
X3435257Y192813D01*
G01X3435750Y194069D02*
X3436242Y193567D01*
G01X3435257Y192813D02*
X3435011Y193064D01*
G01D02*
X3434519Y193315D01*
G01X3435011Y194321D02*
X3435750Y194069D01*
G01X3434027Y194321D02*
X3435011D01*
G01X3434519Y193315D02*
X3433781D01*
G01X3443200Y569429D02*
Y567618D01*
G01X3436419Y577880D02*
Y569429D01*
G01X3434569D02*
Y577880D01*
G01X3436419Y569429D02*
X3443200D01*
G01Y579691D02*
Y577880D01*
G01D02*
X3436419D01*
G01X3438269Y586935D02*
Y582106D01*
G01X3437035D02*
Y586935D01*
G01X3434569D02*
Y582106D01*
G01X3433336D02*
Y586935D01*
G01X3440734Y592368D02*
X3441351Y593274D01*
G01X3441967Y591463D02*
X3442892Y592972D01*
G01X3433028Y589652D02*
X3434569Y589350D01*
G01X3433028Y591161D02*
X3434878Y590859D01*
G01D02*
X3437035D01*
G01X3434569Y589350D02*
X3437344D01*
G01X3441043Y590557D02*
X3441967Y591463D01*
G01X3437035Y586935D02*
X3438269D01*
G01X3433336D02*
X3434569D01*
G01X3438269Y582106D02*
X3437035D01*
G01X3434569D02*
X3433336D01*
G01X3437035Y590859D02*
X3438885Y591161D01*
G01X3437344Y589350D02*
X3438885Y589652D01*
G01X3439810Y589954D02*
X3441043Y590557D01*
G01X3438885Y591161D02*
X3440734Y592368D01*
G01X3438885Y589652D02*
X3439810Y589954D01*
G01X3443200Y594783D02*
X3442892Y596594D01*
G01X3441659Y594783D02*
X3441351Y596292D01*
G01X3442892Y596594D02*
X3441967Y598103D01*
G01X3441351Y596292D02*
X3440734Y597198D01*
G01X3441967Y598103D02*
X3441043Y599009D01*
G01X3441351Y593274D02*
X3441659Y594783D01*
G01X3442892Y592972D02*
X3443200Y594783D01*
G01X3440734Y597198D02*
X3438885Y598405D01*
G01X3434569Y605649D02*
X3434878Y604744D01*
G01X3433645D02*
X3433336Y605649D01*
G01X3434569Y608668D02*
X3433645Y609573D01*
G01X3434878Y604744D02*
X3435494Y604140D01*
G01X3434261D02*
X3433645Y604744D01*
G01X3443200Y604140D02*
Y602631D01*
G01Y608969D02*
Y607460D01*
G01X3434569Y606253D02*
Y605649D01*
G01X3433336Y602631D02*
Y604140D01*
G01Y605649D02*
Y606857D01*
G01X3435186Y609271D02*
X3435802Y608969D01*
G01X3441043Y599009D02*
X3439810Y599613D01*
G01D02*
X3438885Y599914D01*
G01X3434878Y606857D02*
X3434569Y606253D01*
G01X3433336Y606857D02*
X3433645Y607762D01*
G01X3438885Y599914D02*
X3437344Y600216D01*
G01X3438885Y598405D02*
X3437035Y598707D01*
G01X3435802Y608969D02*
X3443200D01*
G01Y607460D02*
X3435802D01*
G01X3433336Y604140D02*
X3434261D01*
G01X3435494D02*
X3443200D01*
G01Y602631D02*
X3433336D01*
G01X3437344Y600216D02*
X3434569D01*
G01X3437035Y598707D02*
X3434878D01*
G01X3435186Y607158D02*
X3434878Y606857D01*
G01X3433645Y607762D02*
X3434569Y608668D01*
G01X3434878Y598707D02*
X3433028Y598405D01*
G01X3434569Y600216D02*
X3433028Y599914D01*
G01X3435802Y607460D02*
X3435186Y607158D01*
G01X3433645Y609573D02*
X3433336Y610479D01*
G01X3434569Y610177D02*
X3434878Y609573D01*
G01D02*
X3435186Y609271D01*
G01X3443200Y613799D02*
Y612290D01*
G01X3434569Y611082D02*
Y610177D01*
G01X3433336Y610479D02*
Y611686D01*
G01X3434878D02*
X3434569Y611082D01*
G01X3433336Y611686D02*
X3433645Y612591D01*
G01X3435802Y613799D02*
X3443200D01*
G01Y612290D02*
X3435802D01*
G01X3435186Y611988D02*
X3434878Y611686D01*
G01X3433645Y612591D02*
X3434261Y613195D01*
G01D02*
X3435802Y613799D01*
G01Y612290D02*
X3435186Y611988D01*
G01X3433645Y623156D02*
X3433336Y624061D01*
G01X3434569Y619232D02*
X3434878Y618326D01*
G01X3433645D02*
X3433336Y619232D01*
G01X3434569Y623759D02*
X3434878Y623156D01*
G01D02*
X3435186Y622854D01*
G01X3434569Y622250D02*
X3433645Y623156D01*
G01X3434878Y618326D02*
X3435494Y617723D01*
G01X3434261D02*
X3433645Y618326D01*
G01X3443200Y617723D02*
Y616213D01*
G01Y622552D02*
Y621043D01*
G01X3434569Y619835D02*
Y619232D01*
G01Y624665D02*
Y623759D01*
G01X3433336Y624061D02*
Y625268D01*
G01Y616213D02*
Y617723D01*
G01Y619232D02*
Y620439D01*
G01X3435186Y622854D02*
X3435802Y622552D01*
G01X3434878Y620439D02*
X3434569Y619835D01*
G01X3434878Y625268D02*
X3434569Y624665D01*
G01X3433336Y620439D02*
X3433645Y621345D01*
G01X3433336Y625268D02*
X3433645Y626174D01*
G01X3435802Y622552D02*
X3443200D01*
G01Y621043D02*
X3435802D01*
G01X3433336Y617723D02*
X3434261D01*
G01X3435494D02*
X3443200D01*
G01Y616213D02*
X3433336D01*
G01X3435186Y620741D02*
X3434878Y620439D01*
G01X3433645Y621345D02*
X3434569Y622250D01*
G01X3435186Y625570D02*
X3434878Y625268D01*
G01X3435802Y621043D02*
X3435186Y620741D01*
G01X3435802Y625872D02*
X3435186Y625570D01*
G01X3443200Y627381D02*
Y625872D01*
G01X3435802Y627381D02*
X3443200D01*
G01Y625872D02*
X3435802D01*
G01X3433645Y626174D02*
X3434261Y626778D01*
G01D02*
X3435802Y627381D01*
G01X3446350Y868090D02*
G03X3450287Y864153I3937J0D01*
G01X3446350Y1061004D02*
Y868090D01*
G01Y1064941D02*
Y1158602D01*
G01X3436967Y1164124D02*
X3436102Y1164774D01*
X3435668Y1165531D01*
X3435524Y1166398D01*
X3435813Y1167480D01*
X3436534Y1168238D01*
X3437400Y1168455D01*
X3438267Y1168346D01*
X3438988Y1167913D01*
X3440432Y1165748D01*
X3441442Y1164774D01*
X3442886Y1164124D01*
X3444185Y1163907D01*
Y1168455D01*
G01X3442453Y1172460D02*
X3443463Y1173110D01*
X3444041Y1173976D01*
X3444185Y1174950D01*
X3444041Y1175816D01*
X3443319Y1176683D01*
X3442453Y1177224D01*
X3441587Y1177332D01*
X3440576Y1177116D01*
X3439855Y1176358D01*
X3439566Y1175600D01*
Y1174625D01*
G01Y1175600D02*
X3439133Y1176249D01*
X3438411Y1176791D01*
X3437545Y1177007D01*
X3436679Y1176791D01*
X3435957Y1176249D01*
X3435524Y1175275D01*
X3435668Y1174301D01*
X3436246Y1173326D01*
G01X3444185Y1184802D02*
X3435524D01*
X3441731Y1180796D01*
Y1186210D01*
G01X3444474Y1192164D02*
X3444329Y1191947D01*
X3444041D01*
X3443896Y1192164D01*
X3444041Y1192381D01*
X3444329D01*
X3444474Y1192164D01*
G01X3444185Y1200825D02*
X3435524D01*
X3437256Y1199526D01*
G01X3444185D02*
Y1202124D01*
G01X3442886Y1207104D02*
X3443608Y1207754D01*
X3444041Y1208512D01*
X3444185Y1209486D01*
X3443896Y1210460D01*
X3443319Y1211218D01*
X3442309Y1211760D01*
X3441154Y1211868D01*
X3439999Y1211651D01*
X3439277Y1211110D01*
X3438700Y1210352D01*
X3438555Y1209594D01*
X3438700Y1208836D01*
X3439277Y1207862D01*
X3435524Y1208187D01*
Y1211110D01*
G01X3455374Y-1852994D02*
Y-1841587D01*
X3453663Y-1843868D01*
G01Y-1852994D02*
X3457085D01*
G01X3466782D02*
X3467780Y-1852804D01*
X3468921Y-1852234D01*
X3469634Y-1851283D01*
X3469919Y-1849952D01*
X3469634Y-1848622D01*
X3468778Y-1847481D01*
X3467495Y-1846910D01*
X3466069D01*
X3465213Y-1846530D01*
X3464500Y-1845580D01*
X3464215Y-1844249D01*
X3464643Y-1842918D01*
X3465641Y-1841967D01*
X3466782Y-1841587D01*
X3467923Y-1841967D01*
X3468921Y-1842918D01*
X3469349Y-1844249D01*
X3469064Y-1845580D01*
X3468351Y-1846530D01*
X3467495Y-1846910D01*
X3466069D01*
X3464786Y-1847481D01*
X3463930Y-1848622D01*
X3463645Y-1849952D01*
X3463930Y-1851283D01*
X3464643Y-1852234D01*
X3465784Y-1852804D01*
X3466782Y-1852994D01*
G01X3473254Y-1750218D02*
X3471754Y-1749218D01*
X3470004Y-1748551D01*
X3468004D01*
X3465754Y-1749551D01*
X3464004Y-1751218D01*
X3462754Y-1753218D01*
X3461754Y-1756551D01*
X3461504Y-1759551D01*
X3462004Y-1762551D01*
X3462754Y-1764551D01*
X3464254Y-1766551D01*
X3466004Y-1767884D01*
X3467754Y-1768551D01*
X3469504D01*
X3471254Y-1767884D01*
X3472754Y-1766885D01*
X3474004Y-1765552D01*
G01X3484254Y-1768551D02*
Y-1755218D01*
G01Y-1757884D02*
X3485504Y-1756551D01*
X3486754Y-1755551D01*
X3488504Y-1755218D01*
X3489754Y-1755551D01*
X3491254Y-1756551D01*
G01X3504004Y-1759551D02*
X3512004D01*
X3511254Y-1757218D01*
X3510004Y-1755885D01*
X3508254Y-1755218D01*
X3506504Y-1755551D01*
X3505004Y-1756551D01*
X3504004Y-1758885D01*
X3503504Y-1760885D01*
Y-1762884D01*
X3504004Y-1764885D01*
X3505254Y-1766885D01*
X3506754Y-1768218D01*
X3508504Y-1768551D01*
X3510254Y-1767884D01*
X3512004Y-1765885D01*
G01X3532254Y-1768551D02*
Y-1755218D01*
G01Y-1757551D02*
X3531254Y-1756218D01*
X3529754Y-1755551D01*
X3528004Y-1755218D01*
X3526254Y-1755885D01*
X3524754Y-1757218D01*
X3523754Y-1759218D01*
X3523254Y-1761885D01*
X3523754Y-1764551D01*
X3524754Y-1766551D01*
X3526254Y-1767884D01*
X3528004Y-1768551D01*
X3529754Y-1768218D01*
X3531254Y-1767218D01*
X3532254Y-1765885D01*
G01X3547754Y-1748551D02*
Y-1768551D01*
G01X3544254Y-1755218D02*
X3551254D01*
G01X3564004Y-1759551D02*
X3572004D01*
X3571254Y-1757218D01*
X3570004Y-1755885D01*
X3568254Y-1755218D01*
X3566504Y-1755551D01*
X3565004Y-1756551D01*
X3564004Y-1758885D01*
X3563504Y-1760885D01*
Y-1762884D01*
X3564004Y-1764885D01*
X3565254Y-1766885D01*
X3566754Y-1768218D01*
X3568504Y-1768551D01*
X3570254Y-1767884D01*
X3572004Y-1765885D01*
G01X3592254Y-1748551D02*
Y-1768551D01*
G01Y-1765552D02*
X3591254Y-1767218D01*
X3589754Y-1768218D01*
X3588004Y-1768551D01*
X3586004Y-1767884D01*
X3584504Y-1766218D01*
X3583504Y-1764218D01*
X3583254Y-1761885D01*
X3583504Y-1759551D01*
X3584504Y-1757551D01*
X3586004Y-1755885D01*
X3588004Y-1755218D01*
X3589754Y-1755551D01*
X3591004Y-1756218D01*
X3592254Y-1757551D01*
G01X3458802Y-1699643D02*
X3465052Y-1719643D01*
X3471302Y-1699643D01*
G01X3481302Y-1710643D02*
X3489302D01*
X3488552Y-1708310D01*
X3487302Y-1706977D01*
X3485552Y-1706310D01*
X3483802Y-1706643D01*
X3482302Y-1707643D01*
X3481302Y-1709977D01*
X3480802Y-1711977D01*
Y-1713976D01*
X3481302Y-1715977D01*
X3482552Y-1717977D01*
X3484052Y-1719310D01*
X3485802Y-1719643D01*
X3487552Y-1718976D01*
X3489302Y-1716977D01*
G01X3501552Y-1719643D02*
Y-1706310D01*
G01Y-1708976D02*
X3502802Y-1707643D01*
X3504052Y-1706643D01*
X3505802Y-1706310D01*
X3507052Y-1706643D01*
X3508552Y-1707643D01*
G01X3521302Y-1717310D02*
X3522552Y-1718643D01*
X3524302Y-1719643D01*
X3525802D01*
X3527302Y-1718976D01*
X3528302Y-1717977D01*
X3528802Y-1716644D01*
X3528552Y-1714643D01*
X3527552Y-1713643D01*
X3523052Y-1711643D01*
X3522052Y-1709309D01*
X3522552Y-1707643D01*
X3523552Y-1706643D01*
X3525052Y-1706310D01*
X3526552Y-1706643D01*
X3528052Y-1707643D01*
G01X3545052Y-1706310D02*
Y-1719643D01*
G01Y-1700977D02*
X3544552Y-1700643D01*
Y-1699976D01*
X3545052Y-1699643D01*
X3545552Y-1699976D01*
Y-1700643D01*
X3545052Y-1700977D01*
G01X3565052Y-1719643D02*
X3563552Y-1719310D01*
X3562052Y-1717977D01*
X3561052Y-1715643D01*
X3560552Y-1712977D01*
X3561052Y-1710310D01*
X3562052Y-1707976D01*
X3563552Y-1706643D01*
X3565052Y-1706310D01*
X3566552Y-1706643D01*
X3568052Y-1707976D01*
X3569052Y-1710310D01*
X3569302Y-1712977D01*
X3569052Y-1715643D01*
X3568052Y-1717977D01*
X3566552Y-1719310D01*
X3565052Y-1719643D01*
G01X3580802D02*
Y-1706310D01*
G01Y-1709643D02*
X3581802Y-1707976D01*
X3583302Y-1706643D01*
X3585302Y-1706310D01*
X3587052Y-1706643D01*
X3588552Y-1707976D01*
X3589302Y-1710310D01*
Y-1719643D01*
G01X3462754Y-1675630D02*
Y-1655630D01*
X3468754D01*
X3470754Y-1656630D01*
X3472254Y-1658963D01*
X3472754Y-1661630D01*
X3472254Y-1664297D01*
X3471004Y-1666297D01*
X3468754Y-1667297D01*
X3462754D01*
G01X3493254Y-1657297D02*
X3491754Y-1656297D01*
X3490004Y-1655630D01*
X3488004D01*
X3485754Y-1656630D01*
X3484004Y-1658297D01*
X3482754Y-1660297D01*
X3481754Y-1663630D01*
X3481504Y-1666630D01*
X3482004Y-1669630D01*
X3482754Y-1671630D01*
X3484254Y-1673630D01*
X3486004Y-1674963D01*
X3487754Y-1675630D01*
X3489504D01*
X3491254Y-1674963D01*
X3492754Y-1673964D01*
X3494004Y-1672631D01*
G01X3509754Y-1664963D02*
X3510754Y-1663963D01*
X3511504Y-1662297D01*
X3512004Y-1659963D01*
X3511504Y-1657963D01*
X3510504Y-1656630D01*
X3508754Y-1655630D01*
X3502004D01*
Y-1675630D01*
X3510254D01*
X3512004Y-1674297D01*
X3513004Y-1672297D01*
X3513504Y-1669963D01*
X3513004Y-1667630D01*
X3511504Y-1665630D01*
X3509754Y-1664963D01*
X3502004D01*
G01X3542004Y-1675630D02*
Y-1655630D01*
X3553504Y-1675630D01*
Y-1655630D01*
G01X3567754Y-1675630D02*
X3566254Y-1675297D01*
X3564754Y-1673964D01*
X3563754Y-1671630D01*
X3563254Y-1668964D01*
X3563754Y-1666297D01*
X3564754Y-1663963D01*
X3566254Y-1662630D01*
X3567754Y-1662297D01*
X3569254Y-1662630D01*
X3570754Y-1663963D01*
X3571754Y-1666297D01*
X3572004Y-1668964D01*
X3571754Y-1671630D01*
X3570754Y-1673964D01*
X3569254Y-1675297D01*
X3567754Y-1675630D01*
G01X3587754Y-1676297D02*
X3587254Y-1675963D01*
Y-1675297D01*
X3587754Y-1674963D01*
X3588254Y-1675297D01*
Y-1675963D01*
X3587754Y-1676297D01*
G01X3454421Y864153D02*
Y320846D01*
G01X3508358Y416712D02*
X3454421D01*
G01X3456606Y484901D02*
Y460098D01*
G01D02*
X3506409D01*
G01X3463988Y468956D02*
Y459114D01*
G01D02*
X3467531D01*
G01X3463988Y476043D02*
Y485885D01*
G01X3467531Y476043D02*
X3463988D01*
G01X3467531Y468956D02*
X3463988D01*
G01X3506409Y484901D02*
X3456606D01*
G01X3463988Y485885D02*
X3467531D01*
G01X3531980Y503917D02*
X3454173D01*
G01X3454421Y521633D02*
X3924500D01*
G01X3450287Y864153D02*
X3509342D01*
G01X3455374Y1438719D02*
Y1450126D01*
X3453663Y1447845D01*
G01Y1438719D02*
X3457085D01*
G01X3466782D02*
X3467780Y1438909D01*
X3468921Y1439479D01*
X3469634Y1440430D01*
X3469919Y1441761D01*
X3469634Y1443091D01*
X3468778Y1444232D01*
X3467495Y1444803D01*
X3466069D01*
X3465213Y1445183D01*
X3464500Y1446133D01*
X3464215Y1447464D01*
X3464643Y1448795D01*
X3465641Y1449746D01*
X3466782Y1450126D01*
X3467923Y1449746D01*
X3468921Y1448795D01*
X3469349Y1447464D01*
X3469064Y1446133D01*
X3468351Y1445183D01*
X3467495Y1444803D01*
X3466069D01*
X3464786Y1444232D01*
X3463930Y1443091D01*
X3463645Y1441761D01*
X3463930Y1440430D01*
X3464643Y1439479D01*
X3465784Y1438909D01*
X3466782Y1438719D01*
G01X3471199Y-1631417D02*
Y-1606417D01*
X3479389Y-1627250D01*
X3487579Y-1606417D01*
Y-1631417D01*
G01X3504589D02*
X3502699Y-1631000D01*
X3500809Y-1629334D01*
X3499549Y-1626417D01*
X3498919Y-1623084D01*
X3499549Y-1619751D01*
X3500809Y-1616834D01*
X3502699Y-1615167D01*
X3504589Y-1614751D01*
X3506479Y-1615167D01*
X3508369Y-1616834D01*
X3509629Y-1619751D01*
X3509944Y-1623084D01*
X3509629Y-1626417D01*
X3508369Y-1629334D01*
X3506479Y-1631000D01*
X3504589Y-1631417D01*
G01X3535459Y-1606417D02*
Y-1631417D01*
G01Y-1627668D02*
X3534199Y-1629751D01*
X3532309Y-1631000D01*
X3530104Y-1631417D01*
X3527584Y-1630584D01*
X3525694Y-1628501D01*
X3524434Y-1626001D01*
X3524119Y-1623084D01*
X3524434Y-1620167D01*
X3525694Y-1617667D01*
X3527584Y-1615584D01*
X3530104Y-1614751D01*
X3532309Y-1615167D01*
X3533884Y-1616001D01*
X3535459Y-1617667D01*
G01X3550264Y-1620167D02*
X3560344D01*
X3559399Y-1617250D01*
X3557824Y-1615584D01*
X3555619Y-1614751D01*
X3553414Y-1615167D01*
X3551524Y-1616417D01*
X3550264Y-1619334D01*
X3549634Y-1621834D01*
Y-1624334D01*
X3550264Y-1626834D01*
X3551839Y-1629334D01*
X3553729Y-1631000D01*
X3555934Y-1631417D01*
X3558139Y-1630584D01*
X3560344Y-1628084D01*
G01X3580189Y-1631417D02*
Y-1606417D01*
G01X3512939Y-1049405D02*
G03I-17323J0D01*
G01X3488490Y-909917D02*
X3476679D01*
G01X3512939Y-882082D02*
G03I-17323J0D01*
G01X3472342Y-521846D02*
G03X3476279Y-517909I0J3937D01*
G01D02*
Y-324996D01*
G01X3495964Y-305311D02*
G03X3476279Y-324996I0J-19685D01*
G01X3531980Y336594D02*
X3471803D01*
G01X3476271Y428194D02*
Y429094D01*
G01Y423090D02*
Y423991D01*
G01X3479184Y428194D02*
X3476271D01*
G01Y423991D02*
X3479184D01*
G01X3483476Y423090D02*
X3476271D01*
G01Y429094D02*
X3483476D01*
G01X3480104Y428194D02*
Y423991D01*
G01X3479184D02*
Y428194D01*
G01X3483476D02*
X3480104D01*
G01Y423991D02*
X3483476D01*
G01X3481023Y432696D02*
Y430295D01*
G01X3480410D02*
Y432696D01*
G01X3479184D02*
Y430295D01*
G01X3478571D02*
Y432696D01*
G01X3480410D02*
X3481023D01*
G01X3478571D02*
X3479184D01*
G01Y430295D02*
X3478571D01*
G01X3481023D02*
X3480410D01*
G01X3476425Y437950D02*
X3476731Y438550D01*
G01X3477191Y437650D02*
X3477038Y436899D01*
G01X3476271Y437049D02*
X3476425Y437950D01*
G01Y435398D02*
X3476271Y436449D01*
G01X3477038Y436299D02*
X3477191Y435548D01*
G01X3477957Y438400D02*
X3477498Y438100D01*
G01X3476731Y438550D02*
X3477345Y439151D01*
G01X3477498Y438100D02*
X3477191Y437650D01*
G01X3477957Y434798D02*
Y434047D01*
G01X3477038Y436899D02*
Y436299D01*
G01X3476271Y436449D02*
Y437049D01*
G01X3476731Y434798D02*
X3476425Y435398D01*
G01X3477191Y435548D02*
X3477498Y435098D01*
G01X3477345Y434198D02*
X3476731Y434798D01*
G01X3477498Y435098D02*
X3477957Y434798D01*
G01X3478877Y438100D02*
X3478264Y438400D01*
G01Y439301D02*
X3478877Y439151D01*
G01X3477957Y434047D02*
X3477345Y434198D01*
G01X3477957Y439301D02*
X3478264D01*
G01Y438400D02*
X3477957D01*
G01X3477345Y439151D02*
X3477957Y439301D01*
G01X3479337Y442603D02*
X3479184Y442303D01*
G01X3479337Y445005D02*
X3479184Y444704D01*
G01X3478571Y442603D02*
X3478724Y443053D01*
G01Y443954D02*
X3478571Y444404D01*
G01X3479184Y442003D02*
X3479337Y441552D01*
G01X3478724D02*
X3478571Y442003D01*
G01X3479184Y444254D02*
X3479337Y443954D01*
G01X3479491Y442753D02*
X3479337Y442603D01*
G01X3478724Y443053D02*
X3479184Y443504D01*
G01Y442303D02*
Y442003D01*
G01Y444704D02*
Y444254D01*
G01X3478571Y444404D02*
Y445005D01*
G01Y440502D02*
Y441252D01*
G01Y442003D02*
Y442603D01*
G01X3479337Y438850D02*
X3482709Y435098D01*
G01Y433897D02*
X3478877Y438100D01*
G01X3479797Y442903D02*
X3479491Y442753D01*
G01X3479337Y443954D02*
X3479491Y443804D01*
G01X3479184Y443504D02*
X3478724Y443954D01*
G01X3479337Y441552D02*
X3479644Y441252D01*
G01X3479031D02*
X3478724Y441552D01*
G01X3478877Y439151D02*
X3479337Y438850D01*
G01X3479491Y443804D02*
X3479797Y443654D01*
G01D02*
X3483476D01*
G01Y442903D02*
X3479797D01*
G01X3478571Y441252D02*
X3479031D01*
G01X3479644D02*
X3483476D01*
G01Y440502D02*
X3478571D01*
G01X3479337Y449357D02*
X3479184Y449057D01*
G01X3478571Y445005D02*
X3478724Y445455D01*
G01X3478571Y449357D02*
X3478724Y449808D01*
G01X3479184Y448757D02*
X3479337Y448307D01*
G01X3478724D02*
X3478571Y448757D01*
G01X3479491Y445155D02*
X3479337Y445005D01*
G01X3478724Y445455D02*
X3479031Y445755D01*
G01X3479491Y449507D02*
X3479337Y449357D01*
G01X3478724Y449808D02*
X3479184Y450258D01*
G01Y449057D02*
Y448757D01*
G01X3478571D02*
Y449357D01*
G01Y447256D02*
Y448007D01*
G01X3479031Y445755D02*
X3479797Y446055D01*
G01Y445305D02*
X3479491Y445155D01*
G01X3479797Y449657D02*
X3479491Y449507D01*
G01X3479184Y450258D02*
X3478724Y450708D01*
G01X3479337Y448307D02*
X3479644Y448007D01*
G01X3479031D02*
X3478724Y448307D01*
G01X3479491Y450558D02*
X3479797Y450408D01*
G01D02*
X3483476D01*
G01Y449657D02*
X3479797D01*
G01X3478571Y448007D02*
X3479031D01*
G01X3479644D02*
X3483476D01*
G01Y447256D02*
X3478571D01*
G01X3479797Y446055D02*
X3483476D01*
G01Y445305D02*
X3479797D01*
G01X3475405Y459114D02*
Y468956D01*
G01X3471862D02*
Y459114D01*
G01X3467531D02*
Y468956D01*
G01X3471862Y459114D02*
X3475405D01*
G01X3479337Y451759D02*
X3479184Y451459D01*
G01X3478571Y451759D02*
X3478724Y452209D01*
G01X3479736Y468956D02*
Y459114D01*
G01X3478724Y450708D02*
X3478571Y451159D01*
G01X3479184Y451009D02*
X3479337Y450708D01*
G01X3479491Y451909D02*
X3479337Y451759D01*
G01X3478724Y452209D02*
X3479031Y452509D01*
G01X3479184Y451459D02*
Y451009D01*
G01X3478571Y451159D02*
Y451759D01*
G01X3479031Y452509D02*
X3479797Y452810D01*
G01Y452059D02*
X3479491Y451909D01*
G01X3479337Y450708D02*
X3479491Y450558D01*
G01X3479736Y459114D02*
X3483279D01*
G01X3479797Y452810D02*
X3483476D01*
G01Y452059D02*
X3479797D01*
G01X3475405Y485885D02*
Y476043D01*
G01X3471862D02*
Y485885D01*
G01X3467531D02*
Y476043D01*
G01X3475405D02*
X3471862D01*
G01X3475405Y468956D02*
X3471862D01*
G01X3479736Y476043D02*
Y485885D01*
G01X3483279Y476043D02*
X3479736D01*
G01X3483279Y468956D02*
X3479736D01*
G01X3471862Y485885D02*
X3475405D01*
G01X3479736D02*
X3483279D01*
G01X3492618Y-1043106D02*
G03Y-1055704I0J-6299D01*
G01D02*
X3498917D01*
G01Y-1043106D02*
X3492618D01*
G01X3492538Y-898068D02*
X3488490Y-909917D01*
G01X3492618Y-875783D02*
G03Y-888381I0J-6299D01*
G01D02*
X3498917D01*
G01X3486318Y-878145D02*
Y-850869D01*
G01X3498917Y-875783D02*
X3492618D01*
G01X3524901Y-854806D02*
X3495767D01*
G01X3867814Y-305311D02*
X3495964D01*
G01X3483476Y423991D02*
Y423090D01*
G01Y429094D02*
Y428194D01*
G01Y439301D02*
Y433897D01*
G01D02*
X3482709D01*
G01X3483476Y441252D02*
Y440502D01*
G01Y443654D02*
Y442903D01*
G01X3482709Y435098D02*
Y439301D01*
G01D02*
X3483476D01*
G01Y448007D02*
Y447256D01*
G01Y446055D02*
Y445305D01*
G01Y450408D02*
Y449657D01*
G01X3491153Y459114D02*
Y468956D01*
G01X3487610D02*
Y459114D01*
G01X3483476Y452810D02*
Y452059D01*
G01X3483279Y459114D02*
Y468956D01*
G01X3487610Y459114D02*
X3491153D01*
G01X3497307Y452118D02*
Y456724D01*
G01X3496613Y455897D02*
Y456842D01*
G01X3495484Y468956D02*
Y459114D01*
G01X3497307Y456724D02*
X3496613Y455897D01*
G01Y456842D02*
X3497307Y457669D01*
G01X3495484Y459114D02*
X3499027D01*
G01X3497307Y457669D02*
X3498001D01*
G01Y452118D02*
X3497307D01*
G01X3491153Y485885D02*
Y476043D01*
G01X3487610D02*
Y485885D01*
G01X3483279D02*
Y476043D01*
G01X3491153D02*
X3487610D01*
G01X3491153Y468956D02*
X3487610D01*
G01X3495484Y476043D02*
Y485885D01*
G01X3499027Y476043D02*
X3495484D01*
G01X3499027Y468956D02*
X3495484D01*
G01X3487610Y485885D02*
X3491153D01*
G01X3495484D02*
X3499027D01*
G01X3498917Y-1055704D02*
G03Y-1043106I0J6299D01*
G01X3506013Y-1035549D02*
X3524348Y-1011111D01*
G01X3498917Y-888381D02*
G03Y-875783I0J6299D01*
G01X3505216Y-878145D02*
Y-850869D01*
G01Y-854806D02*
X3524901D01*
G01X3508358Y285019D02*
Y521633D01*
G01Y285019D02*
X3547728D01*
G01X3508358Y357854D02*
X3776074D01*
G01X3506409Y460098D02*
Y484901D01*
G01X3499027Y459114D02*
Y468956D01*
G01X3498001Y457669D02*
Y452118D01*
G01X3499027Y485885D02*
Y476043D01*
G01X3509342Y864153D02*
G03X3513279Y868090I0J3937D01*
G01Y864153D02*
X3601172D01*
G01X3513279Y868090D02*
Y1061004D01*
G01Y1064941D02*
Y1158602D01*
G01X3532964Y1080689D02*
G03X3513279Y1061004I0J-19685D01*
G01X3503896Y1164124D02*
X3503031Y1164774D01*
X3502597Y1165531D01*
X3502453Y1166398D01*
X3502742Y1167480D01*
X3503463Y1168238D01*
X3504329Y1168455D01*
X3505196Y1168346D01*
X3505917Y1167913D01*
X3507361Y1165748D01*
X3508371Y1164774D01*
X3509815Y1164124D01*
X3511114Y1163907D01*
Y1168455D01*
G01X3509815Y1172460D02*
X3510537Y1173110D01*
X3510970Y1173868D01*
X3511114Y1174842D01*
X3510825Y1175816D01*
X3510248Y1176574D01*
X3509238Y1177116D01*
X3508083Y1177224D01*
X3506928Y1177007D01*
X3506206Y1176466D01*
X3505629Y1175708D01*
X3505484Y1174950D01*
X3505629Y1174192D01*
X3506206Y1173218D01*
X3502453Y1173543D01*
Y1176466D01*
G01X3511114Y1183503D02*
X3502453D01*
X3504185Y1182204D01*
G01X3511114D02*
Y1184802D01*
G01X3511403Y1192164D02*
X3511258Y1191947D01*
X3510970D01*
X3510825Y1192164D01*
X3510970Y1192381D01*
X3511258D01*
X3511403Y1192164D01*
G01X3511114Y1200825D02*
X3502453D01*
X3504185Y1199526D01*
G01X3511114D02*
Y1202124D01*
G01X3509815Y1207104D02*
X3510537Y1207754D01*
X3510970Y1208512D01*
X3511114Y1209486D01*
X3510825Y1210460D01*
X3510248Y1211218D01*
X3509238Y1211760D01*
X3508083Y1211868D01*
X3506928Y1211651D01*
X3506206Y1211110D01*
X3505629Y1210352D01*
X3505484Y1209594D01*
X3505629Y1208836D01*
X3506206Y1207862D01*
X3502453Y1208187D01*
Y1211110D01*
G01X3527077Y-1802054D02*
X3531487Y-1827054D01*
X3536527Y-1802054D01*
X3541567Y-1827054D01*
X3545977Y-1802054D01*
G01X3561727Y-1810388D02*
Y-1827054D01*
G01Y-1803721D02*
X3561097Y-1803304D01*
Y-1802471D01*
X3561727Y-1802054D01*
X3562357Y-1802471D01*
Y-1803304D01*
X3561727Y-1803721D01*
G01X3582202Y-1824138D02*
X3583777Y-1825804D01*
X3585982Y-1827054D01*
X3587872D01*
X3589762Y-1826221D01*
X3591022Y-1824971D01*
X3591652Y-1823305D01*
X3591337Y-1820804D01*
X3590077Y-1819554D01*
X3584407Y-1817055D01*
X3583147Y-1814137D01*
X3583777Y-1812054D01*
X3585037Y-1810804D01*
X3586927Y-1810388D01*
X3588817Y-1810804D01*
X3590707Y-1812054D01*
G01X3612127Y-1802054D02*
Y-1827054D01*
G01X3607717Y-1810388D02*
X3616537D01*
G01X3632917Y-1827054D02*
Y-1810388D01*
G01Y-1813720D02*
X3634492Y-1812054D01*
X3636067Y-1810804D01*
X3638272Y-1810388D01*
X3639847Y-1810804D01*
X3641737Y-1812054D01*
G01X3662527Y-1827054D02*
X3660637Y-1826637D01*
X3658747Y-1824971D01*
X3657487Y-1822054D01*
X3656857Y-1818721D01*
X3657487Y-1815388D01*
X3658747Y-1812471D01*
X3660637Y-1810804D01*
X3662527Y-1810388D01*
X3664417Y-1810804D01*
X3666307Y-1812471D01*
X3667567Y-1815388D01*
X3667882Y-1818721D01*
X3667567Y-1822054D01*
X3666307Y-1824971D01*
X3664417Y-1826637D01*
X3662527Y-1827054D01*
G01X3682372D02*
Y-1810388D01*
G01Y-1814554D02*
X3683632Y-1812471D01*
X3685522Y-1810804D01*
X3688042Y-1810388D01*
X3690247Y-1810804D01*
X3692137Y-1812471D01*
X3693082Y-1815388D01*
Y-1827054D01*
G01X3745057Y-1804138D02*
X3743167Y-1802887D01*
X3740962Y-1802054D01*
X3738442D01*
X3735607Y-1803304D01*
X3733402Y-1805387D01*
X3731827Y-1807888D01*
X3730567Y-1812054D01*
X3730252Y-1815804D01*
X3730882Y-1819554D01*
X3731827Y-1822054D01*
X3733717Y-1824555D01*
X3735922Y-1826221D01*
X3738127Y-1827054D01*
X3740332D01*
X3742537Y-1826221D01*
X3744427Y-1824971D01*
X3746002Y-1823305D01*
G01X3763327Y-1827054D02*
X3761437Y-1826637D01*
X3759547Y-1824971D01*
X3758287Y-1822054D01*
X3757657Y-1818721D01*
X3758287Y-1815388D01*
X3759547Y-1812471D01*
X3761437Y-1810804D01*
X3763327Y-1810388D01*
X3765217Y-1810804D01*
X3767107Y-1812471D01*
X3768367Y-1815388D01*
X3768682Y-1818721D01*
X3768367Y-1822054D01*
X3767107Y-1824971D01*
X3765217Y-1826637D01*
X3763327Y-1827054D01*
G01X3784117D02*
Y-1810388D01*
G01Y-1813720D02*
X3785692Y-1812054D01*
X3787267Y-1810804D01*
X3789472Y-1810388D01*
X3791047Y-1810804D01*
X3792937Y-1812054D01*
G01X3808057Y-1835387D02*
Y-1810388D01*
G01Y-1814137D02*
X3809632Y-1812054D01*
X3811207Y-1810804D01*
X3813727Y-1810388D01*
X3815932Y-1810804D01*
X3818137Y-1812887D01*
X3819082Y-1815804D01*
X3819397Y-1818721D01*
X3819082Y-1821638D01*
X3818137Y-1824555D01*
X3816247Y-1826221D01*
X3813727Y-1827054D01*
X3811522Y-1826637D01*
X3809317Y-1825388D01*
X3808057Y-1823721D01*
G01X3838927Y-1827054D02*
X3837037Y-1826637D01*
X3835147Y-1824971D01*
X3833887Y-1822054D01*
X3833257Y-1818721D01*
X3833887Y-1815388D01*
X3835147Y-1812471D01*
X3837037Y-1810804D01*
X3838927Y-1810388D01*
X3840817Y-1810804D01*
X3842707Y-1812471D01*
X3843967Y-1815388D01*
X3844282Y-1818721D01*
X3843967Y-1822054D01*
X3842707Y-1824971D01*
X3840817Y-1826637D01*
X3838927Y-1827054D01*
G01X3859717D02*
Y-1810388D01*
G01Y-1813720D02*
X3861292Y-1812054D01*
X3862867Y-1810804D01*
X3865072Y-1810388D01*
X3866647Y-1810804D01*
X3868537Y-1812054D01*
G01X3894997Y-1827054D02*
Y-1810388D01*
G01Y-1813304D02*
X3893737Y-1811638D01*
X3891847Y-1810804D01*
X3889642Y-1810388D01*
X3887437Y-1811221D01*
X3885547Y-1812887D01*
X3884287Y-1815388D01*
X3883657Y-1818721D01*
X3884287Y-1822054D01*
X3885547Y-1824555D01*
X3887437Y-1826221D01*
X3889642Y-1827054D01*
X3891847Y-1826637D01*
X3893737Y-1825388D01*
X3894997Y-1823721D01*
G01X3914527Y-1802054D02*
Y-1827054D01*
G01X3910117Y-1810388D02*
X3918937D01*
G01X3939727D02*
Y-1827054D01*
G01Y-1803721D02*
X3939097Y-1803304D01*
Y-1802471D01*
X3939727Y-1802054D01*
X3940357Y-1802471D01*
Y-1803304D01*
X3939727Y-1803721D01*
G01X3964927Y-1827054D02*
X3963037Y-1826637D01*
X3961147Y-1824971D01*
X3959887Y-1822054D01*
X3959257Y-1818721D01*
X3959887Y-1815388D01*
X3961147Y-1812471D01*
X3963037Y-1810804D01*
X3964927Y-1810388D01*
X3966817Y-1810804D01*
X3968707Y-1812471D01*
X3969967Y-1815388D01*
X3970282Y-1818721D01*
X3969967Y-1822054D01*
X3968707Y-1824971D01*
X3966817Y-1826637D01*
X3964927Y-1827054D01*
G01X3984772D02*
Y-1810388D01*
G01Y-1814554D02*
X3986032Y-1812471D01*
X3987922Y-1810804D01*
X3990442Y-1810388D01*
X3992647Y-1810804D01*
X3994537Y-1812471D01*
X3995482Y-1815388D01*
Y-1827054D01*
G01X3527498Y-1011111D02*
X3657708D01*
G01X3524348D02*
X3527498D01*
G01X3549939Y336594D02*
G03I-17322J0D01*
G01X3529618Y342893D02*
G03Y330295I0J-6299D01*
G01D02*
X3535917D01*
G01Y342893D02*
X3529618D01*
G01X3549939Y503917D02*
G03I-17322J0D01*
G01X3529618Y510216D02*
G03Y497618I0J-6299D01*
G01D02*
X3535917D01*
G01Y510216D02*
X3529618D01*
G01X3523384Y555284D02*
X3522519Y555934D01*
X3522085Y556691D01*
X3521941Y557558D01*
X3522230Y558640D01*
X3522951Y559398D01*
X3523817Y559615D01*
X3524684Y559506D01*
X3525405Y559073D01*
X3526849Y556908D01*
X3527859Y555934D01*
X3529303Y555284D01*
X3530602Y555067D01*
Y559615D01*
G01X3529303Y563620D02*
X3530025Y564270D01*
X3530458Y565028D01*
X3530602Y566002D01*
X3530313Y566976D01*
X3529736Y567734D01*
X3528726Y568276D01*
X3527571Y568384D01*
X3526416Y568167D01*
X3525694Y567626D01*
X3525117Y566868D01*
X3524972Y566110D01*
X3525117Y565352D01*
X3525694Y564378D01*
X3521941Y564703D01*
Y567626D01*
G01X3526993Y572606D02*
X3525983Y573364D01*
X3525405Y574013D01*
X3525117Y574880D01*
X3525405Y575637D01*
X3525983Y576179D01*
X3526849Y576612D01*
X3527859Y576720D01*
X3528726Y576612D01*
X3529592Y576179D01*
X3530313Y575529D01*
X3530602Y574771D01*
X3530313Y573905D01*
X3529447Y573147D01*
X3528148Y572714D01*
X3526705Y572606D01*
X3524828Y572822D01*
X3523817Y573147D01*
X3522807Y573689D01*
X3522085Y574446D01*
X3521941Y575204D01*
X3522230Y575962D01*
X3522951Y576504D01*
G01X3530891Y583324D02*
X3530746Y583107D01*
X3530458D01*
X3530313Y583324D01*
X3530458Y583541D01*
X3530746D01*
X3530891Y583324D01*
G01X3530602Y591985D02*
X3521941D01*
X3523673Y590686D01*
G01X3530602D02*
Y593284D01*
G01X3521941Y600646D02*
X3522230Y599780D01*
X3522951Y599130D01*
X3523817Y598697D01*
X3524972Y598372D01*
X3526272Y598264D01*
X3527571Y598372D01*
X3528726Y598697D01*
X3529592Y599130D01*
X3530313Y599780D01*
X3530602Y600646D01*
X3530313Y601512D01*
X3529592Y602162D01*
X3528726Y602595D01*
X3527571Y602920D01*
X3526272Y603028D01*
X3524972Y602920D01*
X3523817Y602595D01*
X3522951Y602162D01*
X3522230Y601512D01*
X3521941Y600646D01*
G01X3519883Y1075713D02*
X3582176Y1005668D01*
G01X3540706Y-1008945D02*
Y-1000284D01*
X3536700Y-1006491D01*
X3542114D01*
G01X3546661Y-1006058D02*
X3549475D01*
G01X3535917Y330295D02*
G03Y342893I0J6299D01*
G01Y497618D02*
G03Y510216I0J6299D01*
G01X3532767Y514153D02*
Y549763D01*
G01X3546645Y514080D02*
X3572150Y532559D01*
G01X3904815Y1080689D02*
X3532964D01*
G01X3904815D02*
X3532964D01*
G01X3553157Y-1008945D02*
Y-1003171D01*
G01Y-1004615D02*
X3553591Y-1003893D01*
X3554240Y-1003315D01*
X3555106Y-1003171D01*
X3555864Y-1003315D01*
X3556514Y-1003893D01*
X3556839Y-1004903D01*
Y-1008945D01*
G01X3566546D02*
X3567304Y-1008801D01*
X3568170Y-1008368D01*
X3568711Y-1007646D01*
X3568928Y-1006635D01*
X3568711Y-1005625D01*
X3568062Y-1004759D01*
X3567087Y-1004326D01*
X3566005D01*
X3565355Y-1004037D01*
X3564814Y-1003315D01*
X3564597Y-1002305D01*
X3564922Y-1001294D01*
X3565680Y-1000573D01*
X3566546Y-1000284D01*
X3567412Y-1000573D01*
X3568170Y-1001294D01*
X3568495Y-1002305D01*
X3568278Y-1003315D01*
X3567737Y-1004037D01*
X3567087Y-1004326D01*
X3566005D01*
X3565030Y-1004759D01*
X3564381Y-1005625D01*
X3564164Y-1006635D01*
X3564381Y-1007646D01*
X3564922Y-1008368D01*
X3565788Y-1008801D01*
X3566546Y-1008945D01*
G01X3575207Y-1009234D02*
X3574990Y-1009089D01*
Y-1008801D01*
X3575207Y-1008656D01*
X3575424Y-1008801D01*
Y-1009089D01*
X3575207Y-1009234D01*
G01X3583868Y-1008945D02*
X3584626Y-1008801D01*
X3585492Y-1008368D01*
X3586033Y-1007646D01*
X3586250Y-1006635D01*
X3586033Y-1005625D01*
X3585384Y-1004759D01*
X3584409Y-1004326D01*
X3583327D01*
X3582677Y-1004037D01*
X3582136Y-1003315D01*
X3581919Y-1002305D01*
X3582244Y-1001294D01*
X3583002Y-1000573D01*
X3583868Y-1000284D01*
X3584734Y-1000573D01*
X3585492Y-1001294D01*
X3585817Y-1002305D01*
X3585600Y-1003315D01*
X3585059Y-1004037D01*
X3584409Y-1004326D01*
X3583327D01*
X3582352Y-1004759D01*
X3581703Y-1005625D01*
X3581486Y-1006635D01*
X3581703Y-1007646D01*
X3582244Y-1008368D01*
X3583110Y-1008801D01*
X3583868Y-1008945D01*
G01X3592529Y-1000284D02*
X3591663Y-1000573D01*
X3591013Y-1001294D01*
X3590580Y-1002160D01*
X3590255Y-1003315D01*
X3590147Y-1004615D01*
X3590255Y-1005914D01*
X3590580Y-1007069D01*
X3591013Y-1007935D01*
X3591663Y-1008656D01*
X3592529Y-1008945D01*
X3593395Y-1008656D01*
X3594045Y-1007935D01*
X3594478Y-1007069D01*
X3594803Y-1005914D01*
X3594911Y-1004615D01*
X3594803Y-1003315D01*
X3594478Y-1002160D01*
X3594045Y-1001294D01*
X3593395Y-1000573D01*
X3592529Y-1000284D01*
G01X3547728Y285019D02*
Y141712D01*
G01X3558612Y1035423D02*
X3565084Y1041179D01*
X3566883Y1039156D01*
X3567135Y1038221D01*
X3567063Y1037433D01*
X3566344Y1036504D01*
X3565338Y1035898D01*
X3564367Y1035904D01*
X3563539Y1036182D01*
X3561740Y1038205D01*
G01X3563539Y1036182D02*
X3561490Y1032187D01*
G01X3564619Y1030623D02*
X3564512Y1029658D01*
X3564692Y1028804D01*
X3565231Y1027980D01*
X3566095Y1027444D01*
X3567030Y1027261D01*
X3568145Y1027528D01*
X3569079Y1028215D01*
X3569798Y1029144D01*
X3569978Y1030028D01*
X3569906Y1030978D01*
X3569510Y1031640D01*
X3568899Y1032111D01*
X3567820Y1032455D01*
X3570840Y1034706D01*
X3572783Y1032522D01*
G01X3570772Y1021316D02*
X3570736Y1021574D01*
X3570951Y1021766D01*
X3571203Y1021700D01*
X3571239Y1021442D01*
X3571024Y1021250D01*
X3570772Y1021316D01*
G01X3583215Y1020792D02*
X3582424Y1021247D01*
X3581453Y1021253D01*
X3580518Y1021001D01*
X3579439Y1020476D01*
X3578396Y1019694D01*
X3577498Y1018749D01*
X3576850Y1017739D01*
X3576491Y1016840D01*
X3576383Y1015875D01*
X3576743Y1015036D01*
X3577535Y1014581D01*
X3578506Y1014575D01*
X3579441Y1014827D01*
X3580519Y1015351D01*
X3581562Y1016134D01*
X3582461Y1017078D01*
X3583108Y1018088D01*
X3583468Y1018988D01*
X3583575Y1019953D01*
X3583215Y1020792D01*
G01X3588971Y1014320D02*
X3588180Y1014775D01*
X3587209Y1014781D01*
X3586274Y1014529D01*
X3585195Y1014004D01*
X3584152Y1013222D01*
X3583254Y1012277D01*
X3582606Y1011267D01*
X3582247Y1010368D01*
X3582139Y1009403D01*
X3582499Y1008564D01*
X3583291Y1008109D01*
X3584262Y1008103D01*
X3585197Y1008355D01*
X3586275Y1008879D01*
X3587318Y1009662D01*
X3588217Y1010606D01*
X3588864Y1011616D01*
X3589224Y1012516D01*
X3589331Y1013481D01*
X3588971Y1014320D01*
G01X3568972Y-1837784D02*
Y-1856796D01*
G01X3567144Y-1837784D02*
X3650797D01*
G01X3569972Y86200D02*
G03X3570759Y86988I0J787D01*
G01X3569972Y84626D02*
G03X3572334Y86988I0J2362D01*
G01X3574303Y87933D02*
Y137539D01*
G01X3573122Y87145D02*
Y84626D01*
G01Y87145D02*
Y86988D01*
G01X3572334Y87145D02*
Y137539D01*
G01Y86988D02*
Y137539D01*
G01X3570759Y86988D02*
Y144704D01*
G01D02*
Y87145D01*
G01X3567019Y84626D02*
Y86200D01*
G01X3575090Y87145D02*
X3574303Y87933D01*
G01X3616429D02*
X3574303D01*
G01X3572334Y87145D02*
X3619972D01*
G01X3570759D02*
X3619972D01*
G01X3573122Y86988D02*
X3617610D01*
G01X3573122Y86200D02*
X3617610D01*
G01X3567019D02*
X3569972D01*
G01X3573122Y84626D02*
X3617610D01*
G01X3569972D02*
X3567019D01*
G01X3579983Y88793D02*
G03X3581161Y87696I1178J84D01*
G01X3578108Y115045D02*
X3579983Y88793D01*
G01X3570759Y92689D02*
X3572334D01*
G01X3570759Y92651D02*
X3572334D01*
G01X3570759Y92636D02*
X3572334D01*
G01Y92473D02*
X3570759D01*
G01X3578893Y115073D02*
X3580714Y89581D01*
G01X3572334Y112802D02*
X3570759D01*
G01Y112090D02*
X3572334D01*
G01Y112014D02*
X3570759D01*
G01Y111302D02*
X3572334D01*
G01X3574027Y125098D02*
G03I-4527J0D01*
G01X3574539Y129626D02*
Y120570D01*
G01X3564460D02*
Y129626D01*
G01X3574539Y120570D02*
X3564460D01*
G01X3578893Y115073D02*
G03X3578697Y115256I-196J-14D01*
G01X3578304D02*
G03X3578108Y115045I0J-197D01*
G01X3578697Y115256D02*
X3578304D01*
G01X3571547Y125098D02*
X3570759Y123075D01*
G01X3571547Y127380D02*
Y125098D01*
G01Y127380D02*
X3570759Y128981D01*
G01X3564460Y129626D02*
X3574539D01*
G01X3618397Y137539D02*
X3572334D01*
G01X3583161Y135767D02*
G03I-1575J0D01*
G01X3583456D02*
G03I-1870J0D01*
G01X3619972Y144704D02*
X3570759D01*
G01X3580530Y141995D02*
G03Y141011I0J-492D01*
G01X3578562Y142684D02*
G03Y140322I0J-1181D01*
G01X3580530Y141011D02*
X3578562Y140322D01*
G01X3580530Y141995D02*
X3578562Y142684D01*
G01D02*
X3589254D01*
G01Y140322D02*
X3578562D01*
G01X3575300Y532559D02*
X3705510D01*
G01X3572150D02*
X3575300D01*
G01X3568972Y1453929D02*
Y1434916D01*
G01X3595708Y-1293500D02*
G03X3599645Y-1289563I0J3937D01*
G01X3597186Y-1011832D02*
X3596103Y-1010388D01*
X3595562Y-1008945D01*
Y-1003171D01*
X3596103Y-1001727D01*
X3597186Y-1000284D01*
G01X3604114Y-1008945D02*
Y-1000284D01*
G01X3608662D02*
Y-1008945D01*
G01Y-1004615D02*
X3604114D01*
G01X3613642Y-1007357D02*
X3616456D01*
G01Y-1004759D02*
X3613642D01*
G01X3623710Y-1000284D02*
X3622844Y-1000573D01*
X3622194Y-1001294D01*
X3621761Y-1002160D01*
X3621436Y-1003315D01*
X3621328Y-1004615D01*
X3621436Y-1005914D01*
X3621761Y-1007069D01*
X3622194Y-1007935D01*
X3622844Y-1008656D01*
X3623710Y-1008945D01*
X3624576Y-1008656D01*
X3625226Y-1007935D01*
X3625659Y-1007069D01*
X3625984Y-1005914D01*
X3626092Y-1004615D01*
X3625984Y-1003315D01*
X3625659Y-1002160D01*
X3625226Y-1001294D01*
X3624576Y-1000573D01*
X3623710Y-1000284D01*
G01X3629123Y-1008945D02*
Y-1003171D01*
G01Y-1004759D02*
X3629448Y-1004037D01*
X3629989Y-1003460D01*
X3630747Y-1003171D01*
X3631505Y-1003460D01*
X3632046Y-1004037D01*
X3632371Y-1004759D01*
Y-1008945D01*
G01Y-1004759D02*
X3632696Y-1004037D01*
X3633237Y-1003460D01*
X3633995Y-1003171D01*
X3634753Y-1003460D01*
X3635294Y-1004037D01*
X3635619Y-1004903D01*
Y-1008945D01*
G01X3637784D02*
Y-1003171D01*
G01Y-1004759D02*
X3638109Y-1004037D01*
X3638650Y-1003460D01*
X3639408Y-1003171D01*
X3640166Y-1003460D01*
X3640707Y-1004037D01*
X3641032Y-1004759D01*
Y-1008945D01*
G01Y-1004759D02*
X3641357Y-1004037D01*
X3641898Y-1003460D01*
X3642656Y-1003171D01*
X3643414Y-1003460D01*
X3643955Y-1004037D01*
X3644280Y-1004903D01*
Y-1008945D01*
G01X3650234Y-1011832D02*
X3651317Y-1010388D01*
X3651858Y-1008945D01*
Y-1003171D01*
X3651317Y-1001727D01*
X3650234Y-1000284D01*
G01X3580714Y89581D02*
G03X3581892Y88484I1178J84D01*
G01X3584124D02*
G03X3585302Y89581I0J1181D01*
G01X3584855Y87696D02*
G03X3586033Y88793I0J1181D01*
G01X3587908Y115045D02*
X3586033Y88793D01*
G01X3584124Y88484D02*
X3581892D01*
G01X3584855Y87696D02*
X3581161D01*
G01X3587122Y115073D02*
X3585302Y89581D01*
G01X3587319Y115256D02*
G03X3587122Y115073I0J-197D01*
G01X3587908Y115045D02*
G03X3587711Y115256I-197J14D01*
G01D02*
X3587319D01*
G01X3589782Y125671D02*
X3589651Y125604D01*
G01X3588929Y127045D02*
X3589060Y127112D01*
G01X3589716Y125872D02*
X3589618Y125805D01*
G01X3588995Y126844D02*
X3589093Y126911D01*
G01X3589913Y125805D02*
X3589782Y125671D01*
G01X3588798Y126911D02*
X3588929Y127045D01*
G01X3593817Y126207D02*
X3593358Y125570D01*
G01X3593161D02*
X3593719Y126375D01*
G01X3589782Y125972D02*
X3589716Y125872D01*
G01X3588929Y126743D02*
X3588995Y126844D01*
G01X3589979Y125939D02*
X3589913Y125805D01*
G01X3588732Y126777D02*
X3588798Y126911D01*
G01X3588240Y126810D02*
X3587781Y125570D01*
G01X3587649Y125738D02*
X3588141Y127145D01*
G01X3589815Y126107D02*
X3589782Y125972D01*
G01X3588896Y126609D02*
X3588929Y126743D01*
G01X3590011Y126107D02*
X3589979Y125939D01*
G01X3588699Y126609D02*
X3588732Y126777D01*
G01X3592899Y125772D02*
Y125570D01*
G01Y127145D02*
Y126944D01*
G01X3592767Y126509D02*
Y126307D01*
G01X3591915Y126944D02*
Y126509D01*
G01Y126307D02*
Y125772D01*
G01X3591718Y125570D02*
Y127145D01*
G01X3591455Y125772D02*
Y125570D01*
G01X3590471Y127145D02*
Y125772D01*
G01X3590274Y125570D02*
Y127145D01*
G01X3590011Y126609D02*
Y126107D01*
G01X3589815Y126609D02*
Y126107D01*
G01X3588896D02*
Y126609D01*
G01X3588699Y126107D02*
Y126609D01*
G01X3588437Y127145D02*
Y125570D01*
G01X3588240D02*
Y126810D01*
G01X3587059D02*
Y125570D01*
G01X3586862D02*
Y127145D01*
G01X3589979Y126777D02*
X3590011Y126609D01*
G01X3588732Y125939D02*
X3588699Y126107D01*
G01X3589782Y126743D02*
X3589815Y126609D01*
G01X3588929Y125972D02*
X3588896Y126107D01*
G01X3587157Y127145D02*
X3587649Y125738D01*
G01X3587518Y125570D02*
X3587059Y126810D01*
G01X3589913Y126911D02*
X3589979Y126777D01*
G01X3588798Y125805D02*
X3588732Y125939D01*
G01X3589716Y126844D02*
X3589782Y126743D01*
G01X3588995Y125872D02*
X3588929Y125972D01*
G01X3593358Y127145D02*
X3593817Y126509D01*
G01X3593719Y126375D02*
X3593161Y127145D01*
G01X3589782Y127045D02*
X3589913Y126911D01*
G01X3588929Y125671D02*
X3588798Y125805D01*
G01X3589618Y126911D02*
X3589716Y126844D01*
G01X3589093Y125805D02*
X3588995Y125872D01*
G01X3589651Y127112D02*
X3589782Y127045D01*
G01X3589060Y125604D02*
X3588929Y125671D01*
G01X3589487Y126944D02*
X3589618Y126911D01*
G01X3589224Y125772D02*
X3589093Y125805D01*
G01X3589487Y127145D02*
X3589651Y127112D01*
G01X3589224Y125570D02*
X3589060Y125604D01*
G01X3593161Y127145D02*
X3593358D01*
G01X3591718D02*
X3592899D01*
G01X3590274D02*
X3590471D01*
G01X3589224D02*
X3589487D01*
G01X3588141D02*
X3588437D01*
G01X3586862D02*
X3587157D01*
G01X3589224Y126944D02*
X3589487D01*
G01X3592899D02*
X3591915D01*
G01Y126509D02*
X3592767D01*
G01Y126307D02*
X3591915D01*
G01Y125772D02*
X3592899D01*
G01X3590471D02*
X3591455D01*
G01X3589487D02*
X3589224D01*
G01X3587781Y125570D02*
X3587518D01*
G01X3587059D02*
X3586862D01*
G01X3592899D02*
X3591718D01*
G01X3591455D02*
X3590274D01*
G01X3589487D02*
X3589224D01*
G01X3588437D02*
X3588240D01*
G01X3593358D02*
X3593161D01*
G01X3589060Y127112D02*
X3589224Y127145D01*
G01X3589651Y125604D02*
X3589487Y125570D01*
G01X3589093Y126911D02*
X3589224Y126944D01*
G01X3589618Y125805D02*
X3589487Y125772D01*
G01X3593004Y135767D02*
G03I-1575J0D01*
G01X3593299D02*
G03I-1870J0D01*
G01X3591065Y136381D02*
X3591189Y136444D01*
G01X3591220Y136285D02*
X3591127Y136221D01*
G01X3591906Y135839D02*
X3591127Y135139D01*
G01X3590878D02*
X3591750Y135935D01*
G01X3590940Y136253D02*
X3591065Y136381D01*
G01X3581498Y136221D02*
X3581311Y135998D01*
G01Y136253D02*
X3581498Y136476D01*
G01X3591969Y135935D02*
X3591906Y135839D01*
G01X3591127Y136221D02*
X3591065Y136126D01*
G01X3591750Y135935D02*
X3591813Y136062D01*
G01X3592000D02*
X3591969Y135935D01*
G01X3590909Y136126D02*
X3590940Y136253D01*
G01X3592000Y136126D02*
Y136062D01*
G01Y135139D02*
Y134980D01*
G01X3591813Y136062D02*
Y136126D01*
G01X3590878Y134980D02*
Y135139D01*
G01X3581685Y136476D02*
Y134980D01*
G01X3581498D02*
Y136221D01*
G01X3581311Y135998D02*
Y136253D01*
G01X3591969D02*
X3592000Y136126D01*
G01X3591813D02*
X3591750Y136221D01*
G01X3591844Y136381D02*
X3591969Y136253D01*
G01X3591750Y136221D02*
X3591657Y136285D01*
G01X3591719Y136444D02*
X3591844Y136381D01*
G01X3591657Y136285D02*
X3591501Y136317D01*
G01X3591532Y136476D02*
X3591719Y136444D01*
G01X3591407Y136476D02*
X3591532D01*
G01X3581498D02*
X3581685D01*
G01X3591501Y136317D02*
X3591376D01*
G01X3591065Y136126D02*
X3590909D01*
G01X3591127Y135139D02*
X3592000D01*
G01X3581685Y134980D02*
X3581498D01*
G01X3592000D02*
X3590878D01*
G01X3591189Y136444D02*
X3591407Y136476D01*
G01X3591376Y136317D02*
X3591220Y136285D01*
G01X3596672Y126542D02*
X3596475Y126408D01*
G01X3596507Y127011D02*
X3596409Y126877D01*
G01X3594474Y127145D02*
X3593916Y126375D01*
G01X3593817Y126509D02*
X3594277Y127145D01*
G01X3596409Y126877D02*
X3596344Y126710D01*
G01X3596475Y126475D02*
X3596507Y126676D01*
G01X3596344Y126710D02*
X3596311Y126475D01*
G01X3596475Y126408D02*
Y126475D01*
G01X3596311D02*
Y126241D01*
G01D02*
X3596344Y126006D01*
G01D02*
X3596409Y125839D01*
G01X3593916Y126375D02*
X3594474Y125570D01*
G01X3594277D02*
X3593817Y126207D01*
G01X3596409Y125839D02*
X3596507Y125705D01*
G01X3594277Y127145D02*
X3594474D01*
G01Y125570D02*
X3594277D01*
G01X3587285Y141011D02*
G03Y141995I0J492D01*
G01X3589254Y140322D02*
G03Y142684I0J1181D01*
G01X3587285Y141995D02*
X3589254Y142684D01*
G01X3587285Y141011D02*
X3589254Y140322D01*
G01X3580530Y141995D02*
X3587285D01*
G01Y141011D02*
X3580530D01*
G01X3593259Y330351D02*
Y324822D01*
G01X3591783D02*
Y336633D01*
G01X3593259Y324822D02*
X3591783D01*
G01X3593259Y336633D02*
Y331859D01*
G01D02*
X3600149D01*
G01Y330351D02*
X3593259D01*
G01X3591783Y336633D02*
X3593259D01*
G01X3588968Y438934D02*
Y433405D01*
G01X3587492D02*
Y445216D01*
G01X3588968Y433405D02*
X3587492D01*
G01X3595858D02*
Y438934D01*
G01X3597334Y433405D02*
X3595858D01*
G01X3588968Y445216D02*
Y440441D01*
G01D02*
X3595858D01*
G01Y438934D02*
X3588968D01*
G01X3587492Y445216D02*
X3588968D01*
G01X3595858Y440441D02*
Y445216D01*
G01D02*
X3597334D01*
G01X3588508Y534724D02*
Y543385D01*
X3584502Y537178D01*
X3589916D01*
G01X3594463Y537611D02*
X3597277D01*
G01X3596350Y722933D02*
Y746555D01*
G01X3599303Y722933D02*
X3596350D01*
G01Y746555D02*
X3599303D01*
G01X3599645Y-1082870D02*
Y-1289563D01*
G01X3603582Y-1078933D02*
G03X3599645Y-1082870I0J-3937D01*
G01X3682322Y-1078933D02*
X3603582D01*
G01X3605430Y89581D02*
G03X3606608Y88484I1178J84D01*
G01X3608839D02*
G03X3610018Y89581I1J1181D01*
G01X3609571Y87696D02*
G03X3610749Y88793I0J1181D01*
G01X3604699D02*
G03X3605877Y87696I1178J84D01*
G01X3604699Y88793D02*
X3602824Y115045D01*
G01X3606608Y88484D02*
X3608839D01*
G01X3609571Y87696D02*
X3605877D01*
G01X3612624Y115045D02*
X3610749Y88793D01*
G01X3603609Y115073D02*
X3605430Y89581D01*
G01X3610018D02*
X3611839Y115073D01*
G01X3603020Y115256D02*
G03X3602824Y115045I0J-197D01*
G01X3603609Y115073D02*
G03X3603413Y115256I-196J-14D01*
G01X3603020D02*
X3603413D01*
G01X3612035D02*
G03X3611839Y115073I0J-197D01*
G01X3612624Y115045D02*
G03X3612428Y115256I-197J14D01*
G01X3612035D02*
X3612428D01*
G01X3605366Y125671D02*
X3605235Y125604D01*
G01Y125772D02*
X3605300Y125805D01*
G01X3603200Y125671D02*
X3603069Y125604D01*
G01Y125772D02*
X3603135Y125805D01*
G01X3604578Y127045D02*
X3604710Y127112D01*
G01X3602413Y127045D02*
X3602545Y127112D01*
G01X3606645Y125604D02*
X3606809Y125705D01*
G01X3606153Y127112D02*
X3605989Y127011D01*
G01X3600051Y125604D02*
X3600215Y125705D01*
G01X3597164Y125604D02*
X3597328Y125705D01*
G01X3599559Y127112D02*
X3599395Y127011D01*
G01X3596672Y127112D02*
X3596507Y127011D01*
G01X3606711Y125839D02*
X3606613Y125772D01*
G01X3606645Y126174D02*
X3606842Y126307D01*
G01X3606613Y126341D02*
X3606711Y126408D01*
G01X3605464Y125738D02*
X3605366Y125671D01*
G01X3606186Y126944D02*
X3606088Y126877D01*
G01X3603299Y125738D02*
X3603200Y125671D01*
G01X3604743Y126944D02*
X3604644Y126877D01*
G01X3602577Y126944D02*
X3602479Y126877D01*
G01X3600018Y125772D02*
X3600117Y125839D01*
G01X3599592Y126375D02*
X3599493Y126307D01*
G01X3599559Y126542D02*
X3599362Y126408D01*
G01X3599493Y126877D02*
X3599592Y126944D01*
G01X3597131Y125772D02*
X3597230Y125839D01*
G01X3596704Y126375D02*
X3596606Y126307D01*
G01Y126877D02*
X3596704Y126944D01*
G01X3605432Y126475D02*
X3605300Y126375D01*
G01X3603266Y126475D02*
X3603135Y126375D01*
G01X3605300Y125805D02*
X3605366Y125872D01*
G01X3605235Y126509D02*
X3605300Y126576D01*
G01X3604447Y126911D02*
X3604578Y127045D01*
G01X3603135Y125805D02*
X3603200Y125872D01*
G01X3603069Y126509D02*
X3603135Y126576D01*
G01X3602282Y126911D02*
X3602413Y127045D01*
G01X3599493Y126307D02*
X3599428Y126241D01*
G01X3596606Y126307D02*
X3596541Y126241D01*
G01X3600871D02*
X3601429Y126877D01*
G01X3600641Y126241D02*
X3601429Y127145D01*
G01X3608122Y126877D02*
X3607925Y126643D01*
G01Y126911D02*
X3608122Y127145D01*
G01X3607466Y126877D02*
X3607269Y126643D01*
G01Y126911D02*
X3607466Y127145D01*
G01X3606809Y125705D02*
X3606908Y125839D01*
G01X3605989Y127011D02*
X3605891Y126877D01*
G01X3600215Y125705D02*
X3600313Y125839D01*
G01X3599395Y127011D02*
X3599296Y126877D01*
G01X3597328Y125705D02*
X3597426Y125839D01*
G01X3606777Y125939D02*
X3606711Y125839D01*
G01Y126408D02*
X3606777Y126509D01*
G01X3605530Y125839D02*
X3605464Y125738D01*
G01X3606088Y126877D02*
X3606022Y126777D01*
G01X3605497Y126576D02*
X3605432Y126475D01*
G01X3604644Y126877D02*
X3604578Y126777D01*
G01X3603365Y125839D02*
X3603299Y125738D01*
G01X3603332Y126576D02*
X3603266Y126475D01*
G01X3602479Y126877D02*
X3602413Y126777D01*
G01X3600117Y125839D02*
X3600182Y125939D01*
G01X3599428Y126777D02*
X3599493Y126877D01*
G01X3597230Y125839D02*
X3597295Y125939D01*
G01X3596541Y126777D02*
X3596606Y126877D01*
G01X3605366Y125872D02*
X3605399Y125939D01*
G01X3605300Y126576D02*
X3605366Y126710D01*
G01X3603200Y125872D02*
X3603233Y125939D01*
G01X3603135Y126576D02*
X3603200Y126710D01*
G01X3598935Y126978D02*
X3598279Y125570D01*
G01X3598082D02*
X3598739Y126978D01*
G01X3606613Y125772D02*
X3606514Y125738D01*
G01Y126307D02*
X3606613Y126341D01*
G01X3605038Y126442D02*
X3605235Y126509D01*
G01X3606285Y126978D02*
X3606186Y126944D01*
G01X3602872Y126442D02*
X3603069Y126509D01*
G01X3599920Y125738D02*
X3600018Y125772D01*
G01X3599690Y126408D02*
X3599592Y126375D01*
G01X3597033Y125738D02*
X3597131Y125772D01*
G01X3599592Y126944D02*
X3599690Y126978D01*
G01X3596803Y126408D02*
X3596704Y126375D01*
G01Y126944D02*
X3596803Y126978D01*
G01X3606908Y125839D02*
X3606974Y126006D01*
G01X3605891Y126877D02*
X3605825Y126710D01*
G01X3600313Y125839D02*
X3600379Y126006D01*
G01X3599296Y126877D02*
X3599231Y126710D01*
G01X3597426Y125839D02*
X3597492Y126006D01*
G01X3606809Y126040D02*
X3606777Y125939D01*
G01Y126509D02*
X3606809Y126609D01*
G01X3606022Y126777D02*
X3605989Y126676D01*
G01X3605563Y125939D02*
X3605530Y125839D01*
G01X3603397Y125939D02*
X3603365Y125839D01*
G01X3600182Y125939D02*
X3600215Y126040D01*
G01X3599428Y126241D02*
X3599395Y126140D01*
G01Y126676D02*
X3599428Y126777D01*
G01X3597295Y125939D02*
X3597328Y126040D01*
G01X3596541Y126241D02*
X3596507Y126140D01*
G01Y126676D02*
X3596541Y126777D01*
G01X3605530Y126710D02*
X3605497Y126576D01*
G01X3604415Y126777D02*
X3604447Y126911D01*
G01X3603365Y126710D02*
X3603332Y126576D01*
G01X3602249Y126777D02*
X3602282Y126911D01*
G01X3606842Y126241D02*
X3606809Y126040D01*
G01X3599362Y126475D02*
X3599395Y126676D01*
G01X3606974Y126006D02*
X3607006Y126241D01*
G01X3599231Y126710D02*
X3599198Y126475D01*
G01X3608319Y127145D02*
Y125570D01*
G01X3608122D02*
Y126877D01*
G01X3607925Y126643D02*
Y126911D01*
G01X3607663Y127145D02*
Y125570D01*
G01X3607466D02*
Y126877D01*
G01X3607269Y126643D02*
Y126911D01*
G01X3607006Y126241D02*
Y126475D01*
G01X3606842Y126307D02*
Y126241D01*
G01X3606809Y126609D02*
Y126676D01*
G01X3605989D02*
Y126609D01*
G01X3605825Y126710D02*
Y126576D01*
G01X3605563Y126073D02*
Y125939D01*
G01X3605530Y126777D02*
Y126710D01*
G01X3605399Y125939D02*
Y126073D01*
G01X3605366Y126710D02*
Y126777D01*
G01X3604907Y126307D02*
Y126442D01*
G01X3604119Y126307D02*
Y126140D01*
G01X3603660D02*
Y126307D01*
G01X3603397Y126073D02*
Y125939D01*
G01X3603365Y126777D02*
Y126710D01*
G01X3603233Y125939D02*
Y126073D01*
G01X3603200Y126710D02*
Y126777D01*
G01X3607006Y126475D02*
X3606974Y126710D01*
G01X3602741Y126307D02*
Y126442D01*
G01X3601954Y126241D02*
Y126040D01*
G01X3601626Y127145D02*
Y126241D01*
G01Y126040D02*
Y125570D01*
G01X3601429D02*
Y126040D01*
G01Y126877D02*
Y126241D01*
G01X3600641Y126040D02*
Y126241D01*
G01X3600379Y126006D02*
Y126174D01*
G01X3600215Y126040D02*
Y126140D01*
G01X3599395D02*
Y126040D01*
G01X3599362Y126408D02*
Y126475D01*
G01X3599198D02*
Y126241D01*
G01X3598935Y127145D02*
Y126978D01*
G01X3597754D02*
Y127145D01*
G01X3597492Y126006D02*
Y126174D01*
G01X3597328Y126040D02*
Y126140D01*
G01X3596507D02*
Y126040D01*
G01X3599198Y126241D02*
X3599231Y126006D01*
G01X3605497Y126911D02*
X3605530Y126777D01*
G01Y126207D02*
X3605563Y126073D01*
G01X3603332Y126911D02*
X3603365Y126777D01*
G01Y126207D02*
X3603397Y126073D01*
G01X3606809Y126676D02*
X3606777Y126777D01*
G01X3605989Y126609D02*
X3606022Y126509D01*
G01X3605891Y125939D02*
X3605924Y125839D01*
G01X3604415D02*
X3604382Y125939D01*
G01X3602249Y125839D02*
X3602216Y125939D01*
G01X3600313Y126777D02*
X3600281Y126877D01*
G01X3600215Y126140D02*
X3600182Y126241D01*
G01X3599395Y126040D02*
X3599428Y125939D01*
G01X3597426Y126777D02*
X3597393Y126877D01*
G01X3597328Y126140D02*
X3597295Y126241D01*
G01X3596507Y126040D02*
X3596541Y125939D01*
G01X3606974Y126710D02*
X3606908Y126877D01*
G01X3605825Y126576D02*
X3605891Y126408D01*
G01X3600379Y126174D02*
X3600313Y126341D01*
G01X3599231Y126006D02*
X3599296Y125839D01*
G01X3597492Y126174D02*
X3597426Y126341D01*
G01X3605399Y126073D02*
X3605333Y126207D01*
G01X3604546Y125939D02*
X3604578Y125872D01*
G01X3603233Y126073D02*
X3603168Y126207D01*
G01X3602380Y125939D02*
X3602413Y125872D01*
G01X3606777Y126777D02*
X3606711Y126877D01*
G01X3606022Y126509D02*
X3606088Y126408D01*
G01X3606120Y125839D02*
X3606055Y125939D01*
G01X3605366Y126777D02*
X3605300Y126877D01*
G01X3605464Y126307D02*
X3605530Y126207D01*
G01X3604480Y125738D02*
X3604415Y125839D01*
G01X3603200Y126777D02*
X3603135Y126877D01*
G01X3603299Y126307D02*
X3603365Y126207D01*
G01X3602315Y125738D02*
X3602249Y125839D01*
G01X3600084Y126877D02*
X3600149Y126777D01*
G01X3599428Y125939D02*
X3599493Y125839D01*
G01X3597196Y126877D02*
X3597262Y126777D01*
G01X3596541Y125939D02*
X3596606Y125839D01*
G01X3606908Y126877D02*
X3606809Y127011D01*
G01X3605891Y126408D02*
X3605989Y126274D01*
G01X3605924Y125839D02*
X3606022Y125705D01*
G01X3600281Y126877D02*
X3600182Y127011D01*
G01X3599296Y125839D02*
X3599395Y125705D01*
G01X3597393Y126877D02*
X3597295Y127011D01*
G01X3605366Y127045D02*
X3605497Y126911D01*
G01X3604578Y125872D02*
X3604644Y125805D01*
G01X3603200Y127045D02*
X3603332Y126911D01*
G01X3602413Y125872D02*
X3602479Y125805D01*
G01X3600313Y126341D02*
X3600215Y126442D01*
G01X3600182Y126241D02*
X3600117Y126307D01*
G01X3597426Y126341D02*
X3597328Y126442D01*
G01X3597295Y126241D02*
X3597230Y126307D01*
G01X3606711Y126877D02*
X3606613Y126944D01*
G01X3606088Y126408D02*
X3606186Y126341D01*
G01X3605300Y126877D02*
X3605202Y126944D01*
G01X3606219Y125772D02*
X3606120Y125839D01*
G01X3605333Y126207D02*
X3605235Y126274D01*
G01X3603135Y126877D02*
X3603037Y126944D01*
G01X3604578Y125671D02*
X3604480Y125738D01*
G01X3603168Y126207D02*
X3603069Y126274D01*
G01X3602413Y125671D02*
X3602315Y125738D01*
G01X3599985Y126944D02*
X3600084Y126877D01*
G01X3600117Y126307D02*
X3600018Y126375D01*
G01X3599493Y125839D02*
X3599592Y125772D01*
G01X3597098Y126944D02*
X3597196Y126877D01*
G01X3597230Y126307D02*
X3597131Y126375D01*
G01X3596606Y125839D02*
X3596704Y125772D01*
G01X3606809Y127011D02*
X3606645Y127112D01*
G01X3605989Y126274D02*
X3606153Y126174D01*
G01X3606022Y125705D02*
X3606186Y125604D01*
G01X3600182Y127011D02*
X3600018Y127112D01*
G01X3600215Y126442D02*
X3600051Y126542D01*
G01X3597295Y127011D02*
X3597131Y127112D01*
G01X3599395Y125705D02*
X3599559Y125604D01*
G01X3597328Y126442D02*
X3597164Y126542D01*
G01X3596507Y125705D02*
X3596672Y125604D01*
G01X3605235Y127112D02*
X3605366Y127045D01*
G01X3603069Y127112D02*
X3603200Y127045D01*
G01X3604644Y125805D02*
X3604710Y125772D01*
G01Y125604D02*
X3604578Y125671D01*
G01X3602479Y125805D02*
X3602545Y125772D01*
G01Y125604D02*
X3602413Y125671D01*
G01X3605300Y126375D02*
X3605464Y126307D01*
G01X3603135Y126375D02*
X3603299Y126307D01*
G01X3606613Y126944D02*
X3606514Y126978D01*
G01X3606186Y126341D02*
X3606285Y126307D01*
G01X3606317Y125738D02*
X3606219Y125772D01*
G01X3599887Y126978D02*
X3599985Y126944D01*
G01X3600018Y126375D02*
X3599920Y126408D01*
G01X3597000Y126978D02*
X3597098Y126944D01*
G01X3599592Y125772D02*
X3599690Y125738D01*
G01X3597131Y126375D02*
X3597033Y126408D01*
G01X3596704Y125772D02*
X3596803Y125738D01*
G01X3604841Y125570D02*
X3604710Y125604D01*
G01X3602676Y125570D02*
X3602545Y125604D01*
G01X3606645Y127112D02*
X3606482Y127145D01*
G01X3605202Y126944D02*
X3605038Y126978D01*
G01X3603037Y126944D02*
X3602872Y126978D01*
G01X3606153Y126174D02*
X3606317Y126140D01*
G01X3600018Y127112D02*
X3599854Y127145D01*
G01X3606186Y125604D02*
X3606350Y125570D01*
G01X3604710Y125772D02*
X3604874Y125738D01*
G01X3600051Y126542D02*
X3599887Y126576D01*
G01X3597131Y127112D02*
X3596967Y127145D01*
G01X3602545Y125772D02*
X3602708Y125738D01*
G01X3597164Y126542D02*
X3597000Y126576D01*
G01X3599559Y125604D02*
X3599723Y125570D01*
G01X3596672Y125604D02*
X3596836Y125570D01*
G01X3605235Y126274D02*
X3605038Y126307D01*
G01X3603069Y126274D02*
X3602872Y126307D01*
G01X3605005Y127145D02*
X3605235Y127112D01*
G01X3602840Y127145D02*
X3603069Y127112D01*
G01X3608122Y127145D02*
X3608319D01*
G01X3607466D02*
X3607663D01*
G01X3604939D02*
X3605005D01*
G01X3602774D02*
X3602840D01*
G01X3601429D02*
X3601626D01*
G01X3597754D02*
X3598935D01*
G01X3596967D02*
X3596836D01*
G01X3599854D02*
X3599723D01*
G01X3606482D02*
X3606317D01*
G01X3599690Y126978D02*
X3599887D01*
G01X3596803D02*
X3597000D01*
G01X3598739D02*
X3597754D01*
G01X3606514D02*
X3606285D01*
G01X3605038D02*
X3604907D01*
G01X3602872D02*
X3602741D01*
G01X3600149Y126777D02*
X3600313D01*
G01X3597262D02*
X3597426D01*
G01X3604578D02*
X3604415D01*
G01X3602413D02*
X3602249D01*
G01X3597000Y126576D02*
X3596836D01*
G01X3599887D02*
X3599723D01*
G01X3604907Y126442D02*
X3605038D01*
G01X3602741D02*
X3602872D01*
G01X3597033Y126408D02*
X3596803D01*
G01X3599920D02*
X3599690D01*
G01X3606285Y126307D02*
X3606514D01*
G01X3603660D02*
X3604119D01*
G01X3605038D02*
X3604907D01*
G01X3602872D02*
X3602741D01*
G01X3601626Y126241D02*
X3601954D01*
G01X3601429D02*
X3600871D01*
G01X3606317Y126140D02*
X3606482D01*
G01X3604119D02*
X3603660D01*
G01X3601429Y126040D02*
X3600641D01*
G01X3601954D02*
X3601626D01*
G01X3604382Y125939D02*
X3604546D01*
G01X3602216D02*
X3602380D01*
G01X3606055D02*
X3605891D01*
G01X3604874Y125738D02*
X3605070D01*
G01X3602708D02*
X3602905D01*
G01X3599690D02*
X3599920D01*
G01X3596803D02*
X3597033D01*
G01X3606514D02*
X3606317D01*
G01X3606350Y125570D02*
X3606482D01*
G01X3599723D02*
X3599887D01*
G01X3596836D02*
X3597000D01*
G01X3601626D02*
X3601429D01*
G01X3598279D02*
X3598082D01*
G01X3605104D02*
X3604841D01*
G01X3602938D02*
X3602676D01*
G01X3608319D02*
X3608122D01*
G01X3607663D02*
X3607466D01*
G01X3602545Y127112D02*
X3602774Y127145D01*
G01X3604710Y127112D02*
X3604939Y127145D01*
G01X3596836D02*
X3596672Y127112D01*
G01X3596836Y126576D02*
X3596672Y126542D01*
G01X3599723Y127145D02*
X3599559Y127112D01*
G01X3599723Y126576D02*
X3599559Y126542D01*
G01X3602741Y126978D02*
X3602577Y126944D01*
G01X3597000Y125570D02*
X3597164Y125604D01*
G01X3604907Y126978D02*
X3604743Y126944D01*
G01X3606317Y127145D02*
X3606153Y127112D01*
G01X3599887Y125570D02*
X3600051Y125604D01*
G01X3602905Y125738D02*
X3603069Y125772D01*
G01X3606482Y126140D02*
X3606645Y126174D01*
G01X3605070Y125738D02*
X3605235Y125772D01*
G01X3606482Y125570D02*
X3606645Y125604D01*
G01X3603069D02*
X3602938Y125570D01*
G01X3605235Y125604D02*
X3605104Y125570D01*
G01X3610720Y135767D02*
G03I-1575J0D01*
G01X3611015D02*
G03I-1870J0D01*
G01X3600878D02*
G03I-1575J0D01*
G01X3601173D02*
G03I-1870J0D01*
G01X3603446Y141995D02*
G03Y141011I0J-492D01*
G01X3601478Y142684D02*
G03Y140322I0J-1181D01*
G01X3603446Y141011D02*
X3601478Y140322D01*
G01X3603446Y141995D02*
X3601478Y142684D01*
G01X3612170D02*
X3601478D01*
G01X3610202Y141995D02*
X3603446D01*
G01Y141011D02*
X3610202D01*
G01X3601478Y140322D02*
X3612170D01*
G01X3610202Y141011D02*
G03Y141995I-1J492D01*
G01X3612170Y140322D02*
G03Y142684I0J1181D01*
G01X3610202Y141995D02*
X3612170Y142684D01*
G01X3610202Y141011D02*
X3612170Y140322D01*
G01X3609500Y329848D02*
X3615405Y336633D01*
G01X3609500Y328341D02*
Y329848D01*
G01X3607531D02*
Y328843D01*
G01X3603594D02*
Y329848D01*
G01X3601626Y336633D02*
Y324822D01*
G01X3600149D02*
Y330351D01*
G01X3603594Y329848D02*
X3607531D01*
G01Y328843D02*
X3603594D01*
G01X3615405Y328341D02*
X3609500D01*
G01X3601626Y324822D02*
X3600149D01*
G01X3607531Y332864D02*
Y331859D01*
G01X3603594D02*
Y332864D01*
G01X3600149Y331859D02*
Y336633D01*
G01X3603594Y332864D02*
X3607531D01*
G01Y331859D02*
X3603594D01*
G01X3611222Y329848D02*
X3615405Y334623D01*
G01Y329848D02*
X3611222D01*
G01X3600149Y336633D02*
X3601626D01*
G01X3608161Y445216D02*
Y433405D01*
G01X3606685D02*
Y443206D01*
G01X3597334Y445216D02*
Y433405D01*
G01X3608161D02*
X3606685D01*
G01X3611360Y434662D02*
Y433405D01*
G01X3610130D02*
Y434662D01*
G01X3611360Y433405D02*
X3610130D01*
G01X3605208Y441447D02*
Y443457D01*
G01X3603240Y438431D02*
Y437426D01*
G01Y441447D02*
Y440441D01*
G01X3606685Y443206D02*
X3605208Y441447D01*
G01Y443457D02*
X3606685Y445216D01*
G01X3599303Y440441D02*
Y441447D01*
G01Y437426D02*
Y438431D01*
G01Y441447D02*
X3603240D01*
G01Y440441D02*
X3599303D01*
G01Y438431D02*
X3603240D01*
G01Y437426D02*
X3599303D01*
G01X3606685Y445216D02*
X3608161D01*
G01X3610130Y434662D02*
X3611360D01*
G01X3600959Y534724D02*
Y540498D01*
G01Y539054D02*
X3601393Y539776D01*
X3602042Y540354D01*
X3602908Y540498D01*
X3603666Y540354D01*
X3604316Y539776D01*
X3604641Y538766D01*
Y534724D01*
G01X3614348D02*
X3615106Y534868D01*
X3615972Y535301D01*
X3616513Y536023D01*
X3616730Y537034D01*
X3616513Y538044D01*
X3615864Y538910D01*
X3614889Y539343D01*
X3613807D01*
X3613157Y539632D01*
X3612616Y540354D01*
X3612399Y541364D01*
X3612724Y542375D01*
X3613482Y543096D01*
X3614348Y543385D01*
X3615214Y543096D01*
X3615972Y542375D01*
X3616297Y541364D01*
X3616080Y540354D01*
X3615539Y539632D01*
X3614889Y539343D01*
X3613807D01*
X3612832Y538910D01*
X3612183Y538044D01*
X3611966Y537034D01*
X3612183Y536023D01*
X3612724Y535301D01*
X3613590Y534868D01*
X3614348Y534724D01*
G01X3623009Y534435D02*
X3622792Y534580D01*
Y534868D01*
X3623009Y535013D01*
X3623226Y534868D01*
Y534580D01*
X3623009Y534435D01*
G01X3631670Y534724D02*
X3632428Y534868D01*
X3633294Y535301D01*
X3633835Y536023D01*
X3634052Y537034D01*
X3633835Y538044D01*
X3633186Y538910D01*
X3632211Y539343D01*
X3631129D01*
X3630479Y539632D01*
X3629938Y540354D01*
X3629721Y541364D01*
X3630046Y542375D01*
X3630804Y543096D01*
X3631670Y543385D01*
X3632536Y543096D01*
X3633294Y542375D01*
X3633619Y541364D01*
X3633402Y540354D01*
X3632861Y539632D01*
X3632211Y539343D01*
X3631129D01*
X3630154Y538910D01*
X3629505Y538044D01*
X3629288Y537034D01*
X3629505Y536023D01*
X3630046Y535301D01*
X3630912Y534868D01*
X3631670Y534724D01*
G01X3640331Y543385D02*
X3639465Y543096D01*
X3638815Y542375D01*
X3638382Y541509D01*
X3638057Y540354D01*
X3637949Y539054D01*
X3638057Y537755D01*
X3638382Y536600D01*
X3638815Y535734D01*
X3639465Y535013D01*
X3640331Y534724D01*
X3641197Y535013D01*
X3641847Y535734D01*
X3642280Y536600D01*
X3642605Y537755D01*
X3642713Y539054D01*
X3642605Y540354D01*
X3642280Y541509D01*
X3641847Y542375D01*
X3641197Y543096D01*
X3640331Y543385D01*
G01X3599303Y733990D02*
Y722933D01*
G01Y746555D02*
Y737006D01*
G01D02*
X3613082D01*
G01Y733990D02*
X3599303D01*
G01X3608751Y866318D02*
Y874979D01*
X3607452Y873247D01*
G01Y866318D02*
X3610050D01*
G01X3615571Y867328D02*
X3616329Y866607D01*
X3617195Y866318D01*
X3618062Y866607D01*
X3618819Y867473D01*
X3619361Y868772D01*
X3619577Y870071D01*
Y871659D01*
X3619361Y872958D01*
X3618819Y874113D01*
X3618170Y874690D01*
X3617412Y874979D01*
X3616546Y874690D01*
X3615896Y874113D01*
X3615463Y873247D01*
X3615247Y872092D01*
X3615463Y871082D01*
X3616005Y870071D01*
X3616654Y869494D01*
X3617412Y869349D01*
X3618278Y869638D01*
X3618928Y870360D01*
X3619577Y871659D01*
G01X3624016Y869927D02*
X3624774Y870937D01*
X3625423Y871515D01*
X3626290Y871803D01*
X3627047Y871515D01*
X3627589Y870937D01*
X3628022Y870071D01*
X3628130Y869061D01*
X3628022Y868194D01*
X3627589Y867328D01*
X3626939Y866607D01*
X3626181Y866318D01*
X3625315Y866607D01*
X3624557Y867473D01*
X3624124Y868772D01*
X3624016Y870215D01*
X3624232Y872092D01*
X3624557Y873103D01*
X3625099Y874113D01*
X3625856Y874835D01*
X3626614Y874979D01*
X3627372Y874690D01*
X3627914Y873969D01*
G01X3634734Y866029D02*
X3634517Y866174D01*
Y866462D01*
X3634734Y866607D01*
X3634951Y866462D01*
Y866174D01*
X3634734Y866029D01*
G01X3643395Y874979D02*
X3642529Y874690D01*
X3641879Y873969D01*
X3641446Y873103D01*
X3641121Y871948D01*
X3641013Y870648D01*
X3641121Y869349D01*
X3641446Y868194D01*
X3641879Y867328D01*
X3642529Y866607D01*
X3643395Y866318D01*
X3644261Y866607D01*
X3644911Y867328D01*
X3645344Y868194D01*
X3645669Y869349D01*
X3645777Y870648D01*
X3645669Y871948D01*
X3645344Y873103D01*
X3644911Y873969D01*
X3644261Y874690D01*
X3643395Y874979D01*
G01X3652056D02*
X3651190Y874690D01*
X3650540Y873969D01*
X3650107Y873103D01*
X3649782Y871948D01*
X3649674Y870648D01*
X3649782Y869349D01*
X3650107Y868194D01*
X3650540Y867328D01*
X3651190Y866607D01*
X3652056Y866318D01*
X3652922Y866607D01*
X3653572Y867328D01*
X3654005Y868194D01*
X3654330Y869349D01*
X3654438Y870648D01*
X3654330Y871948D01*
X3654005Y873103D01*
X3653572Y873969D01*
X3652922Y874690D01*
X3652056Y874979D01*
G01X3627262Y-24419D02*
X3626397Y-23769D01*
X3625963Y-23012D01*
X3625819Y-22145D01*
X3626108Y-21063D01*
X3626829Y-20305D01*
X3627695Y-20088D01*
X3628562Y-20197D01*
X3629283Y-20630D01*
X3630727Y-22795D01*
X3631737Y-23769D01*
X3633181Y-24419D01*
X3634480Y-24636D01*
Y-20088D01*
G01Y-13701D02*
X3634336Y-12943D01*
X3633903Y-12077D01*
X3633181Y-11536D01*
X3632170Y-11319D01*
X3631160Y-11536D01*
X3630294Y-12185D01*
X3629861Y-13160D01*
Y-14242D01*
X3629572Y-14892D01*
X3628850Y-15433D01*
X3627840Y-15650D01*
X3626829Y-15325D01*
X3626108Y-14567D01*
X3625819Y-13701D01*
X3626108Y-12835D01*
X3626829Y-12077D01*
X3627840Y-11752D01*
X3628850Y-11969D01*
X3629572Y-12510D01*
X3629861Y-13160D01*
Y-14242D01*
X3630294Y-15217D01*
X3631160Y-15866D01*
X3632170Y-16083D01*
X3633181Y-15866D01*
X3633903Y-15325D01*
X3634336Y-14459D01*
X3634480Y-13701D01*
G01X3627262Y-7097D02*
X3626397Y-6447D01*
X3625963Y-5690D01*
X3625819Y-4823D01*
X3626108Y-3741D01*
X3626829Y-2983D01*
X3627695Y-2766D01*
X3628562Y-2875D01*
X3629283Y-3308D01*
X3630727Y-5473D01*
X3631737Y-6447D01*
X3633181Y-7097D01*
X3634480Y-7314D01*
Y-2766D01*
G01X3634769Y3621D02*
X3634624Y3404D01*
X3634336D01*
X3634191Y3621D01*
X3634336Y3838D01*
X3634624D01*
X3634769Y3621D01*
G01X3634480Y13581D02*
X3625819D01*
X3632026Y9575D01*
Y14989D01*
G01X3633470Y19102D02*
X3634191Y19860D01*
X3634480Y20726D01*
X3634191Y21593D01*
X3633325Y22350D01*
X3632026Y22892D01*
X3630727Y23108D01*
X3629139D01*
X3627840Y22892D01*
X3626685Y22350D01*
X3626108Y21701D01*
X3625819Y20943D01*
X3626108Y20077D01*
X3626685Y19427D01*
X3627551Y18994D01*
X3628706Y18778D01*
X3629716Y18994D01*
X3630727Y19536D01*
X3631304Y20185D01*
X3631449Y20943D01*
X3631160Y21809D01*
X3630438Y22459D01*
X3629139Y23108D01*
G01X3619972Y86988D02*
G03X3620759Y86200I788J0D01*
G01X3618397Y86988D02*
G03X3620759Y84626I2362J0D01*
G01X3615641Y87145D02*
X3616429Y87933D01*
G01X3623712Y84626D02*
Y86200D01*
G01X3619972Y87145D02*
Y144704D01*
G01Y87145D02*
Y144704D01*
G01Y86988D02*
Y87145D01*
G01X3618397Y86988D02*
Y137539D01*
G01X3617610Y87145D02*
Y84626D01*
G01Y87145D02*
Y86988D01*
G01X3616429Y87933D02*
Y137539D01*
G01X3623712Y86200D02*
X3620759D01*
G01Y84626D02*
X3623712D01*
G01X3618397Y112802D02*
Y92473D01*
G01X3619972Y92689D02*
X3618397D01*
G01X3619972Y92651D02*
X3618397D01*
G01X3619972Y92636D02*
X3618397D01*
G01X3619972Y92473D02*
X3618397D01*
G01X3619972Y112802D02*
X3618397D01*
G01X3619972Y112090D02*
X3618397D01*
G01X3619972Y112014D02*
X3618397D01*
G01X3619972Y111302D02*
X3618397D01*
G01X3625759Y125098D02*
G03I-4527J0D01*
G01X3616193Y120570D02*
Y129626D01*
G01X3626271Y120570D02*
X3616193D01*
G01X3626271Y129626D02*
Y120570D01*
G01X3619185Y127380D02*
X3619972Y128981D01*
G01X3619185Y127380D02*
Y125098D01*
G01D02*
X3619972Y123075D01*
G01X3616193Y129626D02*
X3626271D01*
G01X3622594Y251909D02*
X3623244Y250899D01*
X3624110Y250321D01*
X3625084Y250177D01*
X3625950Y250321D01*
X3626817Y251043D01*
X3627358Y251909D01*
X3627466Y252775D01*
X3627250Y253786D01*
X3626492Y254507D01*
X3625734Y254796D01*
X3624759D01*
G01X3625734D02*
X3626383Y255229D01*
X3626925Y255951D01*
X3627141Y256817D01*
X3626925Y257683D01*
X3626383Y258405D01*
X3625409Y258838D01*
X3624435Y258694D01*
X3623460Y258116D01*
G01X3631796Y251187D02*
X3632554Y250466D01*
X3633420Y250177D01*
X3634287Y250466D01*
X3635044Y251332D01*
X3635586Y252631D01*
X3635802Y253930D01*
Y255518D01*
X3635586Y256817D01*
X3635044Y257972D01*
X3634395Y258549D01*
X3633637Y258838D01*
X3632771Y258549D01*
X3632121Y257972D01*
X3631688Y257106D01*
X3631472Y255951D01*
X3631688Y254941D01*
X3632230Y253930D01*
X3632879Y253353D01*
X3633637Y253208D01*
X3634503Y253497D01*
X3635153Y254219D01*
X3635802Y255518D01*
G01X3642298Y249888D02*
X3642081Y250033D01*
Y250321D01*
X3642298Y250466D01*
X3642515Y250321D01*
Y250033D01*
X3642298Y249888D01*
G01X3648577Y251476D02*
X3649227Y250754D01*
X3649985Y250321D01*
X3650959Y250177D01*
X3651933Y250466D01*
X3652691Y251043D01*
X3653233Y252053D01*
X3653341Y253208D01*
X3653124Y254363D01*
X3652583Y255085D01*
X3651825Y255662D01*
X3651067Y255807D01*
X3650309Y255662D01*
X3649335Y255085D01*
X3649660Y258838D01*
X3652583D01*
G01X3659620D02*
X3658754Y258549D01*
X3658104Y257828D01*
X3657671Y256962D01*
X3657346Y255807D01*
X3657238Y254507D01*
X3657346Y253208D01*
X3657671Y252053D01*
X3658104Y251187D01*
X3658754Y250466D01*
X3659620Y250177D01*
X3660486Y250466D01*
X3661136Y251187D01*
X3661569Y252053D01*
X3661894Y253208D01*
X3662002Y254507D01*
X3661894Y255807D01*
X3661569Y256962D01*
X3661136Y257828D01*
X3660486Y258549D01*
X3659620Y258838D01*
G01X3625248Y324822D02*
Y330854D01*
G01X3622541Y331105D02*
Y324822D01*
G01X3621311D02*
Y332864D01*
G01X3619342Y329848D02*
Y328341D01*
G01X3616882D02*
Y324822D01*
G01Y336633D02*
Y329848D01*
G01X3615405Y324822D02*
Y328341D01*
G01Y334623D02*
Y329848D01*
G01X3616882D02*
X3619342D01*
G01Y328341D02*
X3616882D01*
G01Y324822D02*
X3615405D01*
G01X3622541D02*
X3621311D01*
G01X3626478D02*
X3625248D01*
G01X3626232Y331859D02*
X3626970Y332613D01*
G01X3623033Y331607D02*
X3622541Y331105D01*
G01Y332110D02*
X3623033Y332613D01*
G01X3622541Y332864D02*
Y332110D01*
G01X3625248Y330854D02*
X3625002Y331356D01*
G01X3623771Y331859D02*
X3623033Y331607D01*
G01Y332613D02*
X3623771Y332864D01*
G01X3625494Y332613D02*
X3626232Y331859D01*
G01X3625002Y331356D02*
X3624756Y331607D01*
G01D02*
X3624263Y331859D01*
G01X3624756Y332864D02*
X3625494Y332613D01*
G01X3621311Y332864D02*
X3622541D01*
G01X3623771D02*
X3624756D01*
G01X3624263Y331859D02*
X3623771D01*
G01X3629185Y324822D02*
Y330854D01*
G01X3626478D02*
Y324822D01*
G01X3630415D02*
X3629185D01*
G01X3626724Y331356D02*
X3626478Y330854D01*
G01X3626970Y331607D02*
X3626724Y331356D01*
G01X3627462Y331859D02*
X3626970Y331607D01*
G01X3629185Y330854D02*
X3628939Y331356D01*
G01X3626970Y332613D02*
X3627708Y332864D01*
G01X3628939Y331356D02*
X3628693Y331607D01*
G01D02*
X3628200Y331859D01*
G01X3628693Y332864D02*
X3629431Y332613D01*
G01X3627708Y332864D02*
X3628693D01*
G01X3628200Y331859D02*
X3627462D01*
G01X3615405Y336633D02*
X3616882D01*
G01X3625385Y439688D02*
Y433405D01*
G01X3624155D02*
Y441447D01*
G01X3622187Y434662D02*
Y433405D01*
G01X3613328D02*
Y434662D01*
G01X3622187Y433405D02*
X3613328D01*
G01X3625385D02*
X3624155D01*
G01X3628092D02*
Y439436D01*
G01X3629322Y433405D02*
X3628092D01*
G01X3620218Y440944D02*
X3620710Y441949D01*
G01X3622187D02*
X3621941Y440944D01*
G01X3613574Y442452D02*
X3613820Y443457D01*
G01X3625385Y441447D02*
Y440693D01*
G01X3622187Y442452D02*
Y441949D01*
G01X3620710D02*
Y442452D01*
G01X3621941Y443457D02*
X3622187Y442452D01*
G01X3621448Y440190D02*
X3615297Y434662D01*
G01X3613328D02*
X3620218Y440944D01*
G01X3625878Y440190D02*
X3625385Y439688D01*
G01Y440693D02*
X3625878Y441195D01*
G01X3613820Y443457D02*
X3614805Y444462D01*
G01X3621941Y440944D02*
X3621448Y440190D01*
G01X3615297Y443206D02*
X3614805Y442452D01*
G01X3620710D02*
X3620218Y443206D01*
G01X3616035Y443708D02*
X3615297Y443206D01*
G01X3620956Y444462D02*
X3621941Y443457D01*
G01X3626616Y440441D02*
X3625878Y440190D01*
G01Y441195D02*
X3626616Y441447D01*
G01X3614805Y444462D02*
X3615789Y444965D01*
G01X3620218Y443206D02*
X3619480Y443708D01*
G01X3619972Y444965D02*
X3620956Y444462D01*
G01X3619480Y443708D02*
X3618250Y443960D01*
G01X3618496Y445216D02*
X3619972Y444965D01*
G01X3618250Y443960D02*
X3617265D01*
G01X3614805Y442452D02*
X3613574D01*
G01X3624155Y441447D02*
X3625385D01*
G01X3615297Y434662D02*
X3622187D01*
G01X3615789Y444965D02*
X3617511Y445216D01*
G01X3617265Y443960D02*
X3616035Y443708D01*
G01X3617511Y445216D02*
X3618496D01*
G01X3628092Y439436D02*
X3627846Y439939D01*
G01X3629076Y440441D02*
X3629815Y441195D01*
G01X3628338D02*
X3629076Y440441D01*
G01X3627846Y439939D02*
X3627600Y440190D01*
G01D02*
X3627108Y440441D01*
G01X3627600Y441447D02*
X3628338Y441195D01*
G01X3626616Y441447D02*
X3627600D01*
G01X3627108Y440441D02*
X3626616D01*
G01X3616035Y746555D02*
Y722933D01*
G01X3613082D02*
Y733990D01*
G01X3616035Y722933D02*
X3613082D01*
G01X3619972Y737006D02*
Y739016D01*
G01Y730974D02*
Y732985D01*
G01X3613082Y737006D02*
Y746555D01*
G01X3619972Y739016D02*
X3627846D01*
G01Y737006D02*
X3619972D01*
G01Y732985D02*
X3627846D01*
G01Y730974D02*
X3619972D01*
G01X3627846Y732985D02*
Y730974D01*
G01Y739016D02*
Y737006D01*
G01X3613082Y746555D02*
X3616035D01*
G01X3633741Y-1777616D02*
Y-1582095D01*
G01X3636645Y92500D02*
Y28521D01*
G01X3632708Y92500D02*
G03X3636645Y96437I0J3937D01*
G01Y303130D02*
Y96437D01*
G01X3640582Y307067D02*
G03X3636645Y303130I0J-3937D01*
G01X3719322Y307067D02*
X3640582D01*
G01X3641488Y330854D02*
Y324822D01*
G01X3640257D02*
Y330854D01*
G01X3637551D02*
Y324822D01*
G01X3636320D02*
Y330854D01*
G01X3633614Y331105D02*
Y324822D01*
G01X3632383D02*
Y332864D01*
G01X3630415Y330854D02*
Y324822D01*
G01X3633614D02*
X3632383D01*
G01X3637551D02*
X3636320D01*
G01X3641488D02*
X3640257D01*
G01X3637797Y331356D02*
X3637551Y330854D01*
G01X3638043Y331607D02*
X3637797Y331356D01*
G01X3637305Y331859D02*
X3638043Y332613D01*
G01X3634106Y331607D02*
X3633614Y331105D01*
G01Y332110D02*
X3634106Y332613D01*
G01X3633614Y332864D02*
Y332110D01*
G01X3640996D02*
X3641488Y330854D01*
G01X3638535Y331859D02*
X3638043Y331607D01*
G01X3629923Y332110D02*
X3630415Y330854D01*
G01X3640257D02*
X3640011Y331356D01*
G01X3636320Y330854D02*
X3636074Y331356D01*
G01X3638043Y332613D02*
X3638781Y332864D01*
G01X3634844Y331859D02*
X3634106Y331607D01*
G01Y332613D02*
X3634844Y332864D01*
G01X3640504Y332613D02*
X3640996Y332110D01*
G01X3640011Y331356D02*
X3639765Y331607D01*
G01X3636567Y332613D02*
X3637305Y331859D01*
G01X3636074Y331356D02*
X3635828Y331607D01*
G01X3629431Y332613D02*
X3629923Y332110D01*
G01X3639765Y331607D02*
X3639273Y331859D01*
G01X3635828Y331607D02*
X3635336Y331859D01*
G01X3639765Y332864D02*
X3640504Y332613D01*
G01X3635828Y332864D02*
X3636567Y332613D01*
G01X3634844Y332864D02*
X3635828D01*
G01X3638781D02*
X3639765D01*
G01X3632383D02*
X3633614D01*
G01X3639273Y331859D02*
X3638535D01*
G01X3635336D02*
X3634844D01*
G01X3640395Y439436D02*
Y433405D01*
G01X3639165D02*
Y439436D01*
G01X3636458Y439688D02*
Y433405D01*
G01X3635228D02*
Y441447D01*
G01X3633259Y439436D02*
Y433405D01*
G01X3632029D02*
Y439436D01*
G01X3629322D02*
Y433405D01*
G01X3633259D02*
X3632029D01*
G01X3636458D02*
X3635228D01*
G01X3640395D02*
X3639165D01*
G01X3644332Y439436D02*
Y433405D01*
G01X3643102D02*
Y439436D01*
G01X3644332Y433405D02*
X3643102D01*
G01X3640641Y439939D02*
X3640395Y439436D01*
G01X3629569Y439939D02*
X3629322Y439436D01*
G01X3636458Y441447D02*
Y440693D01*
G01X3632767D02*
X3633259Y439436D01*
G01X3639165D02*
X3638919Y439939D01*
G01X3632029Y439436D02*
X3631783Y439939D01*
G01X3640887Y440190D02*
X3640641Y439939D01*
G01X3640149Y440441D02*
X3640887Y441195D01*
G01X3636950Y440190D02*
X3636458Y439688D01*
G01Y440693D02*
X3636950Y441195D01*
G01X3629815Y440190D02*
X3629569Y439939D01*
G01X3641380Y440441D02*
X3640887Y440190D01*
G01X3642856Y439939D02*
X3642610Y440190D01*
G01X3639411Y441195D02*
X3640149Y440441D01*
G01X3638919Y439939D02*
X3638673Y440190D01*
G01X3632275Y441195D02*
X3632767Y440693D01*
G01X3631783Y439939D02*
X3631537Y440190D01*
G01X3640887Y441195D02*
X3641626Y441447D01*
G01X3637689Y440441D02*
X3636950Y440190D01*
G01Y441195D02*
X3637689Y441447D01*
G01X3629815Y441195D02*
X3630553Y441447D01*
G01X3630307Y440441D02*
X3629815Y440190D01*
G01X3642610D02*
X3642118Y440441D01*
G01X3638673Y440190D02*
X3638181Y440441D01*
G01X3631537Y440190D02*
X3631045Y440441D01*
G01X3642610Y441447D02*
X3643348Y441195D01*
G01X3638673Y441447D02*
X3639411Y441195D01*
G01X3631537Y441447D02*
X3632275Y441195D01*
G01X3641626Y441447D02*
X3642610D01*
G01X3635228D02*
X3636458D01*
G01X3637689D02*
X3638673D01*
G01X3630553D02*
X3631537D01*
G01X3631045Y440441D02*
X3630307D01*
G01X3638181D02*
X3637689D01*
G01X3642118D02*
X3641380D01*
G01X3643840Y440693D02*
X3644332Y439436D01*
G01X3643102D02*
X3642856Y439939D01*
G01X3643348Y441195D02*
X3643840Y440693D01*
G01X3644989Y531837D02*
X3643906Y533281D01*
X3643365Y534724D01*
Y540498D01*
X3643906Y541942D01*
X3644989Y543385D01*
G01X3651917Y534724D02*
Y543385D01*
G01X3656465D02*
Y534724D01*
G01Y539054D02*
X3651917D01*
G01X3661445Y536312D02*
X3664259D01*
G01Y538910D02*
X3661445D01*
G01X3671513Y543385D02*
X3670647Y543096D01*
X3669997Y542375D01*
X3669564Y541509D01*
X3669239Y540354D01*
X3669131Y539054D01*
X3669239Y537755D01*
X3669564Y536600D01*
X3669997Y535734D01*
X3670647Y535013D01*
X3671513Y534724D01*
X3672379Y535013D01*
X3673029Y535734D01*
X3673462Y536600D01*
X3673787Y537755D01*
X3673895Y539054D01*
X3673787Y540354D01*
X3673462Y541509D01*
X3673029Y542375D01*
X3672379Y543096D01*
X3671513Y543385D01*
G01X3676926Y534724D02*
Y540498D01*
G01Y538910D02*
X3677251Y539632D01*
X3677792Y540209D01*
X3678550Y540498D01*
X3679308Y540209D01*
X3679849Y539632D01*
X3680174Y538910D01*
Y534724D01*
G01Y538910D02*
X3680499Y539632D01*
X3681040Y540209D01*
X3681798Y540498D01*
X3682556Y540209D01*
X3683097Y539632D01*
X3683422Y538766D01*
Y534724D01*
G01X3685587D02*
Y540498D01*
G01Y538910D02*
X3685912Y539632D01*
X3686453Y540209D01*
X3687211Y540498D01*
X3687969Y540209D01*
X3688510Y539632D01*
X3688835Y538910D01*
Y534724D01*
G01Y538910D02*
X3689160Y539632D01*
X3689701Y540209D01*
X3690459Y540498D01*
X3691217Y540209D01*
X3691758Y539632D01*
X3692083Y538766D01*
Y534724D01*
G01X3698037Y531837D02*
X3699120Y533281D01*
X3699661Y534724D01*
Y540498D01*
X3699120Y541942D01*
X3698037Y543385D01*
G01X3631783Y722933D02*
Y725446D01*
G01X3649500Y722933D02*
X3631783D01*
G01X3635720Y725446D02*
X3649500D01*
G01X3648023Y736503D02*
X3635720Y725446D01*
G01X3631783D02*
X3645563Y738011D01*
G01X3632275Y741026D02*
X3632767Y743037D01*
G01X3644086Y743539D02*
X3641626Y744042D01*
G01D02*
X3639657D01*
G01X3634736Y741026D02*
X3632275D01*
G01X3635720Y742534D02*
X3634736Y741026D01*
G01X3639657Y744042D02*
X3637196Y743539D01*
G01X3632767Y743037D02*
X3634736Y745047D01*
G01X3637196Y743539D02*
X3635720Y742534D01*
G01X3634736Y745047D02*
X3636704Y746052D01*
G01X3645563Y738011D02*
X3646547Y740021D01*
G01Y741026D02*
X3645563Y742534D01*
G01D02*
X3644086Y743539D01*
G01X3645070Y746052D02*
X3647039Y745047D01*
G01X3642118Y746555D02*
X3645070Y746052D01*
G01X3640149Y746555D02*
X3642118D01*
G01X3636704Y746052D02*
X3640149Y746555D01*
G01X3650797Y-1837784D02*
X3682357D01*
G01X3659140Y-1627710D02*
Y-1602710D01*
G01X3672370D02*
Y-1627710D01*
G01Y-1615210D02*
X3659140D01*
G01X3690955Y-1627710D02*
X3688435Y-1627293D01*
X3686230Y-1625627D01*
X3684340Y-1623127D01*
X3683080Y-1620210D01*
X3682450Y-1616877D01*
Y-1613543D01*
X3683080Y-1610210D01*
X3684340Y-1607293D01*
X3686230Y-1604794D01*
X3688435Y-1603127D01*
X3690955Y-1602710D01*
X3693475Y-1603127D01*
X3695680Y-1604794D01*
X3697570Y-1607293D01*
X3698830Y-1610210D01*
X3699460Y-1613543D01*
Y-1616877D01*
X3698830Y-1620210D01*
X3697570Y-1623127D01*
X3695680Y-1625627D01*
X3693475Y-1627293D01*
X3690955Y-1627710D01*
G01X3708910D02*
Y-1602710D01*
X3723400Y-1627710D01*
Y-1602710D01*
G01X3747655Y-1627710D02*
X3735055D01*
Y-1602710D01*
X3747655D01*
G01X3742615Y-1614793D02*
X3735055D01*
G01X3766555Y-1627710D02*
Y-1616460D01*
X3760255Y-1602710D01*
G01X3772855D02*
X3766555Y-1616460D01*
G01X3819475Y-1614376D02*
X3820735Y-1613127D01*
X3821680Y-1611044D01*
X3822310Y-1608126D01*
X3821680Y-1605627D01*
X3820420Y-1603960D01*
X3818215Y-1602710D01*
X3809710D01*
Y-1627710D01*
X3820105D01*
X3822310Y-1626044D01*
X3823570Y-1623543D01*
X3824200Y-1620627D01*
X3823570Y-1617711D01*
X3821680Y-1615210D01*
X3819475Y-1614376D01*
X3809710D01*
G01X3834280Y-1627710D02*
X3842155Y-1602710D01*
X3850030Y-1627710D01*
G01X3847195Y-1618960D02*
X3837115D01*
G01X3860425Y-1627710D02*
Y-1602710D01*
X3866725D01*
X3869245Y-1603960D01*
X3871135Y-1605627D01*
X3872710Y-1608126D01*
X3873970Y-1611044D01*
X3874285Y-1615210D01*
X3873970Y-1619377D01*
X3872710Y-1622294D01*
X3871135Y-1624794D01*
X3869245Y-1626460D01*
X3866725Y-1627710D01*
X3860425D01*
G01X3894445Y-1615210D02*
X3900745D01*
Y-1622710D01*
X3898855Y-1625211D01*
X3896650Y-1626877D01*
X3893500Y-1627710D01*
X3890350Y-1626877D01*
X3888145Y-1625211D01*
X3886255Y-1622710D01*
X3884995Y-1619793D01*
X3884365Y-1616460D01*
Y-1613543D01*
X3884995Y-1611044D01*
X3886255Y-1608126D01*
X3888145Y-1605627D01*
X3890035Y-1603960D01*
X3892555Y-1602710D01*
X3894760D01*
X3897280Y-1603543D01*
X3899170Y-1605210D01*
G01X3924055Y-1627710D02*
X3911455D01*
Y-1602710D01*
X3924055D01*
G01X3919015Y-1614793D02*
X3911455D01*
G01X3936655Y-1627710D02*
Y-1602710D01*
X3944530D01*
X3947050Y-1603960D01*
X3948625Y-1605627D01*
X3949255Y-1608960D01*
X3948625Y-1612294D01*
X3946735Y-1614376D01*
X3944530Y-1615627D01*
X3936655D01*
G01X3944530D02*
X3949255Y-1627710D01*
G01X3995875Y-1614376D02*
X3997135Y-1613127D01*
X3998080Y-1611044D01*
X3998710Y-1608126D01*
X3998080Y-1605627D01*
X3996820Y-1603960D01*
X3994615Y-1602710D01*
X3986110D01*
Y-1627710D01*
X3996505D01*
X3998710Y-1626044D01*
X3999970Y-1623543D01*
X4000600Y-1620627D01*
X3999970Y-1617711D01*
X3998080Y-1615210D01*
X3995875Y-1614376D01*
X3986110D01*
G01X4010680Y-1627710D02*
X4018555Y-1602710D01*
X4026430Y-1627710D01*
G01X4023595Y-1618960D02*
X4013515D01*
G01X4037140Y-1624377D02*
X4039660Y-1626460D01*
X4042495Y-1627710D01*
X4045015D01*
X4047535Y-1626460D01*
X4049425Y-1624377D01*
X4050370Y-1621460D01*
X4049740Y-1618544D01*
X4048165Y-1616044D01*
X4045330Y-1614376D01*
X4041550Y-1613543D01*
X4039345Y-1611877D01*
X4038400Y-1608960D01*
X4039030Y-1606043D01*
X4040605Y-1603960D01*
X4042810Y-1602710D01*
X4045015D01*
X4047220Y-1603543D01*
X4049110Y-1605627D01*
G01X4075255Y-1627710D02*
X4062655D01*
Y-1602710D01*
X4075255D01*
G01X4070215Y-1614793D02*
X4062655D01*
G01X4096675Y-1614376D02*
X4097935Y-1613127D01*
X4098880Y-1611044D01*
X4099510Y-1608126D01*
X4098880Y-1605627D01*
X4097620Y-1603960D01*
X4095415Y-1602710D01*
X4086910D01*
Y-1627710D01*
X4097305D01*
X4099510Y-1626044D01*
X4100770Y-1623543D01*
X4101400Y-1620627D01*
X4100770Y-1617711D01*
X4098880Y-1615210D01*
X4096675Y-1614376D01*
X4086910D01*
G01X4119355Y-1627710D02*
X4116835Y-1627293D01*
X4114630Y-1625627D01*
X4112740Y-1623127D01*
X4111480Y-1620210D01*
X4110850Y-1616877D01*
Y-1613543D01*
X4111480Y-1610210D01*
X4112740Y-1607293D01*
X4114630Y-1604794D01*
X4116835Y-1603127D01*
X4119355Y-1602710D01*
X4121875Y-1603127D01*
X4124080Y-1604794D01*
X4125970Y-1607293D01*
X4127230Y-1610210D01*
X4127860Y-1613543D01*
Y-1616877D01*
X4127230Y-1620210D01*
X4125970Y-1623127D01*
X4124080Y-1625627D01*
X4121875Y-1627293D01*
X4119355Y-1627710D01*
G01X4136680D02*
X4144555Y-1602710D01*
X4152430Y-1627710D01*
G01X4149595Y-1618960D02*
X4139515D01*
G01X4163455Y-1627710D02*
Y-1602710D01*
X4171330D01*
X4173850Y-1603960D01*
X4175425Y-1605627D01*
X4176055Y-1608960D01*
X4175425Y-1612294D01*
X4173535Y-1614376D01*
X4171330Y-1615627D01*
X4163455D01*
G01X4171330D02*
X4176055Y-1627710D01*
G01X4188025D02*
Y-1602710D01*
X4194325D01*
X4196845Y-1603960D01*
X4198735Y-1605627D01*
X4200310Y-1608126D01*
X4201570Y-1611044D01*
X4201885Y-1615210D01*
X4201570Y-1619377D01*
X4200310Y-1622294D01*
X4198735Y-1624794D01*
X4196845Y-1626460D01*
X4194325Y-1627710D01*
X4188025D01*
G01X3655897Y725446D02*
Y722933D01*
G01X3653437D02*
Y725446D01*
G01X3649500D02*
Y722933D01*
G01X3655897D02*
X3653437D01*
G01Y725446D02*
X3655897D01*
G01X3649500Y741026D02*
Y740021D01*
G01X3646547D02*
Y741026D01*
G01X3649500Y740021D02*
X3649007Y738011D01*
G01D02*
X3648023Y736503D01*
G01X3649007Y743037D02*
X3649500Y741026D01*
G01X3647039Y745047D02*
X3649007Y743037D01*
G01X3659834Y739016D02*
Y743037D01*
G01X3662787Y742534D02*
X3659834Y739016D01*
G01Y743037D02*
X3662787Y746555D01*
G01X3675915Y-1852994D02*
Y-1841587D01*
X3674204Y-1843868D01*
G01Y-1852994D02*
X3677626D01*
G01X3684899Y-1851663D02*
X3685897Y-1852614D01*
X3687038Y-1852994D01*
X3688179Y-1852614D01*
X3689177Y-1851473D01*
X3689890Y-1849762D01*
X3690175Y-1848051D01*
Y-1845960D01*
X3689890Y-1844249D01*
X3689177Y-1842728D01*
X3688321Y-1841967D01*
X3687323Y-1841587D01*
X3686182Y-1841967D01*
X3685327Y-1842728D01*
X3684756Y-1843868D01*
X3684471Y-1845390D01*
X3684756Y-1846720D01*
X3685469Y-1848051D01*
X3686325Y-1848812D01*
X3687323Y-1849002D01*
X3688464Y-1848622D01*
X3689319Y-1847671D01*
X3690175Y-1845960D01*
G01X3665208Y-1746577D02*
Y-1766577D01*
X3675208D01*
G01X3690208D02*
Y-1757577D01*
X3685208Y-1746577D01*
G01X3695208D02*
X3690208Y-1757577D01*
G01X3704458Y-1766577D02*
Y-1746577D01*
X3715958Y-1766577D01*
Y-1746577D01*
G01X3724458Y-1766577D02*
Y-1746577D01*
X3735958Y-1766577D01*
Y-1746577D01*
G01X3675956Y-1673655D02*
Y-1653655D01*
X3672956Y-1657655D01*
G01Y-1673655D02*
X3678956D01*
G01X3690456Y-1669655D02*
X3691956Y-1671989D01*
X3693956Y-1673322D01*
X3696206Y-1673655D01*
X3698206Y-1673322D01*
X3700206Y-1671655D01*
X3701456Y-1669655D01*
X3701706Y-1667655D01*
X3701206Y-1665322D01*
X3699456Y-1663655D01*
X3697706Y-1662988D01*
X3695456D01*
G01X3697706D02*
X3699206Y-1661988D01*
X3700456Y-1660322D01*
X3700956Y-1658322D01*
X3700456Y-1656322D01*
X3699206Y-1654655D01*
X3696956Y-1653655D01*
X3694706Y-1653988D01*
X3692456Y-1655322D01*
G01X3711706Y-1671322D02*
X3713456Y-1672988D01*
X3715456Y-1673655D01*
X3717456Y-1672988D01*
X3719206Y-1670989D01*
X3720456Y-1667988D01*
X3720956Y-1664988D01*
Y-1661322D01*
X3720456Y-1658322D01*
X3719206Y-1655655D01*
X3717706Y-1654322D01*
X3715956Y-1653655D01*
X3713956Y-1654322D01*
X3712456Y-1655655D01*
X3711456Y-1657655D01*
X3710956Y-1660322D01*
X3711456Y-1662655D01*
X3712706Y-1664988D01*
X3714206Y-1666322D01*
X3715956Y-1666655D01*
X3717956Y-1665989D01*
X3719456Y-1664322D01*
X3720956Y-1661322D01*
G01X3738956Y-1673655D02*
Y-1653655D01*
X3729706Y-1667988D01*
X3742206D01*
G01X3755956Y-1673655D02*
X3757706Y-1673322D01*
X3759706Y-1672322D01*
X3760956Y-1670656D01*
X3761456Y-1668322D01*
X3760956Y-1665989D01*
X3759456Y-1663989D01*
X3757206Y-1662988D01*
X3754706D01*
X3753206Y-1662322D01*
X3751956Y-1660655D01*
X3751456Y-1658322D01*
X3752206Y-1655988D01*
X3753956Y-1654322D01*
X3755956Y-1653655D01*
X3757956Y-1654322D01*
X3759706Y-1655988D01*
X3760456Y-1658322D01*
X3759956Y-1660655D01*
X3758706Y-1662322D01*
X3757206Y-1662988D01*
X3754706D01*
X3752456Y-1663989D01*
X3750956Y-1665989D01*
X3750456Y-1668322D01*
X3750956Y-1670656D01*
X3752206Y-1672322D01*
X3754206Y-1673322D01*
X3755956Y-1673655D01*
G01X3750878Y248011D02*
X3667199D01*
G01X3672630Y722933D02*
Y742534D01*
G01X3665740Y746555D02*
Y722933D01*
G01X3662787D02*
Y742534D01*
G01X3665740Y722933D02*
X3662787D01*
G01X3675582D02*
X3672630D01*
G01X3675582Y746555D02*
Y722933D01*
G01X3669677Y739016D02*
Y743037D01*
G01X3672630Y742534D02*
X3669677Y739016D01*
G01Y743037D02*
X3672630Y746555D01*
G01D02*
X3675582D01*
G01X3662787D02*
X3665740D01*
G01X3675915Y1438719D02*
Y1450126D01*
X3674204Y1447845D01*
G01Y1438719D02*
X3677626D01*
G01X3684899Y1440050D02*
X3685897Y1439099D01*
X3687038Y1438719D01*
X3688179Y1439099D01*
X3689177Y1440240D01*
X3689890Y1441951D01*
X3690175Y1443662D01*
Y1445753D01*
X3689890Y1447464D01*
X3689177Y1448985D01*
X3688321Y1449746D01*
X3687323Y1450126D01*
X3686182Y1449746D01*
X3685327Y1448985D01*
X3684756Y1447845D01*
X3684471Y1446323D01*
X3684756Y1444993D01*
X3685469Y1443662D01*
X3686325Y1442901D01*
X3687323Y1442711D01*
X3688464Y1443091D01*
X3689319Y1444042D01*
X3690175Y1445753D01*
G01X3694133Y-1289563D02*
G03X3698070Y-1293500I3937J0D01*
G01X3694133Y-1122240D02*
Y-1289563D01*
G01X3686259Y-1114366D02*
G03X3690196Y-1118303I3937J0D01*
G01X3686259Y-1114366D02*
Y-1082870D01*
G01X3694133Y-1122240D02*
G03X3690196Y-1118303I-3937J0D01*
G01X3686259Y-1082870D02*
G03X3682322Y-1078933I-3937J0D01*
G01X3689854Y734995D02*
Y722933D01*
G01X3687393D02*
Y734995D01*
G01X3681980Y735498D02*
Y722933D01*
G01X3679519D02*
Y739016D01*
G01X3681980Y722933D02*
X3679519D01*
G01X3689854D02*
X3687393D01*
G01Y734995D02*
X3686901Y736000D01*
G01X3687885Y738513D02*
X3689362Y737006D01*
G01X3686901Y736000D02*
X3686409Y736503D01*
G01X3681980Y739016D02*
Y737508D01*
G01X3686409Y736503D02*
X3685425Y737006D01*
G01X3686409Y739016D02*
X3687885Y738513D01*
G01X3690346Y736000D02*
X3689854Y734995D01*
G01X3684441Y739016D02*
X3686409D01*
G01X3679519D02*
X3681980D01*
G01X3685425Y737006D02*
X3684441D01*
G01X3693299D02*
X3691822D01*
G01X3690838Y736503D02*
X3690346Y736000D01*
G01X3689362Y737006D02*
X3690838Y738513D01*
G01X3682964Y736503D02*
X3681980Y735498D01*
G01Y737508D02*
X3682964Y738513D01*
G01X3691822Y737006D02*
X3690838Y736503D01*
G01Y738513D02*
X3692315Y739016D01*
G01X3684441Y737006D02*
X3682964Y736503D01*
G01Y738513D02*
X3684441Y739016D01*
G01X3695267Y734995D02*
X3694775Y736000D01*
G01D02*
X3694283Y736503D01*
G01D02*
X3693299Y737006D01*
G01X3694283Y739016D02*
X3695759Y738513D01*
G01X3692315Y739016D02*
X3694283D01*
G01X3698070Y-1293500D02*
X3883563D01*
G01X3731988Y-1137988D02*
G03I-17323J0D01*
G01X3711515Y-1131689D02*
G03Y-1144287I0J-6299D01*
G01X3731988Y-882082D02*
G03I-17323J0D01*
G01X3711515Y-875783D02*
G03Y-888381I0J-6299D01*
G01X3704126Y735498D02*
Y722933D01*
G01X3701665D02*
Y739016D01*
G01X3697728Y734995D02*
Y722933D01*
G01X3695267D02*
Y734995D01*
G01X3697728Y722933D02*
X3695267D01*
G01X3704126D02*
X3701665D01*
G01X3709539D02*
Y734995D01*
G01X3712000Y722933D02*
X3709539D01*
G01X3696744Y737508D02*
X3697728Y734995D01*
G01X3695759Y738513D02*
X3696744Y737508D01*
G01X3704126Y739016D02*
Y737508D01*
G01X3708555Y736503D02*
X3707570Y737006D01*
G01X3706586Y739016D02*
X3708555D01*
G01X3701665D02*
X3704126D01*
G01X3707570Y737006D02*
X3706586D01*
G01X3705110Y736503D02*
X3704126Y735498D01*
G01Y737508D02*
X3705110Y738513D01*
G01X3706586Y737006D02*
X3705110Y736503D01*
G01Y738513D02*
X3706586Y739016D01*
G01X3709539Y734995D02*
X3709047Y736000D01*
G01X3710031Y738513D02*
X3711507Y737006D01*
G01X3709047Y736000D02*
X3708555Y736503D01*
G01Y739016D02*
X3710031Y738513D01*
G01X3717814Y-1144287D02*
G03Y-1131689I0J6299D01*
G01X3711515Y-1144287D02*
X3717814D01*
G01Y-1131689D02*
X3711515D01*
G01X3833490Y-1089796D02*
X3726666D01*
G01X3717814Y-888381D02*
G03Y-875783I0J6299D01*
G01X3711515Y-888381D02*
X3717814D01*
G01Y-875783D02*
X3711515D01*
G01X3727236Y-24744D02*
X3728246Y-24094D01*
X3728824Y-23228D01*
X3728968Y-22254D01*
X3728824Y-21388D01*
X3728102Y-20521D01*
X3727236Y-19980D01*
X3726370Y-19872D01*
X3725359Y-20088D01*
X3724638Y-20846D01*
X3724349Y-21604D01*
Y-22579D01*
G01Y-21604D02*
X3723916Y-20955D01*
X3723194Y-20413D01*
X3722328Y-20197D01*
X3721462Y-20413D01*
X3720740Y-20955D01*
X3720307Y-21929D01*
X3720451Y-22903D01*
X3721029Y-23878D01*
G01X3720307Y-13701D02*
X3720596Y-14567D01*
X3721317Y-15217D01*
X3722183Y-15650D01*
X3723338Y-15975D01*
X3724638Y-16083D01*
X3725937Y-15975D01*
X3727092Y-15650D01*
X3727958Y-15217D01*
X3728679Y-14567D01*
X3728968Y-13701D01*
X3728679Y-12835D01*
X3727958Y-12185D01*
X3727092Y-11752D01*
X3725937Y-11427D01*
X3724638Y-11319D01*
X3723338Y-11427D01*
X3722183Y-11752D01*
X3721317Y-12185D01*
X3720596Y-12835D01*
X3720307Y-13701D01*
G01X3725359Y-7097D02*
X3724349Y-6339D01*
X3723771Y-5690D01*
X3723483Y-4823D01*
X3723771Y-4066D01*
X3724349Y-3524D01*
X3725215Y-3091D01*
X3726225Y-2983D01*
X3727092Y-3091D01*
X3727958Y-3524D01*
X3728679Y-4174D01*
X3728968Y-4932D01*
X3728679Y-5798D01*
X3727813Y-6556D01*
X3726514Y-6989D01*
X3725071Y-7097D01*
X3723194Y-6881D01*
X3722183Y-6556D01*
X3721173Y-6014D01*
X3720451Y-5257D01*
X3720307Y-4499D01*
X3720596Y-3741D01*
X3721317Y-3199D01*
G01X3729257Y3621D02*
X3729112Y3404D01*
X3728824D01*
X3728679Y3621D01*
X3728824Y3838D01*
X3729112D01*
X3729257Y3621D01*
G01X3728968Y13581D02*
X3720307D01*
X3726514Y9575D01*
Y14989D01*
G01X3727958Y19102D02*
X3728679Y19860D01*
X3728968Y20726D01*
X3728679Y21593D01*
X3727813Y22350D01*
X3726514Y22892D01*
X3725215Y23108D01*
X3723627D01*
X3722328Y22892D01*
X3721173Y22350D01*
X3720596Y21701D01*
X3720307Y20943D01*
X3720596Y20077D01*
X3721173Y19427D01*
X3722039Y18994D01*
X3723194Y18778D01*
X3724204Y18994D01*
X3725215Y19536D01*
X3725792Y20185D01*
X3725937Y20943D01*
X3725648Y21809D01*
X3724926Y22459D01*
X3723627Y23108D01*
G01X3723259Y271633D02*
G03X3727196Y267696I3937J0D01*
G01X3731133Y263759D02*
G03X3727196Y267696I-3937J0D01*
G01X3723259Y271633D02*
Y303130D01*
G01D02*
G03X3719322Y307067I-3937J0D01*
G01X3719874Y734995D02*
Y722933D01*
G01X3717413D02*
Y734995D01*
G01X3712000D02*
Y722933D01*
G01X3719874D02*
X3717413D01*
G01X3718889Y737508D02*
X3719874Y734995D01*
G01X3717413D02*
X3716921Y736000D01*
G01X3717905Y738513D02*
X3718889Y737508D01*
G01X3716921Y736000D02*
X3716429Y736503D01*
G01D02*
X3715445Y737006D01*
G01X3716429Y739016D02*
X3717905Y738513D01*
G01X3712492Y736000D02*
X3712000Y734995D01*
G01X3714460Y739016D02*
X3716429D01*
G01X3715445Y737006D02*
X3713968D01*
G01X3712984Y736503D02*
X3712492Y736000D01*
G01X3711507Y737006D02*
X3712984Y738513D01*
G01X3713968Y737006D02*
X3712984Y736503D01*
G01Y738513D02*
X3714460Y739016D01*
G01X3844470Y-1135883D02*
X3737646D01*
G01X3836930Y-1119585D02*
X3737901D01*
G01X3741786Y-1087631D02*
Y-1081857D01*
G01Y-1083301D02*
X3742220Y-1082579D01*
X3742869Y-1082001D01*
X3743735Y-1081857D01*
X3744493Y-1082001D01*
X3745143Y-1082579D01*
X3745468Y-1083589D01*
Y-1087631D01*
G01X3834284Y-1061188D02*
X3735255D01*
G01X3731133Y92500D02*
Y28521D01*
G01Y96437D02*
G03X3735070Y92500I3937J0D01*
G01X3731133Y263759D02*
Y96437D01*
G01X3735070Y92500D02*
X3920563D01*
G01X3762163Y261791D02*
G03Y234232I-10498J-13780D01*
G01X3748515Y254311D02*
G03Y241712I0J-6300D01*
G01X3736704Y272027D02*
G03X3738673Y270059I1969J1D01*
G01X3736704Y272027D02*
Y279409D01*
G01X3742019D02*
X3736704D01*
G01X3760326Y277834D02*
X3736704D01*
G01X3744578Y270059D02*
X3738673D01*
G01X3737689Y282460D02*
Y283641D01*
G01Y286791D02*
Y285610D01*
G01D02*
X3745563D01*
G01Y283641D02*
X3737689D01*
G01X3745563Y282460D02*
X3737689D01*
G01X3742019Y274881D02*
G03X3742807Y274094I788J1D01*
G01X3741232Y274881D02*
G03X3742807Y273307I1575J1D01*
G01Y274094D02*
Y273307D01*
G01X3742019Y274881D02*
Y477047D01*
G01X3741232D02*
Y274881D01*
G01D02*
X3742019D01*
G01X3747137Y274094D02*
X3742807D01*
G01X3747137Y273307D02*
X3742807D01*
G01X3737689Y289941D02*
Y288759D01*
G01Y293090D02*
Y291909D01*
G01Y296240D02*
Y295059D01*
G01X3745563Y296240D02*
X3737689D01*
G01Y295059D02*
X3745563D01*
G01Y293090D02*
X3737689D01*
G01Y291909D02*
X3745563D01*
G01Y289941D02*
X3737689D01*
G01Y288759D02*
X3745563D01*
G01Y286791D02*
X3737689D01*
G01Y299389D02*
Y298208D01*
G01Y302539D02*
Y301358D01*
G01X3745563Y302539D02*
X3737689D01*
G01Y301358D02*
X3745563D01*
G01Y299389D02*
X3737689D01*
G01Y298208D02*
X3745563D01*
G01X3737689Y305689D02*
Y304507D01*
G01Y308838D02*
Y307657D01*
G01Y311988D02*
Y310807D01*
G01X3745563Y311988D02*
X3737689D01*
G01Y310807D02*
X3745563D01*
G01Y308838D02*
X3737689D01*
G01Y307657D02*
X3745563D01*
G01Y305689D02*
X3737689D01*
G01Y304507D02*
X3745563D01*
G01X3737689Y315137D02*
Y313956D01*
G01Y318287D02*
Y317106D01*
G01X3745563Y318287D02*
X3737689D01*
G01Y317106D02*
X3745563D01*
G01Y315137D02*
X3737689D01*
G01Y313956D02*
X3745563D01*
G01X3737689Y321437D02*
Y320256D01*
G01Y324586D02*
Y323405D01*
G01Y327736D02*
Y326555D01*
G01Y330885D02*
Y329704D01*
G01D02*
X3745563D01*
G01Y327736D02*
X3737689D01*
G01Y326555D02*
X3745563D01*
G01Y324586D02*
X3737689D01*
G01Y323405D02*
X3745563D01*
G01Y321437D02*
X3737689D01*
G01Y320256D02*
X3745563D01*
G01X3737689Y334035D02*
Y332854D01*
G01X3745563Y334035D02*
X3737689D01*
G01Y332854D02*
X3745563D01*
G01Y330885D02*
X3737689D01*
G01Y337185D02*
Y336004D01*
G01Y340334D02*
Y339153D01*
G01Y343484D02*
Y342303D01*
G01Y346633D02*
Y345452D01*
G01D02*
X3745563D01*
G01Y343484D02*
X3737689D01*
G01Y342303D02*
X3745563D01*
G01Y340334D02*
X3737689D01*
G01Y339153D02*
X3745563D01*
G01Y337185D02*
X3737689D01*
G01Y336004D02*
X3745563D01*
G01X3737689Y349783D02*
Y348602D01*
G01Y352933D02*
Y351752D01*
G01D02*
X3745563D01*
G01Y349783D02*
X3737689D01*
G01Y348602D02*
X3745563D01*
G01Y346633D02*
X3737689D01*
G01X3742019Y342893D02*
X3741232D01*
G01Y336594D02*
X3742019D01*
G01X3737689Y356082D02*
Y354901D01*
G01Y359232D02*
Y358051D01*
G01Y362381D02*
Y361200D01*
G01X3745563Y362381D02*
X3737689D01*
G01Y361200D02*
X3745563D01*
G01Y359232D02*
X3737689D01*
G01Y358051D02*
X3745563D01*
G01Y356082D02*
X3737689D01*
G01Y354901D02*
X3745563D01*
G01Y352933D02*
X3737689D01*
G01Y365531D02*
Y364350D01*
G01Y368681D02*
Y367500D01*
G01D02*
X3745563D01*
G01Y365531D02*
X3737689D01*
G01Y364350D02*
X3745563D01*
G01X3742019Y358641D02*
X3741232D01*
G01Y352342D02*
X3742019D01*
G01X3737689Y371830D02*
Y370649D01*
G01Y374980D02*
Y373799D01*
G01Y378130D02*
Y376948D01*
G01X3745563Y378130D02*
X3737689D01*
G01Y376948D02*
X3745563D01*
G01Y374980D02*
X3737689D01*
G01Y373799D02*
X3745563D01*
G01Y371830D02*
X3737689D01*
G01Y370649D02*
X3745563D01*
G01Y368681D02*
X3737689D01*
G01Y381279D02*
Y380098D01*
G01Y384429D02*
Y383248D01*
G01X3745563Y384429D02*
X3737689D01*
G01Y383248D02*
X3745563D01*
G01Y381279D02*
X3737689D01*
G01Y380098D02*
X3745563D01*
G01X3742059Y376637D02*
Y371998D01*
G01Y371047D02*
Y370333D01*
G01Y381870D02*
Y377588D01*
G01X3742019Y378064D02*
X3742059D01*
G01X3742019Y377588D02*
X3742059D01*
G01X3742019Y376637D02*
X3742059D01*
G01X3742019Y376518D02*
X3742059D01*
G01X3742019Y376280D02*
X3742059D01*
G01X3742019Y375923D02*
X3742059D01*
G01X3742019Y375804D02*
X3742059D01*
G01X3742019Y375567D02*
X3742059D01*
G01X3742019Y375329D02*
X3742059D01*
G01X3742019Y375209D02*
X3742059D01*
G01Y374734D02*
X3742019D01*
G01Y373663D02*
X3742059D01*
G01X3742019Y373188D02*
X3742059D01*
G01X3742019Y373069D02*
X3742059D01*
G01X3742019Y372831D02*
X3742059D01*
G01X3742019Y372712D02*
X3742059D01*
G01X3742019Y372593D02*
X3742059D01*
G01X3742019Y372117D02*
X3742059D01*
G01X3742019Y371998D02*
X3742059D01*
G01Y371047D02*
X3742019D01*
G01Y370333D02*
X3742059D01*
G01Y381870D02*
X3742019D01*
G01X3742059Y381156D02*
X3742019D01*
G01X3737689Y387578D02*
Y386397D01*
G01Y390728D02*
Y389547D01*
G01Y393878D02*
Y392696D01*
G01X3745563Y393878D02*
X3737689D01*
G01Y392696D02*
X3745563D01*
G01Y390728D02*
X3737689D01*
G01Y389547D02*
X3745563D01*
G01Y387578D02*
X3737689D01*
G01Y386397D02*
X3745563D01*
G01X3737689Y397027D02*
Y395846D01*
G01Y400177D02*
Y398996D01*
G01X3745563Y400177D02*
X3737689D01*
G01Y398996D02*
X3745563D01*
G01Y397027D02*
X3737689D01*
G01Y395846D02*
X3745563D01*
G01X3741232Y393287D02*
X3742019D01*
G01Y399586D02*
X3741232D01*
G01X3737689Y403326D02*
Y402145D01*
G01Y406476D02*
Y405295D01*
G01Y409626D02*
Y408444D01*
G01Y412775D02*
Y411594D01*
G01D02*
X3745563D01*
G01Y409626D02*
X3737689D01*
G01Y408444D02*
X3745563D01*
G01Y406476D02*
X3737689D01*
G01Y405295D02*
X3745563D01*
G01Y403326D02*
X3737689D01*
G01Y402145D02*
X3745563D01*
G01X3737689Y415925D02*
Y414744D01*
G01X3745563Y415925D02*
X3737689D01*
G01Y414744D02*
X3745563D01*
G01Y412775D02*
X3737689D01*
G01X3741232Y409035D02*
X3742019D01*
G01Y415334D02*
X3741232D01*
G01X3737689Y419074D02*
Y417893D01*
G01Y422224D02*
Y421043D01*
G01Y425374D02*
Y424193D01*
G01Y428523D02*
Y427342D01*
G01X3745563Y428523D02*
X3737689D01*
G01Y427342D02*
X3745563D01*
G01Y425374D02*
X3737689D01*
G01Y424193D02*
X3745563D01*
G01Y422224D02*
X3737689D01*
G01Y421043D02*
X3745563D01*
G01Y419074D02*
X3737689D01*
G01Y417893D02*
X3745563D01*
G01X3737689Y431673D02*
Y430492D01*
G01Y434822D02*
Y433641D01*
G01D02*
X3745563D01*
G01Y431673D02*
X3737689D01*
G01Y430492D02*
X3745563D01*
G01X3737689Y437972D02*
Y436791D01*
G01Y441122D02*
Y439941D01*
G01Y444271D02*
Y443090D01*
G01X3745563Y444271D02*
X3737689D01*
G01Y443090D02*
X3745563D01*
G01Y441122D02*
X3737689D01*
G01Y439941D02*
X3745563D01*
G01Y437972D02*
X3737689D01*
G01Y436791D02*
X3745563D01*
G01Y434822D02*
X3737689D01*
G01Y447421D02*
Y446240D01*
G01Y450570D02*
Y449389D01*
G01D02*
X3745563D01*
G01Y447421D02*
X3737689D01*
G01Y446240D02*
X3745563D01*
G01X3737689Y453720D02*
Y452539D01*
G01Y456870D02*
Y455689D01*
G01Y460019D02*
Y458838D01*
G01X3745563Y460019D02*
X3737689D01*
G01Y458838D02*
X3745563D01*
G01Y456870D02*
X3737689D01*
G01Y455689D02*
X3745563D01*
G01Y453720D02*
X3737689D01*
G01Y452539D02*
X3745563D01*
G01Y450570D02*
X3737689D01*
G01Y463169D02*
Y461988D01*
G01Y466318D02*
Y465137D01*
G01X3745563Y466318D02*
X3737689D01*
G01Y465137D02*
X3745563D01*
G01Y463169D02*
X3737689D01*
G01Y461988D02*
X3745563D01*
G01X3737689Y468287D02*
Y469468D01*
G01X3736704Y472519D02*
Y479901D01*
G01X3760326Y474094D02*
X3736704D01*
G01X3742019Y472519D02*
X3736704D01*
G01X3745563Y469468D02*
X3737689D01*
G01Y468287D02*
X3745563D01*
G01X3738673Y481870D02*
G03X3736704Y479901I0J-1969D01*
G01X3744578Y481870D02*
X3738673D01*
G01X3742807Y477834D02*
G03X3742019Y477047I-1J-787D01*
G01X3742807Y478622D02*
G03X3741232Y477047I0J-1575D01*
G01X3742807Y478622D02*
Y477834D01*
G01D02*
X3747137D01*
G01X3742019Y477047D02*
X3741232D01*
G01X3747137Y478622D02*
X3742807D01*
G01X3762163Y517696D02*
G03Y490137I-10498J-13780D01*
G01X3748515Y510216D02*
G03Y497618I0J-6299D01*
G01X3747768Y556622D02*
X3748778Y557272D01*
X3749356Y558138D01*
X3749500Y559112D01*
X3749356Y559978D01*
X3748634Y560845D01*
X3747768Y561386D01*
X3746902Y561494D01*
X3745891Y561278D01*
X3745170Y560520D01*
X3744881Y559762D01*
Y558787D01*
G01Y559762D02*
X3744448Y560411D01*
X3743726Y560953D01*
X3742860Y561169D01*
X3741994Y560953D01*
X3741272Y560411D01*
X3740839Y559437D01*
X3740983Y558463D01*
X3741561Y557488D01*
G01X3749500Y567665D02*
X3740839D01*
X3742571Y566366D01*
G01X3749500D02*
Y568964D01*
G01Y576326D02*
X3740839D01*
X3742571Y575027D01*
G01X3749500D02*
Y577625D01*
G01X3749789Y584987D02*
X3749644Y584770D01*
X3749356D01*
X3749211Y584987D01*
X3749356Y585204D01*
X3749644D01*
X3749789Y584987D01*
G01X3749500Y593431D02*
X3747624Y593648D01*
X3746036Y593973D01*
X3744592Y594406D01*
X3743004Y594947D01*
X3740839Y595813D01*
Y591483D01*
G01Y602309D02*
X3741128Y601443D01*
X3741849Y600793D01*
X3742715Y600360D01*
X3743870Y600035D01*
X3745170Y599927D01*
X3746469Y600035D01*
X3747624Y600360D01*
X3748490Y600793D01*
X3749211Y601443D01*
X3749500Y602309D01*
X3749211Y603175D01*
X3748490Y603825D01*
X3747624Y604258D01*
X3746469Y604583D01*
X3745170Y604691D01*
X3743870Y604583D01*
X3742715Y604258D01*
X3741849Y603825D01*
X3741128Y603175D01*
X3740839Y602309D01*
G01X3782733Y-1193692D02*
X3759969Y-1165458D01*
G01D02*
X3763119D01*
G01X3752767Y-1133718D02*
Y-1127944D01*
G01Y-1129388D02*
X3753201Y-1128666D01*
X3753850Y-1128088D01*
X3754716Y-1127944D01*
X3755474Y-1128088D01*
X3756124Y-1128666D01*
X3756449Y-1129676D01*
Y-1133718D01*
G01X3757424Y-1131986D02*
X3758074Y-1132996D01*
X3758940Y-1133574D01*
X3759914Y-1133718D01*
X3760780Y-1133574D01*
X3761647Y-1132852D01*
X3762188Y-1131986D01*
X3762296Y-1131120D01*
X3762080Y-1130109D01*
X3761322Y-1129388D01*
X3760564Y-1129099D01*
X3759589D01*
G01X3760564D02*
X3761213Y-1128666D01*
X3761755Y-1127944D01*
X3761971Y-1127078D01*
X3761755Y-1126212D01*
X3761213Y-1125490D01*
X3760239Y-1125057D01*
X3759265Y-1125201D01*
X3758290Y-1125779D01*
G01X3768467Y-1134007D02*
X3768250Y-1133862D01*
Y-1133574D01*
X3768467Y-1133429D01*
X3768684Y-1133574D01*
Y-1133862D01*
X3768467Y-1134007D01*
G01X3775071Y-1126500D02*
X3775721Y-1125635D01*
X3776478Y-1125201D01*
X3777345Y-1125057D01*
X3778427Y-1125346D01*
X3779185Y-1126067D01*
X3779402Y-1126933D01*
X3779293Y-1127800D01*
X3778860Y-1128521D01*
X3776695Y-1129965D01*
X3775721Y-1130975D01*
X3775071Y-1132419D01*
X3774854Y-1133718D01*
X3779402D01*
G01X3785789Y-1125057D02*
X3784923Y-1125346D01*
X3784273Y-1126067D01*
X3783840Y-1126933D01*
X3783515Y-1128088D01*
X3783407Y-1129388D01*
X3783515Y-1130687D01*
X3783840Y-1131842D01*
X3784273Y-1132708D01*
X3784923Y-1133429D01*
X3785789Y-1133718D01*
X3786655Y-1133429D01*
X3787305Y-1132708D01*
X3787738Y-1131842D01*
X3788063Y-1130687D01*
X3788171Y-1129388D01*
X3788063Y-1128088D01*
X3787738Y-1126933D01*
X3787305Y-1126067D01*
X3786655Y-1125346D01*
X3785789Y-1125057D01*
G01X3753022Y-1117420D02*
Y-1111646D01*
G01Y-1113090D02*
X3753456Y-1112368D01*
X3754105Y-1111790D01*
X3754971Y-1111646D01*
X3755729Y-1111790D01*
X3756379Y-1112368D01*
X3756704Y-1113378D01*
Y-1117420D01*
G01X3760061D02*
X3760819Y-1117276D01*
X3761685Y-1116843D01*
X3762226Y-1116121D01*
X3762443Y-1115110D01*
X3762226Y-1114100D01*
X3761577Y-1113234D01*
X3760602Y-1112801D01*
X3759520D01*
X3758870Y-1112512D01*
X3758329Y-1111790D01*
X3758112Y-1110780D01*
X3758437Y-1109769D01*
X3759195Y-1109048D01*
X3760061Y-1108759D01*
X3760927Y-1109048D01*
X3761685Y-1109769D01*
X3762010Y-1110780D01*
X3761793Y-1111790D01*
X3761252Y-1112512D01*
X3760602Y-1112801D01*
X3759520D01*
X3758545Y-1113234D01*
X3757896Y-1114100D01*
X3757679Y-1115110D01*
X3757896Y-1116121D01*
X3758437Y-1116843D01*
X3759303Y-1117276D01*
X3760061Y-1117420D01*
G01X3768722Y-1117709D02*
X3768505Y-1117564D01*
Y-1117276D01*
X3768722Y-1117131D01*
X3768939Y-1117276D01*
Y-1117564D01*
X3768722Y-1117709D01*
G01X3777383Y-1108759D02*
X3776517Y-1109048D01*
X3775867Y-1109769D01*
X3775434Y-1110635D01*
X3775109Y-1111790D01*
X3775001Y-1113090D01*
X3775109Y-1114389D01*
X3775434Y-1115544D01*
X3775867Y-1116410D01*
X3776517Y-1117131D01*
X3777383Y-1117420D01*
X3778249Y-1117131D01*
X3778899Y-1116410D01*
X3779332Y-1115544D01*
X3779657Y-1114389D01*
X3779765Y-1113090D01*
X3779657Y-1111790D01*
X3779332Y-1110635D01*
X3778899Y-1109769D01*
X3778249Y-1109048D01*
X3777383Y-1108759D01*
G01X3786044D02*
X3785178Y-1109048D01*
X3784528Y-1109769D01*
X3784095Y-1110635D01*
X3783770Y-1111790D01*
X3783662Y-1113090D01*
X3783770Y-1114389D01*
X3784095Y-1115544D01*
X3784528Y-1116410D01*
X3785178Y-1117131D01*
X3786044Y-1117420D01*
X3786910Y-1117131D01*
X3787560Y-1116410D01*
X3787993Y-1115544D01*
X3788318Y-1114389D01*
X3788426Y-1113090D01*
X3788318Y-1111790D01*
X3787993Y-1110635D01*
X3787560Y-1109769D01*
X3786910Y-1109048D01*
X3786044Y-1108759D01*
G01X3746444Y-1085899D02*
X3747094Y-1086909D01*
X3747960Y-1087487D01*
X3748934Y-1087631D01*
X3749800Y-1087487D01*
X3750667Y-1086765D01*
X3751208Y-1085899D01*
X3751316Y-1085033D01*
X3751100Y-1084022D01*
X3750342Y-1083301D01*
X3749584Y-1083012D01*
X3748609D01*
G01X3749584D02*
X3750233Y-1082579D01*
X3750775Y-1081857D01*
X3750991Y-1080991D01*
X3750775Y-1080125D01*
X3750233Y-1079403D01*
X3749259Y-1078970D01*
X3748285Y-1079114D01*
X3747310Y-1079692D01*
G01X3757487Y-1087920D02*
X3757270Y-1087775D01*
Y-1087487D01*
X3757487Y-1087342D01*
X3757704Y-1087487D01*
Y-1087775D01*
X3757487Y-1087920D01*
G01X3764091Y-1080413D02*
X3764741Y-1079548D01*
X3765498Y-1079114D01*
X3766365Y-1078970D01*
X3767447Y-1079259D01*
X3768205Y-1079980D01*
X3768422Y-1080846D01*
X3768313Y-1081713D01*
X3767880Y-1082434D01*
X3765715Y-1083878D01*
X3764741Y-1084888D01*
X3764091Y-1086332D01*
X3763874Y-1087631D01*
X3768422D01*
G01X3774809Y-1078970D02*
X3773943Y-1079259D01*
X3773293Y-1079980D01*
X3772860Y-1080846D01*
X3772535Y-1082001D01*
X3772427Y-1083301D01*
X3772535Y-1084600D01*
X3772860Y-1085755D01*
X3773293Y-1086621D01*
X3773943Y-1087342D01*
X3774809Y-1087631D01*
X3775675Y-1087342D01*
X3776325Y-1086621D01*
X3776758Y-1085755D01*
X3777083Y-1084600D01*
X3777191Y-1083301D01*
X3777083Y-1082001D01*
X3776758Y-1080846D01*
X3776325Y-1079980D01*
X3775675Y-1079259D01*
X3774809Y-1078970D01*
G01X3750376Y-1059022D02*
Y-1053248D01*
G01Y-1054692D02*
X3750810Y-1053970D01*
X3751459Y-1053392D01*
X3752325Y-1053248D01*
X3753083Y-1053392D01*
X3753733Y-1053970D01*
X3754058Y-1054980D01*
Y-1059022D01*
G01X3757415D02*
X3758173Y-1058878D01*
X3759039Y-1058445D01*
X3759580Y-1057723D01*
X3759797Y-1056712D01*
X3759580Y-1055702D01*
X3758931Y-1054836D01*
X3757956Y-1054403D01*
X3756874D01*
X3756224Y-1054114D01*
X3755683Y-1053392D01*
X3755466Y-1052382D01*
X3755791Y-1051371D01*
X3756549Y-1050650D01*
X3757415Y-1050361D01*
X3758281Y-1050650D01*
X3759039Y-1051371D01*
X3759364Y-1052382D01*
X3759147Y-1053392D01*
X3758606Y-1054114D01*
X3757956Y-1054403D01*
X3756874D01*
X3755899Y-1054836D01*
X3755250Y-1055702D01*
X3755033Y-1056712D01*
X3755250Y-1057723D01*
X3755791Y-1058445D01*
X3756657Y-1058878D01*
X3757415Y-1059022D01*
G01X3766076Y-1059311D02*
X3765859Y-1059166D01*
Y-1058878D01*
X3766076Y-1058733D01*
X3766293Y-1058878D01*
Y-1059166D01*
X3766076Y-1059311D01*
G01X3774737Y-1050361D02*
X3773871Y-1050650D01*
X3773221Y-1051371D01*
X3772788Y-1052237D01*
X3772463Y-1053392D01*
X3772355Y-1054692D01*
X3772463Y-1055991D01*
X3772788Y-1057146D01*
X3773221Y-1058012D01*
X3773871Y-1058733D01*
X3774737Y-1059022D01*
X3775603Y-1058733D01*
X3776253Y-1058012D01*
X3776686Y-1057146D01*
X3777011Y-1055991D01*
X3777119Y-1054692D01*
X3777011Y-1053392D01*
X3776686Y-1052237D01*
X3776253Y-1051371D01*
X3775603Y-1050650D01*
X3774737Y-1050361D01*
G01X3783398D02*
X3782532Y-1050650D01*
X3781882Y-1051371D01*
X3781449Y-1052237D01*
X3781124Y-1053392D01*
X3781016Y-1054692D01*
X3781124Y-1055991D01*
X3781449Y-1057146D01*
X3781882Y-1058012D01*
X3782532Y-1058733D01*
X3783398Y-1059022D01*
X3784264Y-1058733D01*
X3784914Y-1058012D01*
X3785347Y-1057146D01*
X3785672Y-1055991D01*
X3785780Y-1054692D01*
X3785672Y-1053392D01*
X3785347Y-1052237D01*
X3784914Y-1051371D01*
X3784264Y-1050650D01*
X3783398Y-1050361D01*
G01X3782488Y-1018697D02*
X3746482Y-975839D01*
G01X3759700Y-973674D02*
Y-967900D01*
G01Y-969344D02*
X3760134Y-968622D01*
X3760783Y-968044D01*
X3761649Y-967900D01*
X3762407Y-968044D01*
X3763057Y-968622D01*
X3763382Y-969632D01*
Y-973674D01*
G01X3749632Y-975839D02*
X3848661D01*
G01X3746482D02*
X3749632D01*
G01X3754815Y241712D02*
G03Y254311I0J6299D01*
G01X3748515Y241712D02*
X3754815D01*
G01Y254311D02*
X3748515D01*
G01X3746271Y279055D02*
X3745484Y278267D01*
G01X3751547D02*
X3750759Y279055D01*
G01X3754224Y276830D02*
G03X3755011Y277618I0J787D01*
G01X3749893Y276043D02*
G03X3748712Y274870I0J-1181D01*
G01X3754224Y276043D02*
G03X3755799Y277618I0J1575D01*
G01X3749893Y276830D02*
G03X3747925Y274876I0J-1968D01*
G01X3747137Y274094D02*
G03X3747925Y274876I1J787D01*
G01X3749357Y273208D02*
G03I-842J0D01*
G01X3747137Y273307D02*
G03X3748712Y274870I0J1575D01*
G01X3750534Y273208D02*
G03I-2019J0D01*
G01X3750681D02*
G03I-2166J0D01*
G01X3756389Y275570D02*
Y272421D01*
G01X3755799Y474311D02*
Y277618D01*
G01X3755011Y474311D02*
Y277618D01*
G01X3754224Y276043D02*
Y276830D01*
G01X3752452Y270846D02*
Y270059D01*
G01X3751547Y473661D02*
Y278267D01*
G01X3750759Y472874D02*
Y279055D01*
G01X3749893Y276043D02*
Y276830D01*
G01X3747137Y273307D02*
Y274094D01*
G01X3746271Y472874D02*
Y279055D01*
G01X3745484Y278267D02*
Y473661D01*
G01X3744578Y270846D02*
Y270059D01*
G01X3758752Y274830D02*
X3757177Y273921D01*
G01X3758752Y273011D02*
X3757177Y273921D01*
G01X3760326Y279409D02*
X3755011D01*
G01X3750759Y279055D02*
X3746271D01*
G01X3747925Y274876D02*
X3748712Y274870D01*
G01X3751547Y278267D02*
X3745484D01*
G01X3755011Y277618D02*
X3755799D01*
G01X3754224Y276830D02*
X3749893D01*
G01X3754224Y276043D02*
X3749893D01*
G01X3759539Y275570D02*
X3756389D01*
G01X3759539Y272421D02*
X3756389D01*
G01X3752452Y270846D02*
X3744578D01*
G01X3758358Y270059D02*
X3752452D01*
G01X3751468Y283641D02*
Y282460D01*
G01Y286791D02*
Y285610D01*
G01X3745563D02*
Y286791D01*
G01Y282460D02*
Y283641D01*
G01X3751468Y285610D02*
X3759342D01*
G01Y283641D02*
X3751468D01*
G01Y282460D02*
X3759342D01*
G01X3758358Y270059D02*
G03X3760326Y272027I0J1968D01*
G01Y279409D02*
Y272027D01*
G01X3759539Y275570D02*
Y272421D01*
G01X3758752Y274830D02*
Y273011D01*
G01X3759637Y283221D02*
Y283588D01*
G01X3759342Y285610D02*
Y286791D01*
G01Y282460D02*
Y283641D01*
G01X3760137Y283221D02*
X3760574Y282854D01*
G01X3760074D02*
X3759637Y283221D01*
G01Y283588D02*
X3762574D01*
G01Y283221D02*
X3760137D01*
G01X3760574Y282854D02*
X3760074D01*
G01X3751468Y293090D02*
Y291909D01*
G01Y289941D02*
Y288759D01*
G01Y296240D02*
Y295059D01*
G01X3745563D02*
Y296240D01*
G01Y288759D02*
Y289941D01*
G01Y291909D02*
Y293090D01*
G01X3759342Y296240D02*
X3751468D01*
G01Y295059D02*
X3759342D01*
G01Y293090D02*
X3751468D01*
G01Y291909D02*
X3759342D01*
G01Y289941D02*
X3751468D01*
G01Y288759D02*
X3759342D01*
G01Y286791D02*
X3751468D01*
G01Y302539D02*
Y301358D01*
G01Y299389D02*
Y298208D01*
G01X3745563D02*
Y299389D01*
G01Y301358D02*
Y302539D01*
G01X3759342D02*
X3751468D01*
G01Y301358D02*
X3759342D01*
G01Y299389D02*
X3751468D01*
G01Y298208D02*
X3759342D01*
G01Y295059D02*
Y296240D01*
G01Y291909D02*
Y293090D01*
G01Y288759D02*
Y289941D01*
G01Y301358D02*
Y302539D01*
G01Y298208D02*
Y299389D01*
G01X3751468Y305689D02*
Y304507D01*
G01Y311988D02*
Y310807D01*
G01Y308838D02*
Y307657D01*
G01X3745563D02*
Y308838D01*
G01Y310807D02*
Y311988D01*
G01Y304507D02*
Y305689D01*
G01X3759342Y311988D02*
X3751468D01*
G01Y310807D02*
X3759342D01*
G01Y308838D02*
X3751468D01*
G01Y307657D02*
X3759342D01*
G01Y305689D02*
X3751468D01*
G01Y304507D02*
X3759342D01*
G01X3751468Y315137D02*
Y313956D01*
G01Y318287D02*
Y317106D01*
G01X3745563D02*
Y318287D01*
G01Y313956D02*
Y315137D01*
G01X3759342Y318287D02*
X3751468D01*
G01Y317106D02*
X3759342D01*
G01Y315137D02*
X3751468D01*
G01Y313956D02*
X3759342D01*
G01Y310807D02*
Y311988D01*
G01Y307657D02*
Y308838D01*
G01Y304507D02*
Y305689D01*
G01Y317106D02*
Y318287D01*
G01Y313956D02*
Y315137D01*
G01X3751468Y321437D02*
Y320256D01*
G01Y324586D02*
Y323405D01*
G01Y330885D02*
Y329704D01*
G01Y327736D02*
Y326555D01*
G01X3745563D02*
Y327736D01*
G01Y329704D02*
Y330885D01*
G01Y323405D02*
Y324586D01*
G01Y320256D02*
Y321437D01*
G01X3751468Y329704D02*
X3759342D01*
G01Y327736D02*
X3751468D01*
G01Y326555D02*
X3759342D01*
G01Y324586D02*
X3751468D01*
G01Y323405D02*
X3759342D01*
G01Y321437D02*
X3751468D01*
G01Y320256D02*
X3759342D01*
G01X3751468Y334035D02*
Y332854D01*
G01X3745563D02*
Y334035D01*
G01X3759342D02*
X3751468D01*
G01Y332854D02*
X3759342D01*
G01Y330885D02*
X3751468D01*
G01X3759342Y329704D02*
Y330885D01*
G01Y326555D02*
Y327736D01*
G01Y323405D02*
Y324586D01*
G01Y320256D02*
Y321437D01*
G01Y332854D02*
Y334035D01*
G01X3751468Y340334D02*
Y339153D01*
G01Y337185D02*
Y336004D01*
G01Y343484D02*
Y342303D01*
G01Y346633D02*
Y345452D01*
G01X3745563D02*
Y346633D01*
G01Y342303D02*
Y343484D01*
G01Y336004D02*
Y337185D01*
G01Y339153D02*
Y340334D01*
G01X3751468Y345452D02*
X3759342D01*
G01Y343484D02*
X3751468D01*
G01X3755011Y342893D02*
X3755799D01*
G01X3751468Y342303D02*
X3759342D01*
G01Y340334D02*
X3751468D01*
G01Y339153D02*
X3759342D01*
G01Y337185D02*
X3751468D01*
G01X3755799Y336594D02*
X3755011D01*
G01X3751468Y336004D02*
X3759342D01*
G01X3751468Y349783D02*
Y348602D01*
G01Y352933D02*
Y351752D01*
G01X3745563D02*
Y352933D01*
G01Y348602D02*
Y349783D01*
G01X3751468Y351752D02*
X3759342D01*
G01Y349783D02*
X3751468D01*
G01Y348602D02*
X3759342D01*
G01Y346633D02*
X3751468D01*
G01X3759342Y345452D02*
Y346633D01*
G01Y342303D02*
Y343484D01*
G01Y339153D02*
Y340334D01*
G01Y336004D02*
Y337185D01*
G01Y351752D02*
Y352933D01*
G01Y348602D02*
Y349783D01*
G01X3751468Y359232D02*
Y358051D01*
G01Y356082D02*
Y354901D01*
G01Y362381D02*
Y361200D01*
G01X3745563D02*
Y362381D01*
G01Y354901D02*
Y356082D01*
G01Y358051D02*
Y359232D01*
G01X3759342Y362381D02*
X3751468D01*
G01Y361200D02*
X3759342D01*
G01Y359232D02*
X3751468D01*
G01X3755011Y358641D02*
X3755799D01*
G01X3751468Y358051D02*
X3759342D01*
G01Y356082D02*
X3751468D01*
G01Y354901D02*
X3759342D01*
G01Y352933D02*
X3751468D01*
G01X3755799Y352342D02*
X3755011D01*
G01X3751468Y368681D02*
Y367500D01*
G01Y365531D02*
Y364350D01*
G01X3745563D02*
Y365531D01*
G01Y367500D02*
Y368681D01*
G01X3751468Y367500D02*
X3759342D01*
G01Y365531D02*
X3751468D01*
G01Y364350D02*
X3759342D01*
G01Y361200D02*
Y362381D01*
G01Y358051D02*
Y359232D01*
G01Y354901D02*
Y356082D01*
G01Y367500D02*
Y368681D01*
G01Y364350D02*
Y365531D01*
G01X3751468Y371830D02*
Y370649D01*
G01Y374980D02*
Y373799D01*
G01Y378130D02*
Y376948D01*
G01X3745563D02*
Y378130D01*
G01Y373799D02*
Y374980D01*
G01Y370649D02*
Y371830D01*
G01X3759342Y378130D02*
X3751468D01*
G01Y376948D02*
X3759342D01*
G01Y374980D02*
X3751468D01*
G01Y373799D02*
X3759342D01*
G01Y371830D02*
X3751468D01*
G01Y370649D02*
X3759342D01*
G01Y368681D02*
X3751468D01*
G01Y381279D02*
Y380098D01*
G01Y384429D02*
Y383248D01*
G01X3745563D02*
Y384429D01*
G01Y380098D02*
Y381279D01*
G01X3759342Y384429D02*
X3751468D01*
G01Y383248D02*
X3759342D01*
G01Y381279D02*
X3751468D01*
G01Y380098D02*
X3759342D01*
G01Y376948D02*
Y378130D01*
G01Y373799D02*
Y374980D01*
G01Y370649D02*
Y371830D01*
G01Y383248D02*
Y384429D01*
G01Y380098D02*
Y381279D01*
G01X3751468Y390728D02*
Y389547D01*
G01Y387578D02*
Y386397D01*
G01Y393878D02*
Y392696D01*
G01X3745563D02*
Y393878D01*
G01Y386397D02*
Y387578D01*
G01Y389547D02*
Y390728D01*
G01X3759342Y393878D02*
X3751468D01*
G01X3755799Y393287D02*
X3755011D01*
G01X3751468Y392696D02*
X3759342D01*
G01Y390728D02*
X3751468D01*
G01Y389547D02*
X3759342D01*
G01Y387578D02*
X3751468D01*
G01Y386397D02*
X3759342D01*
G01X3751468Y400177D02*
Y398996D01*
G01Y397027D02*
Y395846D01*
G01X3745563D02*
Y397027D01*
G01Y398996D02*
Y400177D01*
G01X3759342D02*
X3751468D01*
G01X3755799Y399586D02*
X3755011D01*
G01X3751468Y398996D02*
X3759342D01*
G01Y397027D02*
X3751468D01*
G01Y395846D02*
X3759342D01*
G01Y392696D02*
Y393878D01*
G01Y389547D02*
Y390728D01*
G01Y386397D02*
Y387578D01*
G01Y398996D02*
Y400177D01*
G01Y395846D02*
Y397027D01*
G01X3751468Y403326D02*
Y402145D01*
G01Y409626D02*
Y408444D01*
G01Y406476D02*
Y405295D01*
G01Y412775D02*
Y411594D01*
G01X3745563D02*
Y412775D01*
G01Y405295D02*
Y406476D01*
G01Y408444D02*
Y409626D01*
G01Y402145D02*
Y403326D01*
G01X3751468Y411594D02*
X3759342D01*
G01Y409626D02*
X3751468D01*
G01X3755799Y409035D02*
X3755011D01*
G01X3751468Y408444D02*
X3759342D01*
G01Y406476D02*
X3751468D01*
G01Y405295D02*
X3759342D01*
G01Y403326D02*
X3751468D01*
G01Y402145D02*
X3759342D01*
G01X3751468Y415925D02*
Y414744D01*
G01X3745563D02*
Y415925D01*
G01X3759342D02*
X3751468D01*
G01X3755799Y415334D02*
X3755011D01*
G01X3751468Y414744D02*
X3759342D01*
G01Y412775D02*
X3751468D01*
G01X3759342Y411594D02*
Y412775D01*
G01Y408444D02*
Y409626D01*
G01Y405295D02*
Y406476D01*
G01Y402145D02*
Y403326D01*
G01Y414744D02*
Y415925D01*
G01X3751468Y419074D02*
Y417893D01*
G01Y422224D02*
Y421043D01*
G01Y428523D02*
Y427342D01*
G01Y425374D02*
Y424193D01*
G01X3745563D02*
Y425374D01*
G01Y427342D02*
Y428523D01*
G01Y421043D02*
Y422224D01*
G01Y417893D02*
Y419074D01*
G01X3759342Y428523D02*
X3751468D01*
G01Y427342D02*
X3759342D01*
G01Y425374D02*
X3751468D01*
G01Y424193D02*
X3759342D01*
G01Y422224D02*
X3751468D01*
G01Y421043D02*
X3759342D01*
G01Y419074D02*
X3751468D01*
G01Y417893D02*
X3759342D01*
G01X3751468Y431673D02*
Y430492D01*
G01Y434822D02*
Y433641D01*
G01X3745563D02*
Y434822D01*
G01Y430492D02*
Y431673D01*
G01X3751468Y433641D02*
X3759342D01*
G01Y431673D02*
X3751468D01*
G01Y430492D02*
X3759342D01*
G01Y427342D02*
Y428523D01*
G01Y424193D02*
Y425374D01*
G01Y421043D02*
Y422224D01*
G01Y417893D02*
Y419074D01*
G01Y433641D02*
Y434822D01*
G01Y430492D02*
Y431673D01*
G01X3751468Y437972D02*
Y436791D01*
G01Y441122D02*
Y439941D01*
G01Y444271D02*
Y443090D01*
G01X3745563D02*
Y444271D01*
G01Y439941D02*
Y441122D01*
G01Y436791D02*
Y437972D01*
G01X3759342Y444271D02*
X3751468D01*
G01Y443090D02*
X3759342D01*
G01Y441122D02*
X3751468D01*
G01Y439941D02*
X3759342D01*
G01Y437972D02*
X3751468D01*
G01Y436791D02*
X3759342D01*
G01Y434822D02*
X3751468D01*
G01Y447421D02*
Y446240D01*
G01Y450570D02*
Y449389D01*
G01X3745563D02*
Y450570D01*
G01Y446240D02*
Y447421D01*
G01X3751468Y449389D02*
X3759342D01*
G01Y447421D02*
X3751468D01*
G01Y446240D02*
X3759342D01*
G01Y443090D02*
Y444271D01*
G01Y439941D02*
Y441122D01*
G01Y436791D02*
Y437972D01*
G01Y449389D02*
Y450570D01*
G01Y446240D02*
Y447421D01*
G01X3751468Y456870D02*
Y455689D01*
G01Y453720D02*
Y452539D01*
G01Y460019D02*
Y458838D01*
G01X3745563D02*
Y460019D01*
G01Y452539D02*
Y453720D01*
G01Y455689D02*
Y456870D01*
G01X3759342Y460019D02*
X3751468D01*
G01Y458838D02*
X3759342D01*
G01Y456870D02*
X3751468D01*
G01Y455689D02*
X3759342D01*
G01Y453720D02*
X3751468D01*
G01Y452539D02*
X3759342D01*
G01Y450570D02*
X3751468D01*
G01Y466318D02*
Y465137D01*
G01Y463169D02*
Y461988D01*
G01X3745563D02*
Y463169D01*
G01Y465137D02*
Y466318D01*
G01X3759342D02*
X3751468D01*
G01Y465137D02*
X3759342D01*
G01Y463169D02*
X3751468D01*
G01Y461988D02*
X3759342D01*
G01Y458838D02*
Y460019D01*
G01Y455689D02*
Y456870D01*
G01Y452539D02*
Y453720D01*
G01Y465137D02*
Y466318D01*
G01Y461988D02*
Y463169D01*
G01X3745484Y473661D02*
X3746271Y472874D01*
G01X3750759D02*
X3751547Y473661D01*
G01X3755011Y474311D02*
G03X3754224Y475098I-787J0D01*
G01X3747925Y477052D02*
G03X3747137Y477834I-787J-5D01*
G01X3748712Y477058D02*
G03X3749893Y475885I1181J8D01*
G01X3749733Y478720D02*
G03I-1218J0D01*
G01X3749893D02*
G03I-1378J0D01*
G01X3748712Y477058D02*
G03X3747137Y478622I-1575J-11D01*
G01X3755799Y474311D02*
G03X3754224Y475885I-1575J-1D01*
G01X3747925Y477052D02*
G03X3749893Y475098I1968J15D01*
G01X3750484Y478720D02*
G03I-1969J0D01*
G01X3754224Y475098D02*
Y475885D01*
G01X3751468Y469468D02*
Y468287D01*
G01X3749893Y475098D02*
Y475885D01*
G01X3747137Y477834D02*
Y478622D01*
G01X3745563Y468287D02*
Y469468D01*
G01X3754224Y475885D02*
X3749893D01*
G01Y475098D02*
X3754224D01*
G01X3755799Y474311D02*
X3755011D01*
G01X3745484Y473661D02*
X3751547D01*
G01X3750759Y472874D02*
X3746271D01*
G01X3760326Y472519D02*
X3755011D01*
G01X3759342Y469468D02*
X3751468D01*
G01X3759342Y468287D02*
X3751468D01*
G01X3748712Y477058D02*
X3747925Y477052D01*
G01X3752452Y481870D02*
Y481082D01*
G01X3744578Y481870D02*
Y481082D01*
G01X3758358Y481870D02*
X3752452D01*
G01Y481082D02*
X3744578D01*
G01X3760326Y479901D02*
Y472519D01*
G01X3759342Y468287D02*
Y469468D01*
G01X3760326Y479901D02*
G03X3758358Y481870I-1968J1D01*
G01X3754815Y497618D02*
G03Y510216I0J6299D01*
G01X3748515Y497618D02*
X3754815D01*
G01Y510216D02*
X3748515D01*
G01X3751665Y514153D02*
Y551425D01*
G01X3808366Y-1205951D02*
G03I-15748J0D01*
G01X3789139Y-1200700D02*
X3775664Y-1180353D01*
G01D02*
X3778813D01*
G01X3773187Y-1163292D02*
Y-1157518D01*
G01Y-1158962D02*
X3773621Y-1158240D01*
X3774270Y-1157662D01*
X3775136Y-1157518D01*
X3775894Y-1157662D01*
X3776544Y-1158240D01*
X3776869Y-1159250D01*
Y-1163292D01*
G01X3763119Y-1165458D02*
X3862148D01*
G01X3777734Y-1090518D02*
X3776651Y-1089074D01*
X3776110Y-1087631D01*
Y-1081857D01*
X3776651Y-1080413D01*
X3777734Y-1078970D01*
G01X3784446Y-1087631D02*
Y-1078970D01*
X3789426Y-1087631D01*
Y-1078970D01*
G01X3793432Y-1087631D02*
Y-1078970D01*
X3796030D01*
X3796896Y-1079403D01*
X3797546Y-1080413D01*
X3797762Y-1081568D01*
X3797546Y-1082723D01*
X3797004Y-1083589D01*
X3796030Y-1084022D01*
X3793432D01*
G01X3804258Y-1078970D02*
Y-1087631D01*
G01X3801768Y-1078970D02*
X3806748D01*
G01X3810645Y-1087631D02*
Y-1078970D01*
G01X3815193D02*
Y-1087631D01*
G01Y-1083301D02*
X3810645D01*
G01X3822121Y-1090518D02*
X3823204Y-1089074D01*
X3823745Y-1087631D01*
Y-1081857D01*
X3823204Y-1080413D01*
X3822121Y-1078970D01*
G01X3808366Y-1030754D02*
G03I-15748J0D01*
G01X3790255Y-1024915D02*
X3776922Y-991966D01*
G01D02*
X3780072D01*
G01X3773090Y-973674D02*
X3773848Y-973530D01*
X3774714Y-973097D01*
X3775255Y-972375D01*
X3775472Y-971364D01*
X3775255Y-970354D01*
X3774606Y-969488D01*
X3773631Y-969055D01*
X3772549D01*
X3771899Y-968766D01*
X3771358Y-968044D01*
X3771141Y-967034D01*
X3771466Y-966023D01*
X3772224Y-965302D01*
X3773090Y-965013D01*
X3773956Y-965302D01*
X3774714Y-966023D01*
X3775039Y-967034D01*
X3774822Y-968044D01*
X3774281Y-968766D01*
X3773631Y-969055D01*
X3772549D01*
X3771574Y-969488D01*
X3770925Y-970354D01*
X3770708Y-971364D01*
X3770925Y-972375D01*
X3771466Y-973097D01*
X3772332Y-973530D01*
X3773090Y-973674D01*
G01X3781751Y-973963D02*
X3781534Y-973818D01*
Y-973530D01*
X3781751Y-973385D01*
X3781968Y-973530D01*
Y-973818D01*
X3781751Y-973963D01*
G01X3790412Y-965013D02*
X3789546Y-965302D01*
X3788896Y-966023D01*
X3788463Y-966889D01*
X3788138Y-968044D01*
X3788030Y-969344D01*
X3788138Y-970643D01*
X3788463Y-971798D01*
X3788896Y-972664D01*
X3789546Y-973385D01*
X3790412Y-973674D01*
X3791278Y-973385D01*
X3791928Y-972664D01*
X3792361Y-971798D01*
X3792686Y-970643D01*
X3792794Y-969344D01*
X3792686Y-968044D01*
X3792361Y-966889D01*
X3791928Y-966023D01*
X3791278Y-965302D01*
X3790412Y-965013D01*
G01X3799073D02*
X3798207Y-965302D01*
X3797557Y-966023D01*
X3797124Y-966889D01*
X3796799Y-968044D01*
X3796691Y-969344D01*
X3796799Y-970643D01*
X3797124Y-971798D01*
X3797557Y-972664D01*
X3798207Y-973385D01*
X3799073Y-973674D01*
X3799939Y-973385D01*
X3800589Y-972664D01*
X3801022Y-971798D01*
X3801347Y-970643D01*
X3801455Y-969344D01*
X3801347Y-968044D01*
X3801022Y-966889D01*
X3800589Y-966023D01*
X3799939Y-965302D01*
X3799073Y-965013D01*
G01X3776074Y92500D02*
Y234232D01*
G01X3762163D02*
X3809145D01*
G01X3762163Y261791D02*
X3809145D01*
G01X3776074D02*
Y490137D01*
G01X3762574Y283588D02*
Y283221D01*
G01X3790228Y441515D02*
X3775779D01*
G01X3762163Y490137D02*
X3810720D01*
G01X3762163Y517696D02*
X3810720D01*
G01X3776074D02*
Y521633D01*
G01X3789513Y-1837784D02*
Y-1856796D01*
G01X3798917Y-1205951D02*
G03I-6299J0D01*
G01X3788882Y-1178188D02*
Y-1172414D01*
G01Y-1173858D02*
X3789316Y-1173136D01*
X3789965Y-1172558D01*
X3790831Y-1172414D01*
X3791589Y-1172558D01*
X3792239Y-1173136D01*
X3792564Y-1174146D01*
Y-1178188D01*
G01X3778813Y-1180353D02*
X3885637D01*
G01X3786577Y-1163292D02*
X3787335Y-1163148D01*
X3788201Y-1162715D01*
X3788742Y-1161993D01*
X3788959Y-1160982D01*
X3788742Y-1159972D01*
X3788093Y-1159106D01*
X3787118Y-1158673D01*
X3786036D01*
X3785386Y-1158384D01*
X3784845Y-1157662D01*
X3784628Y-1156652D01*
X3784953Y-1155641D01*
X3785711Y-1154920D01*
X3786577Y-1154631D01*
X3787443Y-1154920D01*
X3788201Y-1155641D01*
X3788526Y-1156652D01*
X3788309Y-1157662D01*
X3787768Y-1158384D01*
X3787118Y-1158673D01*
X3786036D01*
X3785061Y-1159106D01*
X3784412Y-1159972D01*
X3784195Y-1160982D01*
X3784412Y-1161993D01*
X3784953Y-1162715D01*
X3785819Y-1163148D01*
X3786577Y-1163292D01*
G01X3795238Y-1163581D02*
X3795021Y-1163436D01*
Y-1163148D01*
X3795238Y-1163003D01*
X3795455Y-1163148D01*
Y-1163436D01*
X3795238Y-1163581D01*
G01X3803899Y-1154631D02*
X3803033Y-1154920D01*
X3802383Y-1155641D01*
X3801950Y-1156507D01*
X3801625Y-1157662D01*
X3801517Y-1158962D01*
X3801625Y-1160261D01*
X3801950Y-1161416D01*
X3802383Y-1162282D01*
X3803033Y-1163003D01*
X3803899Y-1163292D01*
X3804765Y-1163003D01*
X3805415Y-1162282D01*
X3805848Y-1161416D01*
X3806173Y-1160261D01*
X3806281Y-1158962D01*
X3806173Y-1157662D01*
X3805848Y-1156507D01*
X3805415Y-1155641D01*
X3804765Y-1154920D01*
X3803899Y-1154631D01*
G01X3812560D02*
X3811694Y-1154920D01*
X3811044Y-1155641D01*
X3810611Y-1156507D01*
X3810286Y-1157662D01*
X3810178Y-1158962D01*
X3810286Y-1160261D01*
X3810611Y-1161416D01*
X3811044Y-1162282D01*
X3811694Y-1163003D01*
X3812560Y-1163292D01*
X3813426Y-1163003D01*
X3814076Y-1162282D01*
X3814509Y-1161416D01*
X3814834Y-1160261D01*
X3814942Y-1158962D01*
X3814834Y-1157662D01*
X3814509Y-1156507D01*
X3814076Y-1155641D01*
X3813426Y-1154920D01*
X3812560Y-1154631D01*
G01X3788715Y-1136605D02*
X3787632Y-1135161D01*
X3787091Y-1133718D01*
Y-1127944D01*
X3787632Y-1126500D01*
X3788715Y-1125057D01*
G01X3795427Y-1133718D02*
Y-1125057D01*
X3800407Y-1133718D01*
Y-1125057D01*
G01X3804413Y-1133718D02*
Y-1125057D01*
X3807011D01*
X3807877Y-1125490D01*
X3808527Y-1126500D01*
X3808743Y-1127655D01*
X3808527Y-1128810D01*
X3807985Y-1129676D01*
X3807011Y-1130109D01*
X3804413D01*
G01X3815239Y-1125057D02*
Y-1133718D01*
G01X3812749Y-1125057D02*
X3817729D01*
G01X3821626Y-1133718D02*
Y-1125057D01*
G01X3826174D02*
Y-1133718D01*
G01Y-1129388D02*
X3821626D01*
G01X3833102Y-1136605D02*
X3834185Y-1135161D01*
X3834726Y-1133718D01*
Y-1127944D01*
X3834185Y-1126500D01*
X3833102Y-1125057D01*
G01X3789836Y-1120307D02*
X3788753Y-1118863D01*
X3788212Y-1117420D01*
Y-1111646D01*
X3788753Y-1110202D01*
X3789836Y-1108759D01*
G01X3796873Y-1117420D02*
Y-1108759D01*
X3799471D01*
X3800337Y-1109192D01*
X3800987Y-1110202D01*
X3801203Y-1111357D01*
X3800987Y-1112512D01*
X3800445Y-1113378D01*
X3799471Y-1113811D01*
X3796873D01*
G01X3804992Y-1117420D02*
X3807699Y-1108759D01*
X3810406Y-1117420D01*
G01X3809431Y-1114389D02*
X3805967D01*
G01X3813978Y-1117420D02*
Y-1108759D01*
X3816143D01*
X3817010Y-1109192D01*
X3817659Y-1109769D01*
X3818201Y-1110635D01*
X3818634Y-1111646D01*
X3818742Y-1113090D01*
X3818634Y-1114533D01*
X3818201Y-1115544D01*
X3817659Y-1116410D01*
X3817010Y-1116987D01*
X3816143Y-1117420D01*
X3813978D01*
G01X3825562Y-1120307D02*
X3826645Y-1118863D01*
X3827186Y-1117420D01*
Y-1111646D01*
X3826645Y-1110202D01*
X3825562Y-1108759D01*
G01X3787189Y-1061909D02*
X3786106Y-1060465D01*
X3785565Y-1059022D01*
Y-1053248D01*
X3786106Y-1051804D01*
X3787189Y-1050361D01*
G01X3794226Y-1059022D02*
Y-1050361D01*
X3796824D01*
X3797690Y-1050794D01*
X3798340Y-1051804D01*
X3798556Y-1052959D01*
X3798340Y-1054114D01*
X3797798Y-1054980D01*
X3796824Y-1055413D01*
X3794226D01*
G01X3802345Y-1059022D02*
X3805052Y-1050361D01*
X3807759Y-1059022D01*
G01X3806784Y-1055991D02*
X3803320D01*
G01X3811331Y-1059022D02*
Y-1050361D01*
X3813496D01*
X3814363Y-1050794D01*
X3815012Y-1051371D01*
X3815554Y-1052237D01*
X3815987Y-1053248D01*
X3816095Y-1054692D01*
X3815987Y-1056135D01*
X3815554Y-1057146D01*
X3815012Y-1058012D01*
X3814363Y-1058589D01*
X3813496Y-1059022D01*
X3811331D01*
G01X3822915Y-1061909D02*
X3823998Y-1060465D01*
X3824539Y-1059022D01*
Y-1053248D01*
X3823998Y-1051804D01*
X3822915Y-1050361D01*
G01X3798917Y-1030754D02*
G03I-6299J0D01*
G01X3790140Y-989801D02*
Y-984027D01*
G01Y-985471D02*
X3790574Y-984749D01*
X3791223Y-984171D01*
X3792089Y-984027D01*
X3792847Y-984171D01*
X3793497Y-984749D01*
X3793822Y-985759D01*
Y-989801D01*
G01X3780072Y-991966D02*
X3886896D01*
G01X3791626Y106476D02*
Y92696D01*
G01X3829027D02*
X3791626D01*
G01X3829027Y106476D02*
X3791626D01*
G01X3792216Y130098D02*
G03Y132067I0J985D01*
G01X3792885Y131474D02*
X3792623Y130687D01*
G01X3792705Y131206D02*
X3792557Y130754D01*
G01X3792722Y131274D02*
X3792787Y131474D01*
G01X3792216Y130098D02*
Y128130D01*
G01Y134035D02*
Y132067D01*
G01X3792328Y131474D02*
X3792393Y131274D01*
G01X3792557Y130754D02*
X3792410Y131206D01*
G01X3792492Y130687D02*
X3792230Y131474D01*
G01D02*
X3792328D01*
G01X3792787D02*
X3792885D01*
G01X3792393Y131274D02*
X3792722D01*
G01X3792410Y131206D02*
X3792705D01*
G01X3792623Y130687D02*
X3792492D01*
G01X3792216Y128130D02*
X3804815D01*
G01Y134035D02*
X3792216D01*
G01X3778673Y399590D02*
G03X3782610Y395653I3937J0D01*
G01X3797570D02*
X3782610D01*
G01X3784578Y401559D02*
Y397779D01*
G01X3783791Y401559D02*
Y398567D01*
G01X3783397Y398720D02*
Y433602D01*
G01X3782610Y411543D02*
Y398567D01*
G01X3781822Y401165D02*
Y397779D01*
G01X3780248Y401165D02*
Y413173D01*
G01X3778673Y399590D02*
Y483448D01*
G01X3781822Y397779D02*
X3782610Y398567D01*
G01X3784578Y397779D02*
X3783791Y398567D01*
G01X3780248Y401165D02*
X3782610D01*
G01Y399980D02*
X3783397D01*
G01Y399389D02*
X3782610D01*
G01X3783397Y399310D02*
X3782610D01*
G01X3783397Y399193D02*
X3782610D01*
G01Y398956D02*
X3783397D01*
G01Y398799D02*
X3782610D01*
G01X3783397Y398720D02*
X3782610D01*
G01X3783791Y398567D02*
X3782610D01*
G01X3784578Y397779D02*
X3781822D01*
G01X3784185Y422618D02*
Y403090D01*
G01X3783791Y405889D02*
Y401952D01*
G01X3783200Y418511D02*
Y405519D01*
G01X3782610Y412487D02*
Y411543D01*
G01X3782413Y419298D02*
Y404731D01*
G01X3782610Y411543D02*
X3782413D01*
G01X3782610Y411424D02*
X3782413D01*
G01X3783397Y407566D02*
X3783200D01*
G01X3782610Y406812D02*
X3782413D01*
G01X3782610Y406778D02*
X3782413D01*
G01Y406700D02*
X3782610D01*
G01X3783200Y405913D02*
X3783397D01*
G01X3783791Y405889D02*
X3778673D01*
G01X3783200Y405519D02*
X3783397D01*
G01X3782413Y404731D02*
X3782610D01*
G01X3793450Y403090D02*
X3782610D01*
G01X3783397Y402342D02*
X3782610D01*
G01Y402303D02*
X3783397D01*
G01X3783791Y401952D02*
X3796389D01*
G01X3791032Y401559D02*
X3783791D01*
G01X3782610Y412487D02*
Y484472D01*
G01Y417290D02*
X3782413D01*
G01Y417218D02*
X3782610D01*
G01X3783397Y417015D02*
X3783200D01*
G01X3778673Y415063D02*
X3780506D01*
G01X3780248Y413173D02*
X3778673D01*
G01X3782610Y413156D02*
X3782413D01*
G01X3782610Y412487D02*
X3782413D01*
G01X3783397Y412369D02*
X3783200D01*
G01X3783397Y412211D02*
X3783200D01*
G01X3792476Y422028D02*
Y403090D01*
G01X3791919Y422028D02*
Y403090D01*
G01X3791362D02*
Y422618D01*
G01X3791032Y401559D02*
X3794323Y404304D01*
G01X3784985Y420846D02*
G03X3785379Y421403I-197J557D01*
G01X3784198Y421240D02*
G03X3784591Y421796I-197J556D01*
G01Y421864D02*
G03X3784198Y422421I-590J1D01*
G01X3785379Y422258D02*
G03X3784985Y422815I-591J0D01*
G01X3783397Y420846D02*
G03X3783791Y421403I-197J557D01*
G01X3782610Y421240D02*
G03X3783004Y421796I-197J557D01*
G01X3783791Y422258D02*
G03X3783397Y422815I-591J0D01*
G01X3783004Y421864D02*
G03X3782610Y422421I-591J0D01*
G01X3784972Y421830D02*
G03I-1968J0D01*
G01X3785799Y421397D02*
Y422145D01*
G01X3785379Y421403D02*
Y422258D01*
G01X3784985Y420846D02*
Y420452D01*
G01Y423208D02*
Y422815D01*
G01X3784880Y421403D02*
Y422258D01*
G01X3784591Y421864D02*
Y421796D01*
G01X3784558Y420846D02*
Y420452D01*
G01Y423208D02*
Y422815D01*
G01X3784235Y421796D02*
Y421864D01*
G01X3784204Y422258D02*
Y421403D01*
G01X3784198Y423208D02*
Y422421D01*
G01Y421240D02*
Y420452D01*
G01X3784127Y422258D02*
Y421403D01*
G01X3783978Y420452D02*
Y420846D01*
G01Y422815D02*
Y423208D01*
G01X3783913D02*
Y422421D01*
G01Y421240D02*
Y420452D01*
G01X3783901D02*
Y420846D01*
G01Y422815D02*
Y423208D01*
G01X3783791Y421403D02*
Y422258D01*
G01X3783752Y421864D02*
Y421796D01*
G01X3783675Y421864D02*
Y421796D01*
G01X3783655Y420452D02*
Y423208D01*
G01X3783526Y422421D02*
Y423208D01*
G01Y420452D02*
Y421240D01*
G01X3783449Y422421D02*
Y423208D01*
G01Y420452D02*
Y421240D01*
G01X3783441Y420666D02*
Y422995D01*
G01X3783010Y420452D02*
Y423208D01*
G01X3783004Y421864D02*
Y421796D01*
G01X3782654Y420666D02*
Y422995D01*
G01X3790765Y422145D02*
X3789873Y422893D01*
G01X3783397Y426397D02*
X3782610D01*
G01X3797570Y426362D02*
X3782610D01*
G01Y425875D02*
X3783397D01*
G01Y425116D02*
X3782610D01*
G01Y423237D02*
X3783397D01*
G01X3784985Y423208D02*
X3782610D01*
G01X3789873Y422893D02*
X3790892D01*
G01X3783397Y422815D02*
X3784985D01*
G01X3791806Y422618D02*
X3782610D01*
G01X3784198Y422421D02*
X3782610D01*
G01X3783791Y422258D02*
X3785379D01*
G01X3785799Y422145D02*
X3790765D01*
G01X3784591Y421864D02*
X3783004D01*
G01X3784591Y421796D02*
X3783004D01*
G01X3785379Y421403D02*
X3783791D01*
G01X3791783Y421397D02*
X3785799D01*
G01X3782610Y421240D02*
X3784198D01*
G01X3782654Y421043D02*
X3783441D01*
G01X3783397Y420846D02*
X3784985D01*
G01Y420452D02*
X3782610D01*
G01X3783397Y420347D02*
X3782610D01*
G01X3782532Y419630D02*
X3782610D01*
G01X3782413Y419298D02*
X3782610D01*
G01Y419089D02*
X3783397D01*
G01X3783200Y418511D02*
X3783397D01*
G01Y418407D02*
X3782610D01*
G01X3783200Y418117D02*
X3783397D01*
G01X3782742Y434018D02*
X3782755Y434023D01*
G01X3782730Y434014D02*
X3782742Y434018D01*
G01X3782717Y434010D02*
X3782730Y434014D01*
G01X3782703Y434007D02*
X3782717Y434010D01*
G01X3785816Y433902D02*
X3785837Y434035D01*
G01X3785755Y433781D02*
X3785816Y433902D01*
G01X3785659Y433685D02*
X3785755Y433781D01*
G01X3785538Y433623D02*
X3785659Y433685D01*
G01X3785404Y433602D02*
X3785538Y433623D01*
G01X3782620Y433996D02*
X3782610D01*
G01X3782634D02*
X3782620D01*
G01X3782649Y433998D02*
X3782634Y433996D01*
G01X3782664Y434000D02*
X3782649Y433998D01*
G01X3783857Y433930D02*
X3783870Y434030D01*
G01X3783820Y433833D02*
X3783857Y433930D01*
G01X3783762Y433749D02*
X3783820Y433833D01*
G01X3783689Y433683D02*
X3783762Y433749D01*
G01X3783604Y433636D02*
X3783689Y433683D01*
G01X3783517Y433610D02*
X3783604Y433636D01*
G01X3783440Y433602D02*
X3783517Y433610D01*
G01X3782681Y434002D02*
X3782610Y433996D01*
G01X3782756Y434024D02*
X3782681Y434002D01*
G01X3782761Y434026D02*
X3782610Y433996D01*
G01X3783402Y433602D02*
X3783436D01*
G01X3784548Y433996D02*
G03X3784941Y434389I-1J394D01*
G01X3785404Y433602D02*
G03X3785837Y434035I0J433D01*
G01X3782610Y433996D02*
G03X3783004Y434389I0J394D01*
G01X3783437Y433602D02*
G03X3783870Y434035I0J433D01*
G01X3783421Y435570D02*
Y433602D01*
G01X3783409Y431043D02*
Y437736D01*
G01X3783397Y433602D02*
Y435570D01*
G01X3782634Y431043D02*
Y433996D01*
G01X3782609D02*
X3782628D01*
G01X3782610D02*
X3784548D01*
G01X3782628D02*
X3782634D01*
G01X3783437Y433602D02*
X3785404D01*
G01X3783437D02*
X3783397D01*
G01X3786612Y431043D02*
X3782610D01*
G01X3783413Y433602D02*
X3783440D01*
G01X3791783Y422145D02*
Y421397D01*
G01X3794842Y418681D02*
X3792476Y422028D01*
G01X3794285Y418681D02*
X3791919Y422028D01*
G01X3790892Y422893D02*
X3791783Y422145D01*
G01X3791919Y422028D02*
X3792476D01*
G01X3783604Y444974D02*
X3783689Y445022D01*
G01X3783517Y444948D02*
X3783604Y444974D01*
G01X3783440Y444941D02*
X3783517Y444948D01*
G01X3782974Y434934D02*
X3783004Y434783D01*
G01X3782889Y435061D02*
X3782974Y434934D01*
G01X3782761Y435147D02*
X3782889Y435061D01*
G01X3782610Y435177D02*
X3782761Y435147D01*
G01X3782959Y434208D02*
X3782975Y434243D01*
G01X3782940Y434175D02*
X3782959Y434208D01*
G01X3782918Y434144D02*
X3782940Y434175D01*
G01X3782892Y434115D02*
X3782918Y434144D01*
G01X3782987Y434278D02*
X3782975Y434243D01*
G01X3782996Y434315D02*
X3782987Y434278D01*
G01X3785538Y435549D02*
X3785404Y435570D01*
G01X3785659Y435487D02*
X3785538Y435549D01*
G01X3785755Y435392D02*
X3785659Y435487D01*
G01X3785816Y435271D02*
X3785755Y435392D01*
G01X3785837Y435137D02*
X3785816Y435271D01*
G01X3783517Y435563D02*
X3783439Y435570D01*
G01X3783604Y435537D02*
X3783517Y435563D01*
G01X3783689Y435489D02*
X3783604Y435537D01*
G01X3783762Y435423D02*
X3783689Y435489D01*
G01X3783820Y435340D02*
X3783762Y435423D01*
G01X3783857Y435243D02*
X3783820Y435340D01*
G01X3783870Y435143D02*
X3783857Y435243D01*
G01X3782889Y434111D02*
X3782761Y434026D01*
G01X3782974Y434239D02*
X3782889Y434111D01*
G01X3783004Y434389D02*
X3782974Y434239D01*
G01X3783402Y444941D02*
X3783436D01*
G01Y435570D02*
X3783402D01*
G01X3783397Y437737D02*
X3783399Y437736D01*
G01Y442775D02*
X3783397Y442774D01*
G01X3784941Y434783D02*
G03X3784548Y435177I-394J0D01*
G01X3785404Y444941D02*
G03X3785837Y445374I0J433D01*
G01Y435137D02*
G03X3785404Y435570I-433J0D01*
G01X3783004Y434783D02*
G03X3782610Y435177I-394J0D01*
G01X3783437Y444941D02*
G03X3783870Y445374I0J433D01*
G01Y435137D02*
G03X3783437Y435570I-433J0D01*
G01X3783002Y434354D02*
X3782996Y434315D01*
G01X3782975Y434243D02*
X3782988Y434278D01*
G01X3783004Y434393D02*
X3783002Y434353D01*
G01X3785837Y435137D02*
Y434035D01*
G01X3785830Y435137D02*
Y434035D01*
G01X3785447D02*
Y435137D01*
G01X3784941Y434783D02*
Y434389D01*
G01X3784935Y434783D02*
Y434389D01*
G01X3784616D02*
Y434783D01*
G01X3783882Y434035D02*
Y435137D01*
G01X3783870D02*
Y434035D01*
G01X3783421Y446909D02*
Y444941D01*
G01X3783409Y442775D02*
Y449074D01*
G01X3783397Y435570D02*
Y444941D01*
G01D02*
Y446909D01*
G01X3783016Y434783D02*
Y434389D01*
G01X3783004Y434783D02*
Y434389D01*
G01Y448484D02*
Y434547D01*
G01X3782634Y442775D02*
Y445334D01*
G01Y435177D02*
Y437736D01*
G01X3782862Y434087D02*
X3782892Y434115D01*
G01D02*
X3782893D01*
G01X3782862Y434087D02*
X3782828Y434062D01*
G01X3782892Y434115D02*
X3782862Y434087D01*
G01X3782829Y434063D02*
X3782793Y434041D01*
G01X3782613Y442775D02*
X3782610Y442774D01*
G01X3782755Y434023D02*
X3782753D01*
G01X3782794Y434041D02*
X3782755Y434023D01*
G01X3782610Y437737D02*
X3782613Y437736D01*
G01X3783439Y435570D02*
X3783413Y435571D01*
G01X3782629Y435177D02*
X3782628D01*
G01X3783397Y444941D02*
X3783437D01*
G01X3785404D02*
X3783437D01*
G01X3782610Y444462D02*
X3783397D01*
G01X3782610Y443845D02*
X3783397D01*
G01Y443702D02*
X3782610D01*
G01X3783397Y443675D02*
X3782610D01*
G01X3786612Y442775D02*
X3782613D01*
G01X3783397Y442774D02*
X3782610D01*
G01X3783397Y439356D02*
X3782610D01*
G01Y439329D02*
X3783397D01*
G01Y439186D02*
X3782610D01*
G01X3783397Y438569D02*
X3782610D01*
G01Y437737D02*
X3783397D01*
G01X3782613Y437736D02*
X3786612D01*
G01X3785404Y435570D02*
X3783437D01*
G01D02*
X3783397D01*
G01X3784548Y435177D02*
X3782610D01*
G01X3782628D02*
X3782609D01*
G01X3783870Y435137D02*
X3785837D01*
G01X3782610Y434822D02*
X3783397D01*
G01X3783016Y434783D02*
X3783022D01*
G01D02*
X3784941D01*
G01X3782610D02*
X3783016D01*
G01X3782610Y434389D02*
X3783016D01*
G01X3784941D02*
X3783022D01*
G01D02*
X3783016D01*
G01X3785837Y434035D02*
X3783870D01*
G01X3783413Y444941D02*
X3783440D01*
G01X3782742Y445357D02*
X3782755Y445362D01*
G01X3782730Y445353D02*
X3782742Y445357D01*
G01X3782717Y445349D02*
X3782730Y445353D01*
G01X3782703Y445346D02*
X3782717Y445349D01*
G01X3782620Y445335D02*
X3782610Y445334D01*
G01X3782634Y445335D02*
X3782620D01*
G01X3782649Y445336D02*
X3782634Y445335D01*
G01X3782664Y445338D02*
X3782649Y445336D01*
G01X3783857Y445268D02*
X3783870Y445368D01*
G01X3783820Y445172D02*
X3783857Y445268D01*
G01X3783762Y445088D02*
X3783820Y445172D01*
G01X3783689Y445022D02*
X3783762Y445088D01*
G01X3782974Y446272D02*
X3783004Y446122D01*
G01X3782889Y446400D02*
X3782974Y446272D01*
G01X3782761Y446485D02*
X3782889Y446400D01*
G01X3782610Y446515D02*
X3782761Y446485D01*
G01X3782681Y445341D02*
X3782610Y445334D01*
G01X3782756Y445362D02*
X3782681Y445341D01*
G01X3782959Y445546D02*
X3782975Y445581D01*
G01X3782940Y445513D02*
X3782959Y445546D01*
G01X3782918Y445482D02*
X3782940Y445513D01*
G01X3782892Y445454D02*
X3782918Y445482D01*
G01X3782761Y445365D02*
X3782610Y445334D01*
G01X3782889Y445450D02*
X3782761Y445365D01*
G01X3782974Y445578D02*
X3782889Y445450D01*
G01X3783004Y445728D02*
X3782974Y445578D01*
G01X3783517Y446901D02*
X3783439Y446909D01*
G01X3783604Y446876D02*
X3783517Y446901D01*
G01X3783689Y446828D02*
X3783604Y446876D01*
G01X3783762Y446762D02*
X3783689Y446828D01*
G01X3783820Y446678D02*
X3783762Y446762D01*
G01X3783857Y446581D02*
X3783820Y446678D01*
G01X3783870Y446481D02*
X3783857Y446581D01*
G01X3783436Y446909D02*
X3783402D01*
G01X3783397Y449076D02*
X3783399Y449074D01*
G01X3784548Y445334D02*
G03X3784941Y445728I-1J394D01*
G01Y446122D02*
G03X3784548Y446515I-393J0D01*
G01X3785837Y446476D02*
G03X3785404Y446909I-433J0D01*
G01X3783004Y446122D02*
G03X3782610Y446515I-394J-1D01*
G01Y445334D02*
G03X3783004Y445728I0J394D01*
G01X3783870Y446476D02*
G03X3783437Y446909I-433J0D01*
G01X3782975Y445581D02*
X3782988Y445617D01*
G01X3782996Y445654D02*
X3782987Y445617D01*
G01X3783002Y445692D02*
X3782996Y445653D01*
G01X3783004Y445731D02*
X3783002Y445692D01*
G01X3785837Y445374D02*
Y446476D01*
G01X3785830D02*
Y445374D01*
G01X3785447D02*
Y446476D01*
G01X3784941Y445728D02*
Y446122D01*
G01X3784935D02*
Y445728D01*
G01X3784616D02*
Y446122D01*
G01X3783882Y446476D02*
Y445374D01*
G01X3783870Y446476D02*
Y445374D01*
G01X3783397Y446909D02*
Y483685D01*
G01X3783016Y446122D02*
Y445728D01*
G01X3783004D02*
Y446122D01*
G01X3782634Y446515D02*
Y449074D01*
G01X3782892Y445453D02*
X3782893Y445454D01*
G01X3782862Y445426D02*
X3782828Y445400D01*
G01X3782892Y445453D02*
X3782862Y445425D01*
G01X3782829Y445401D02*
X3782793Y445379D01*
G01X3782755Y445362D02*
X3782753Y445361D01*
G01X3782794Y445380D02*
X3782755Y445362D01*
G01X3782610Y449076D02*
X3782613Y449074D01*
G01X3783439Y446909D02*
X3783413D01*
G01X3782629Y446515D02*
X3782628D01*
G01X3782610Y450334D02*
X3783397D01*
G01X3782610Y449076D02*
X3783397D01*
G01X3782613Y449074D02*
X3786612D01*
G01X3783397Y446909D02*
X3783437D01*
G01X3785404D02*
X3783437D01*
G01X3784548Y446515D02*
X3782610D01*
G01X3782628D02*
X3782609D01*
G01X3783870Y446476D02*
X3785837D01*
G01X3783016Y446122D02*
X3783022D01*
G01D02*
X3784941D01*
G01X3782610D02*
X3783016D01*
G01X3783022Y445728D02*
X3784941D01*
G01X3783016D02*
X3782610D01*
G01X3783022D02*
X3783016D01*
G01X3785837Y445374D02*
X3783870D01*
G01X3782609Y445334D02*
X3782628D01*
G01X3782610D02*
X3784548D01*
G01X3782628D02*
X3782634D01*
G01X3784985Y460216D02*
G03X3785379Y460773I-197J557D01*
G01X3783397Y460216D02*
G03X3783791Y460773I-197J557D01*
G01X3782610Y460610D02*
G03X3783004Y461167I-197J557D01*
G01Y461234D02*
G03X3782610Y461791I-591J0D01*
G01X3784591Y461234D02*
G03X3784198Y461791I-590J1D01*
G01Y460610D02*
G03X3784591Y461167I-197J556D01*
G01X3784972Y461200D02*
G03I-1968J0D01*
G01X3784221Y460772D02*
G03X3784440Y460775I57J3846D01*
G01X3785379Y461628D02*
Y460773D01*
G01X3784985Y460216D02*
Y459822D01*
G01X3784880Y460773D02*
Y461628D01*
G01X3784591Y461167D02*
Y461234D01*
G01X3784558Y460216D02*
Y459822D01*
G01X3784440Y461628D02*
Y460773D01*
G01X3784235Y461167D02*
Y461234D01*
G01X3784198Y460610D02*
Y459822D01*
G01X3783978D02*
Y460216D01*
G01X3783913Y460610D02*
Y459822D01*
G01X3783901D02*
Y460216D01*
G01X3783791Y461628D02*
Y460773D01*
G01X3783752Y461234D02*
Y461167D01*
G01X3783675Y461234D02*
Y461167D01*
G01X3783655Y459822D02*
Y462578D01*
G01X3783526Y459822D02*
Y460610D01*
G01X3783449Y459822D02*
Y460610D01*
G01X3783441Y460036D02*
Y462365D01*
G01X3783010Y459822D02*
Y462578D01*
G01X3783004Y461167D02*
Y461234D01*
G01X3782654Y460036D02*
Y462365D01*
G01X3784221Y460771D02*
X3784137Y460773D01*
G01X3784591Y461234D02*
X3783004D01*
G01X3784591Y461167D02*
X3783004D01*
G01X3784137Y460773D02*
X3783791D01*
G01X3785379D02*
X3784440D01*
G01X3782610Y460610D02*
X3784198D01*
G01X3783441Y460413D02*
X3782654D01*
G01X3783397Y460216D02*
X3784985D01*
G01Y459822D02*
X3782610D01*
G01X3783397Y459794D02*
X3782610D01*
G01Y457915D02*
X3783397D01*
G01Y457156D02*
X3782610D01*
G01X3797570Y456677D02*
X3782610D01*
G01X3783397Y454114D02*
X3782610D01*
G01X3785379Y461628D02*
G03X3784985Y462185I-591J0D01*
G01X3783791Y461628D02*
G03X3783397Y462185I-591J0D01*
G01X3784440Y461628D02*
G03X3784221Y461630I-145J-3863D01*
G01X3784985Y462578D02*
Y462185D01*
G01X3784558Y462578D02*
Y462185D01*
G01X3784198Y462578D02*
Y461791D01*
G01X3783978Y462185D02*
Y462578D01*
G01X3783913D02*
Y461791D01*
G01X3783901Y462185D02*
Y462578D01*
G01X3783526Y461791D02*
Y462578D01*
G01X3783449Y461791D02*
Y462578D01*
G01X3783397Y465689D02*
X3782610D01*
G01Y464624D02*
X3783397D01*
G01Y463942D02*
X3782610D01*
G01Y462684D02*
X3783397D01*
G01X3784985Y462578D02*
X3782610D01*
G01X3783397Y462185D02*
X3784985D01*
G01X3782654Y461988D02*
X3783441D01*
G01X3782610Y461791D02*
X3784198D01*
G01X3784440Y461628D02*
X3785379D01*
G01X3783791D02*
X3784127D01*
G01D02*
X3784221Y461630D01*
G01X3783791Y481086D02*
Y477149D01*
G01X3778673D02*
X3783791D01*
G01X3783397Y471988D02*
X3782610D01*
G01X3778673Y470259D02*
X3782610D01*
G01Y467976D02*
X3778673D01*
G01X3784575Y481472D02*
Y484472D01*
G01X3783788Y483685D02*
Y481472D01*
G01X3783397Y481870D02*
X3782610D01*
G01X3783788Y481472D02*
X3791032D01*
G01X3783791Y481086D02*
X3796389D01*
G01X3783397Y480689D02*
X3782610D01*
G01X3794323Y478727D02*
X3791032Y481472D01*
G01X3782610Y487385D02*
G03X3778673Y483448I0J-3937D01*
G01X3790428Y487464D02*
Y487385D01*
G01X3790250Y487464D02*
Y487385D01*
G01X3790131Y487464D02*
Y487385D01*
G01X3789537Y487464D02*
Y487385D01*
G01X3789419D02*
Y487464D01*
G01X3789240D02*
Y487385D01*
G01X3789181D02*
Y487464D01*
G01X3789122D02*
Y487385D01*
G01X3788884Y487464D02*
Y487385D01*
G01X3788765Y487464D02*
Y487385D01*
G01X3787934Y487464D02*
Y487385D01*
G01X3783788Y483685D02*
X3784575Y484472D01*
G01X3791734Y487464D02*
X3787934D01*
G01X3782610Y487385D02*
X3797570D01*
G01X3784575Y484472D02*
X3782610D01*
G01X3783788Y483685D02*
X3782610D01*
G01X3783397Y483641D02*
X3782610D01*
G01X3791734Y487464D02*
Y487385D01*
G01X3791217D02*
Y487464D01*
G01X3790903D02*
Y487385D01*
G01X3790784Y487464D02*
Y487385D01*
G01X3790546Y487464D02*
Y487385D01*
G01X3790487D02*
Y487464D01*
G01X3789513Y1453929D02*
Y1434916D01*
G01X3799889Y-1176456D02*
X3800539Y-1177466D01*
X3801405Y-1178044D01*
X3802379Y-1178188D01*
X3803245Y-1178044D01*
X3804112Y-1177322D01*
X3804653Y-1176456D01*
X3804761Y-1175590D01*
X3804545Y-1174579D01*
X3803787Y-1173858D01*
X3803029Y-1173569D01*
X3802054D01*
G01X3803029D02*
X3803678Y-1173136D01*
X3804220Y-1172414D01*
X3804436Y-1171548D01*
X3804220Y-1170682D01*
X3803678Y-1169960D01*
X3802704Y-1169527D01*
X3801730Y-1169671D01*
X3800755Y-1170249D01*
G01X3810932Y-1178477D02*
X3810715Y-1178332D01*
Y-1178044D01*
X3810932Y-1177899D01*
X3811149Y-1178044D01*
Y-1178332D01*
X3810932Y-1178477D01*
G01X3817536Y-1170970D02*
X3818186Y-1170105D01*
X3818943Y-1169671D01*
X3819810Y-1169527D01*
X3820892Y-1169816D01*
X3821650Y-1170537D01*
X3821867Y-1171403D01*
X3821758Y-1172270D01*
X3821325Y-1172991D01*
X3819160Y-1174435D01*
X3818186Y-1175445D01*
X3817536Y-1176889D01*
X3817319Y-1178188D01*
X3821867D01*
G01X3828254Y-1169527D02*
X3827388Y-1169816D01*
X3826738Y-1170537D01*
X3826305Y-1171403D01*
X3825980Y-1172558D01*
X3825872Y-1173858D01*
X3825980Y-1175157D01*
X3826305Y-1176312D01*
X3826738Y-1177178D01*
X3827388Y-1177899D01*
X3828254Y-1178188D01*
X3829120Y-1177899D01*
X3829770Y-1177178D01*
X3830203Y-1176312D01*
X3830528Y-1175157D01*
X3830636Y-1173858D01*
X3830528Y-1172558D01*
X3830203Y-1171403D01*
X3829770Y-1170537D01*
X3829120Y-1169816D01*
X3828254Y-1169527D01*
G01X3801148Y-988069D02*
X3801798Y-989079D01*
X3802664Y-989657D01*
X3803638Y-989801D01*
X3804504Y-989657D01*
X3805371Y-988935D01*
X3805912Y-988069D01*
X3806020Y-987203D01*
X3805804Y-986192D01*
X3805046Y-985471D01*
X3804288Y-985182D01*
X3803313D01*
G01X3804288D02*
X3804937Y-984749D01*
X3805479Y-984027D01*
X3805695Y-983161D01*
X3805479Y-982295D01*
X3804937Y-981573D01*
X3803963Y-981140D01*
X3802989Y-981284D01*
X3802014Y-981862D01*
G01X3812191Y-990090D02*
X3811974Y-989945D01*
Y-989657D01*
X3812191Y-989512D01*
X3812408Y-989657D01*
Y-989945D01*
X3812191Y-990090D01*
G01X3818795Y-982583D02*
X3819445Y-981718D01*
X3820202Y-981284D01*
X3821069Y-981140D01*
X3822151Y-981429D01*
X3822909Y-982150D01*
X3823126Y-983016D01*
X3823017Y-983883D01*
X3822584Y-984604D01*
X3820419Y-986048D01*
X3819445Y-987058D01*
X3818795Y-988502D01*
X3818578Y-989801D01*
X3823126D01*
G01X3829513Y-981140D02*
X3828647Y-981429D01*
X3827997Y-982150D01*
X3827564Y-983016D01*
X3827239Y-984171D01*
X3827131Y-985471D01*
X3827239Y-986770D01*
X3827564Y-987925D01*
X3827997Y-988791D01*
X3828647Y-989512D01*
X3829513Y-989801D01*
X3830379Y-989512D01*
X3831029Y-988791D01*
X3831462Y-987925D01*
X3831787Y-986770D01*
X3831895Y-985471D01*
X3831787Y-984171D01*
X3831462Y-983016D01*
X3831029Y-982150D01*
X3830379Y-981429D01*
X3829513Y-981140D01*
G01X3803730Y-976561D02*
X3802647Y-975117D01*
X3802106Y-973674D01*
Y-967900D01*
X3802647Y-966456D01*
X3803730Y-965013D01*
G01X3810767Y-973674D02*
Y-965013D01*
X3813365D01*
X3814231Y-965446D01*
X3814881Y-966456D01*
X3815097Y-967611D01*
X3814881Y-968766D01*
X3814339Y-969632D01*
X3813365Y-970065D01*
X3810767D01*
G01X3818886Y-973674D02*
X3821593Y-965013D01*
X3824300Y-973674D01*
G01X3823325Y-970643D02*
X3819861D01*
G01X3827872Y-973674D02*
Y-965013D01*
X3830037D01*
X3830904Y-965446D01*
X3831553Y-966023D01*
X3832095Y-966889D01*
X3832528Y-967900D01*
X3832636Y-969344D01*
X3832528Y-970787D01*
X3832095Y-971798D01*
X3831553Y-972664D01*
X3830904Y-973241D01*
X3830037Y-973674D01*
X3827872D01*
G01X3839456Y-976561D02*
X3840539Y-975117D01*
X3841080Y-973674D01*
Y-967900D01*
X3840539Y-966456D01*
X3839456Y-965013D01*
G01X3805405Y84822D02*
X3806389Y86527D01*
G01X3803437Y84822D02*
X3804421Y86527D01*
G01X3802846Y85845D02*
Y92696D01*
G01X3802452Y86527D02*
Y97421D01*
G01X3806389Y86527D02*
X3807374Y84822D01*
G01X3804421Y86527D02*
X3805405Y84822D01*
G01X3802452Y86527D02*
X3803437Y84822D01*
G01X3807374D02*
X3808358Y86527D01*
G01D02*
Y97421D01*
G01X3807964Y85845D02*
Y97421D01*
G01X3798515Y99586D02*
G03I-1574J0D01*
G01X3798712D02*
G03I-1771J0D01*
G01X3818200Y97421D02*
X3802452D01*
G01X3802846Y115334D02*
Y105492D01*
G01X3798122D02*
Y115334D01*
G01X3802846Y105492D02*
X3798122D01*
G01X3809704Y98141D02*
X3809622Y98078D01*
G01X3809601Y98204D02*
X3809642Y98246D01*
G01X3808514Y97764D02*
X3808432Y97681D01*
G01X3809765Y98225D02*
X3809704Y98141D01*
G01X3808432Y97869D02*
X3808391Y97806D01*
G01X3808556Y97848D02*
X3808514Y97764D01*
G01X3808432Y97681D02*
X3808350Y97639D01*
G01X3808391Y97806D02*
X3808330Y97764D01*
G01X3809786Y98288D02*
X3809765Y98225D01*
G01X3809642Y98246D02*
X3809663Y98309D01*
G01X3808453Y97953D02*
X3808432Y97869D01*
G01X3808576Y97953D02*
X3808556Y97848D01*
G01X3809540Y98183D02*
X3809601Y98204D01*
G01X3809786Y98372D02*
Y98288D01*
G01X3809663Y98309D02*
Y98372D01*
G01X3809150Y98497D02*
Y98183D01*
G01Y98057D02*
Y97618D01*
G01X3809027D02*
Y98602D01*
G01X3808863D02*
Y97618D01*
G01X3808740D02*
Y98602D01*
G01X3808576Y98267D02*
Y97953D01*
G01X3808453Y98267D02*
Y97953D01*
G01X3807879Y97743D02*
Y98476D01*
G01X3807756Y97618D02*
Y98602D01*
G01X3808556Y98372D02*
X3808576Y98267D01*
G01X3808432Y98351D02*
X3808453Y98267D01*
G01X3809765Y98435D02*
X3809786Y98372D01*
G01X3809663D02*
X3809642Y98435D01*
G01X3808514Y98456D02*
X3808556Y98372D01*
G01X3808391Y98413D02*
X3808432Y98351D01*
G01X3809704Y98518D02*
X3809765Y98435D01*
G01X3809642D02*
X3809601Y98476D01*
G01X3808432Y98539D02*
X3808514Y98456D01*
G01X3809622Y98581D02*
X3809704Y98518D01*
G01X3808330Y98456D02*
X3808391Y98413D01*
G01X3808350Y98581D02*
X3808432Y98539D01*
G01X3809601Y98476D02*
X3809540Y98497D01*
G01X3808248Y98476D02*
X3808330Y98456D01*
G01X3809519Y98602D02*
X3809622Y98581D01*
G01X3808248Y98602D02*
X3808350Y98581D01*
G01X3809027Y98602D02*
X3809519D01*
G01X3808740D02*
X3808863D01*
G01X3807756D02*
X3808248D01*
G01X3809540Y98497D02*
X3809150D01*
G01X3807879Y98476D02*
X3808248D01*
G01X3809150Y98183D02*
X3809540D01*
G01X3809519Y98057D02*
X3809150D01*
G01X3808248Y97743D02*
X3807879D01*
G01X3809150Y97618D02*
X3809027D01*
G01X3808863D02*
X3808740D01*
G01X3808248D02*
X3807756D01*
G01X3809622Y98078D02*
X3809519Y98057D01*
G01X3808350Y97639D02*
X3808248Y97618D01*
G01X3808330Y97764D02*
X3808248Y97743D01*
G01X3807964Y105492D02*
Y115334D01*
G01X3812689Y105492D02*
X3807964D01*
G01X3800482Y110865D02*
X3800236Y110572D01*
G01Y110907D02*
X3800482Y111200D01*
G01X3801665Y114350D02*
Y106476D01*
G01X3800728Y111200D02*
Y109232D01*
G01X3800482D02*
Y110865D01*
G01X3800236Y110572D02*
Y110907D01*
G01X3799303Y106476D02*
Y114350D01*
G01X3798122Y115334D02*
X3802846D01*
G01X3801665Y114350D02*
X3799303D01*
G01X3800482Y111200D02*
X3800728D01*
G01Y109232D02*
X3800482D01*
G01X3809145Y106476D02*
Y114350D01*
G01X3807964Y115334D02*
X3812689D01*
G01X3811507Y114350D02*
X3809145D01*
G01X3804815Y132067D02*
G03Y130098I0J-984D01*
G01X3804519Y131035D02*
X3804159Y130649D01*
G01X3804027D02*
X3804322Y130968D01*
G01X3798407Y130830D02*
X3798387Y130807D01*
G01Y130833D02*
X3798407Y130857D01*
G01X3797981Y130830D02*
X3797961Y130807D01*
G01Y130833D02*
X3797981Y130857D01*
G01X3799260Y130880D02*
X3799250Y130867D01*
G01X3798240Y130951D02*
X3798230Y130937D01*
G01X3797443Y130880D02*
X3797433Y130867D01*
G01X3796924Y130951D02*
X3796915Y130937D01*
G01X3795887Y130880D02*
X3795878Y130867D01*
G01X3795819Y130900D02*
X3795828Y130914D01*
G01X3795753Y130937D02*
X3795743Y130924D01*
G01X3798998Y130837D02*
X3799004Y130847D01*
G01X3798243Y130928D02*
X3798250Y130937D01*
G01X3798099Y130833D02*
X3798106Y130844D01*
G01X3798010Y130864D02*
X3798017Y130874D01*
G01X3797741Y130924D02*
X3797748Y130934D01*
G01X3797600Y130924D02*
X3797607Y130934D01*
G01X3797370Y130837D02*
X3797377Y130847D01*
G01X3797072Y130924D02*
X3797078Y130934D01*
G01X3796928Y130928D02*
X3796934Y130937D01*
G01X3796856Y130833D02*
X3796862Y130844D01*
G01X3796770Y130864D02*
X3796777Y130874D01*
G01X3796704Y130833D02*
X3796718Y130854D01*
G01X3796767Y130937D02*
X3796773Y130948D01*
G01X3796652Y130937D02*
X3796639Y130917D01*
G01X3796337Y130833D02*
X3796344Y130844D01*
G01X3796252Y130864D02*
X3796258Y130874D01*
G01X3796248Y130937D02*
X3796255Y130948D01*
G01X3795819Y130837D02*
X3795825Y130847D01*
G01X3795753Y130864D02*
X3795746Y130854D01*
G01X3798309Y130867D02*
X3798325Y130877D01*
G01X3798256Y130961D02*
X3798240Y130951D01*
G01X3796993Y130867D02*
X3797009Y130877D01*
G01X3796698Y130810D02*
X3796714Y130820D01*
G01X3796941Y130961D02*
X3796924Y130951D01*
G01X3796659Y130961D02*
X3796642Y130951D01*
G01X3795809Y130810D02*
X3795825Y130820D01*
G01X3795759Y130961D02*
X3795743Y130951D01*
G01X3798988Y130830D02*
X3798998Y130837D01*
G01X3798932Y130941D02*
X3798922Y130934D01*
G01X3798089Y130827D02*
X3798099Y130833D01*
G01X3798250Y130937D02*
X3798259Y130944D01*
G01X3797810Y130837D02*
X3797800Y130830D01*
G01X3797748Y130934D02*
X3797757Y130941D01*
G01X3797607Y130934D02*
X3797617Y130941D01*
G01X3797361Y130830D02*
X3797370Y130837D01*
G01X3797305Y130941D02*
X3797295Y130934D01*
G01X3797141Y130837D02*
X3797131Y130830D01*
G01X3797078Y130934D02*
X3797088Y130941D01*
G01X3796846Y130827D02*
X3796856Y130833D01*
G01X3796934Y130937D02*
X3796944Y130944D01*
G01X3796695Y130827D02*
X3796704Y130833D01*
G01X3796773Y130948D02*
X3796783Y130954D01*
G01X3796662Y130944D02*
X3796652Y130937D01*
G01X3796327Y130827D02*
X3796337Y130833D01*
G01X3796255Y130948D02*
X3796265Y130954D01*
G01X3798319Y130894D02*
X3798306Y130884D01*
G01X3797003Y130894D02*
X3796990Y130884D01*
G01X3796777Y130874D02*
X3796790Y130884D01*
G01X3796258Y130874D02*
X3796271Y130884D01*
G01X3795806Y130827D02*
X3795819Y130837D01*
G01X3795825Y130887D02*
X3795838Y130897D01*
G01X3795766Y130874D02*
X3795753Y130864D01*
G01X3798017Y130874D02*
X3798099Y130948D01*
G01X3798125D02*
X3798033Y130864D01*
G01X3804405Y131051D02*
X3804519Y131168D01*
G01X3799277Y130870D02*
X3799270Y130864D01*
G01X3799017Y130830D02*
X3799004Y130817D01*
G01X3798903Y130941D02*
X3798916Y130954D01*
G01X3798119Y130830D02*
X3798106Y130817D01*
G01X3797817D02*
X3797830Y130830D01*
G01X3797741Y130954D02*
X3797728Y130941D01*
G01X3797600Y130954D02*
X3797587Y130941D01*
G01X3797459Y130870D02*
X3797452Y130864D01*
G01X3797390Y130830D02*
X3797377Y130817D01*
G01X3797275Y130941D02*
X3797289Y130954D01*
G01X3797147Y130817D02*
X3797161Y130830D01*
G01X3797072Y130954D02*
X3797059Y130941D01*
G01X3796875Y130830D02*
X3796862Y130817D01*
G01X3796796Y130870D02*
X3796790Y130864D01*
G01X3796714Y130820D02*
X3796724Y130830D01*
G01X3796790Y130941D02*
X3796783Y130934D01*
G01X3796642Y130951D02*
X3796632Y130941D01*
G01X3796357Y130830D02*
X3796344Y130817D01*
G01X3796278Y130870D02*
X3796271Y130864D01*
G01Y130941D02*
X3796265Y130934D01*
G01X3795904Y130870D02*
X3795897Y130864D01*
G01X3795825Y130820D02*
X3795835Y130830D01*
G01X3795746Y130880D02*
X3795737Y130870D01*
G01X3795743Y130951D02*
X3795733Y130941D01*
G01X3799024Y130844D02*
X3799017Y130830D01*
G01X3798033Y130864D02*
X3798027Y130850D01*
G01X3797728Y130941D02*
X3797722Y130928D01*
G01X3797587Y130941D02*
X3797580Y130928D01*
G01X3797397Y130844D02*
X3797390Y130830D01*
G01X3797059Y130941D02*
X3797052Y130928D01*
G01X3796790Y130864D02*
X3796783Y130850D01*
G01Y130934D02*
X3796780Y130928D01*
G01X3796724Y130830D02*
X3796731Y130844D01*
G01X3796632Y130941D02*
X3796626Y130928D01*
G01X3796271Y130864D02*
X3796265Y130850D01*
G01Y130934D02*
X3796261Y130928D01*
G01X3795737Y130870D02*
X3795730Y130857D01*
G01X3798230Y130937D02*
X3798224Y130921D01*
G01X3796915Y130937D02*
X3796908Y130921D01*
G01X3795835Y130830D02*
X3795842Y130847D01*
G01X3795838Y130897D02*
X3795845Y130914D01*
G01X3795733Y130941D02*
X3795727Y130924D01*
G01X3799605Y130944D02*
X3799559Y130807D01*
G01X3799539D02*
X3799592Y130964D01*
G01X3796521D02*
X3796468Y130807D01*
G01X3799270Y130864D02*
X3799267Y130854D01*
G01X3799250Y130867D02*
X3799247Y130857D01*
G01X3798922Y130934D02*
X3798919Y130924D01*
G01X3798240Y130917D02*
X3798243Y130928D01*
G01X3797813Y130847D02*
X3797810Y130837D01*
G01X3797452Y130864D02*
X3797449Y130854D01*
G01X3797433Y130867D02*
X3797430Y130857D01*
G01X3797295Y130934D02*
X3797292Y130924D01*
G01X3797144Y130847D02*
X3797141Y130837D01*
G01X3796924Y130917D02*
X3796928Y130928D01*
G01X3796763D02*
X3796767Y130937D01*
G01X3796731Y130844D02*
X3796734Y130854D01*
G01X3796626Y130928D02*
X3796622Y130917D01*
G01X3796485Y130911D02*
X3796455Y130820D01*
G01X3796488Y130924D02*
X3796501Y130964D01*
G01X3796245Y130928D02*
X3796248Y130937D01*
G01X3795897Y130864D02*
X3795894Y130854D01*
G01X3795878Y130867D02*
X3795874Y130857D01*
G01X3799004Y130847D02*
X3799007Y130860D01*
G01X3798899Y130928D02*
X3798903Y130941D01*
G01X3798122Y130844D02*
X3798119Y130830D01*
G01X3798007Y130850D02*
X3798010Y130864D01*
G01X3797830Y130830D02*
X3797833Y130844D01*
G01X3797597Y130911D02*
X3797600Y130924D01*
G01X3797377Y130847D02*
X3797380Y130860D01*
G01X3797161Y130830D02*
X3797164Y130844D01*
G01X3796878D02*
X3796875Y130830D01*
G01X3796767Y130850D02*
X3796770Y130864D01*
G01X3796360Y130844D02*
X3796357Y130830D01*
G01X3796248Y130850D02*
X3796252Y130864D01*
G01X3799027Y130860D02*
X3799024Y130844D01*
G01X3797580Y130928D02*
X3797577Y130911D01*
G01X3797400Y130860D02*
X3797397Y130844D01*
G01X3797272Y130924D02*
X3797275Y130941D01*
G01X3796734Y130854D02*
X3796737Y130870D01*
G01X3796622Y130917D02*
X3796619Y130900D01*
G01X3796718Y130854D02*
X3796721Y130874D01*
G01X3796639Y130917D02*
X3796635Y130897D01*
G01X3799273Y130887D02*
X3799260Y130880D01*
G01X3799004Y130817D02*
X3798991Y130810D01*
G01X3798916Y130954D02*
X3798929Y130961D01*
G01X3798106Y130817D02*
X3798092Y130810D01*
G01X3797804D02*
X3797817Y130817D01*
G01X3797754Y130961D02*
X3797741Y130954D01*
G01X3797377Y130817D02*
X3797364Y130810D01*
G01X3797613Y130961D02*
X3797600Y130954D01*
G01X3797456Y130887D02*
X3797443Y130880D01*
G01X3797134Y130810D02*
X3797147Y130817D01*
G01X3797289Y130954D02*
X3797302Y130961D01*
G01X3796862Y130817D02*
X3796849Y130810D01*
G01X3797085Y130961D02*
X3797072Y130954D01*
G01X3796796Y130944D02*
X3796790Y130941D01*
G01X3796783Y130954D02*
X3796796Y130961D01*
G01X3796344Y130817D02*
X3796330Y130810D01*
G01X3796278Y130944D02*
X3796271Y130941D01*
G01X3796265Y130954D02*
X3796278Y130961D01*
G01X3795901Y130887D02*
X3795887Y130880D01*
G01X3795819Y130884D02*
X3795825Y130887D01*
G01X3795806Y130894D02*
X3795819Y130900D01*
G01X3795753Y130884D02*
X3795746Y130880D01*
G01X3795766Y130944D02*
X3795753Y130937D01*
G01X3804815Y132067D02*
Y134035D01*
G01Y128130D02*
Y130098D01*
G01X3804618Y131437D02*
Y130649D01*
G01X3804519D02*
Y131035D01*
G01Y131168D02*
Y131437D01*
G01X3802452Y134035D02*
Y128130D01*
G01X3802289D02*
Y134035D01*
G01X3799815Y130964D02*
Y130807D01*
G01X3799795Y130827D02*
Y130870D01*
G01Y130891D02*
Y130944D01*
G01X3799710Y130870D02*
Y130891D01*
G01X3799696Y130944D02*
Y130964D01*
G01Y130807D02*
Y130827D01*
G01X3799513Y130964D02*
Y130807D01*
G01X3799493Y130827D02*
Y130870D01*
G01Y130891D02*
Y130944D01*
G01X3799408Y130870D02*
Y130891D01*
G01X3799395Y130944D02*
Y130964D01*
G01Y130807D02*
Y130827D01*
G01X3799369Y130807D02*
Y130964D01*
G01X3799349Y130824D02*
Y130874D01*
G01Y130964D02*
Y130894D01*
G01X3799267Y130854D02*
Y130844D01*
G01X3799247Y130857D02*
Y130844D01*
G01X3799218Y130964D02*
Y130807D01*
G01X3799198D02*
Y130944D01*
G01X3799100D02*
Y130964D01*
G01X3799073D02*
Y130807D01*
G01X3799054D02*
Y130964D01*
G01X3799027Y130911D02*
Y130860D01*
G01X3799007D02*
Y130911D01*
G01X3798948Y130897D02*
Y130877D01*
G01X3798919Y130924D02*
Y130897D01*
G01X3798899Y130877D02*
Y130928D01*
G01X3798873Y130964D02*
Y130807D01*
G01X3798854D02*
Y130870D01*
G01Y130891D02*
Y130964D01*
G01X3798761Y130870D02*
Y130807D01*
G01Y130964D02*
Y130891D01*
G01X3798742Y130807D02*
Y130964D01*
G01X3798716Y130824D02*
Y130807D01*
G01X3798663Y130964D02*
Y130824D01*
G01X3798643D02*
Y130964D01*
G01X3798591Y130807D02*
Y130824D01*
G01X3798407Y130857D02*
Y130830D01*
G01X3798387Y130964D02*
Y130833D01*
G01X3798368Y130807D02*
Y130964D01*
G01X3798342Y130807D02*
Y130894D01*
G01X3798325Y130877D02*
Y130824D01*
G01X3798240Y130911D02*
Y130917D01*
G01X3798230Y130824D02*
Y130807D01*
G01X3798224Y130921D02*
Y130907D01*
G01X3798197D02*
Y130891D01*
G01X3798151D02*
Y130907D01*
G01X3798125Y130964D02*
Y130948D01*
G01X3798027Y130850D02*
Y130844D01*
G01X3798007D02*
Y130850D01*
G01Y130948D02*
Y130964D01*
G01X3797981Y130857D02*
Y130830D01*
G01X3797961Y130964D02*
Y130833D01*
G01X3797941Y130807D02*
Y130964D01*
G01X3797915Y130907D02*
Y130891D01*
G01X3797869D02*
Y130907D01*
G01X3797833Y130844D02*
Y130857D01*
G01X3797813Y130854D02*
Y130847D01*
G01X3797741Y130914D02*
Y130924D01*
G01X3797722Y130928D02*
Y130911D01*
G01X3797695Y130807D02*
Y130911D01*
G01X3797676D02*
Y130807D01*
G01X3797597D02*
Y130911D01*
G01X3797577D02*
Y130807D01*
G01X3797551D02*
Y130964D01*
G01X3797531Y130824D02*
Y130874D01*
G01Y130964D02*
Y130894D01*
G01X3797449Y130854D02*
Y130844D01*
G01X3797430Y130857D02*
Y130844D01*
G01X3797400Y130911D02*
Y130860D01*
G01X3797380D02*
Y130911D01*
G01X3797246Y130907D02*
Y130891D01*
G01X3797200D02*
Y130907D01*
G01X3797164Y130844D02*
Y130857D01*
G01X3797144Y130854D02*
Y130847D01*
G01X3797072Y130914D02*
Y130924D01*
G01X3797052Y130928D02*
Y130911D01*
G01X3797026Y130807D02*
Y130894D01*
G01X3797009Y130877D02*
Y130824D01*
G01X3796924Y130911D02*
Y130917D01*
G01X3796915Y130824D02*
Y130807D01*
G01X3796908Y130921D02*
Y130907D01*
G01X3796829Y130891D02*
Y130877D01*
G01X3796783Y130850D02*
Y130844D01*
G01X3796780Y130928D02*
Y130914D01*
G01X3796767Y130844D02*
Y130850D01*
G01X3796763Y130914D02*
Y130928D01*
G01X3796737Y130870D02*
Y130900D01*
G01X3796721Y130874D02*
Y130897D01*
G01X3796635D02*
Y130874D01*
G01X3796619Y130900D02*
Y130870D01*
G01X3796593Y130907D02*
Y130891D01*
G01X3796547D02*
Y130907D01*
G01X3796311Y130891D02*
Y130877D01*
G01X3796265Y130850D02*
Y130844D01*
G01X3796261Y130928D02*
Y130914D01*
G01X3796248Y130844D02*
Y130850D01*
G01X3796245Y130914D02*
Y130928D01*
G01X3796219Y130907D02*
Y130891D01*
G01X3796173D02*
Y130907D01*
G01X3796147Y130824D02*
Y130807D01*
G01X3796094Y130964D02*
Y130824D01*
G01X3796074D02*
Y130964D01*
G01X3796022Y130807D02*
Y130824D01*
G01X3795996Y130807D02*
Y130964D01*
G01X3795976Y130824D02*
Y130874D01*
G01Y130964D02*
Y130894D01*
G01X3795894Y130854D02*
Y130844D01*
G01X3795874Y130857D02*
Y130844D01*
G01X3795845Y130914D02*
Y130924D01*
G01X3795842Y130847D02*
Y130857D01*
G01X3795828Y130914D02*
Y130924D01*
G01X3795825Y130847D02*
Y130854D01*
G01X3795746D02*
Y130847D01*
G01X3795743Y130924D02*
Y130914D01*
G01X3795730Y130857D02*
Y130847D01*
G01X3795727Y130924D02*
Y130914D01*
G01X3794743Y134035D02*
Y128130D01*
G01X3794578Y134035D02*
Y128130D01*
G01X3796721Y130897D02*
X3796718Y130917D01*
G01X3796635Y130874D02*
X3796639Y130854D01*
G01X3799287Y130874D02*
X3799277Y130870D01*
G01X3797800Y130830D02*
X3797791Y130827D01*
G01X3797469Y130874D02*
X3797459Y130870D01*
G01X3797131Y130830D02*
X3797121Y130827D01*
G01X3796816Y130877D02*
X3796796Y130870D01*
G01X3796298Y130877D02*
X3796278Y130870D01*
G01X3795914Y130874D02*
X3795904Y130870D01*
G01X3799024Y130928D02*
X3799027Y130911D01*
G01X3798903Y130830D02*
X3798899Y130847D01*
G01X3797695Y130911D02*
X3797692Y130928D01*
G01X3797397D02*
X3797400Y130911D01*
G01X3797275Y130830D02*
X3797272Y130847D01*
G01X3796737Y130900D02*
X3796734Y130917D01*
G01X3796619Y130870D02*
X3796622Y130854D01*
G01X3799007Y130911D02*
X3799004Y130924D01*
G01X3798010Y130830D02*
X3798007Y130844D01*
G01X3797843Y130921D02*
X3797840Y130934D01*
G01X3797833Y130857D02*
X3797830Y130870D01*
G01X3797672Y130924D02*
X3797676Y130911D01*
G01X3797380D02*
X3797377Y130924D01*
G01X3797174Y130921D02*
X3797170Y130934D01*
G01X3797164Y130857D02*
X3797161Y130870D01*
G01X3796767Y130900D02*
X3796763Y130914D01*
G01X3796770Y130830D02*
X3796767Y130844D01*
G01X3796248Y130900D02*
X3796245Y130914D01*
G01X3796252Y130830D02*
X3796248Y130844D01*
G01X3799267D02*
X3799270Y130833D01*
G01X3799247Y130844D02*
X3799250Y130833D01*
G01X3798919Y130847D02*
X3798922Y130837D01*
G01X3798243Y130900D02*
X3798240Y130911D01*
G01X3797820Y130931D02*
X3797823Y130921D01*
G01X3797810Y130864D02*
X3797813Y130854D01*
G01X3797732Y130844D02*
X3797735Y130833D01*
G01X3797449Y130844D02*
X3797452Y130833D01*
G01X3797430Y130844D02*
X3797433Y130833D01*
G01X3797292Y130847D02*
X3797295Y130837D01*
G01X3797151Y130931D02*
X3797154Y130921D01*
G01X3797141Y130864D02*
X3797144Y130854D01*
G01X3797062Y130844D02*
X3797065Y130833D01*
G01X3796928Y130900D02*
X3796924Y130911D01*
G01X3796878Y130937D02*
X3796882Y130928D01*
G01X3796734Y130917D02*
X3796731Y130928D01*
G01X3796622Y130854D02*
X3796626Y130844D01*
G01X3796455Y130820D02*
X3796426Y130911D01*
G01X3796409Y130964D02*
X3796422Y130924D01*
G01X3796360Y130937D02*
X3796363Y130928D01*
G01X3795894Y130844D02*
X3795897Y130833D01*
G01X3795874Y130844D02*
X3795878Y130833D01*
G01X3799618Y130964D02*
X3799670Y130807D01*
G01X3796442D02*
X3796389Y130964D01*
G01X3799651Y130807D02*
X3799605Y130944D01*
G01X3799293Y130894D02*
X3799267Y130964D01*
G01X3797476Y130894D02*
X3797449Y130964D01*
G01X3795920Y130894D02*
X3795894Y130964D01*
G01X3799244D02*
X3799273Y130887D01*
G01X3797426Y130964D02*
X3797456Y130887D01*
G01X3795871Y130964D02*
X3795901Y130887D01*
G01X3798224Y130907D02*
X3798230Y130891D01*
G01X3796908Y130907D02*
X3796915Y130891D01*
G01X3795845Y130924D02*
X3795838Y130941D01*
G01X3795727Y130914D02*
X3795733Y130897D01*
G01X3795730Y130847D02*
X3795737Y130830D01*
G01X3799017Y130941D02*
X3799024Y130928D01*
G01X3798342Y130924D02*
X3798335Y130937D01*
G01X3798315D02*
X3798322Y130924D01*
G01X3797722Y130911D02*
X3797728Y130897D01*
G01X3797754Y130837D02*
X3797751Y130844D01*
G01X3797692Y130928D02*
X3797685Y130941D01*
G01X3797390D02*
X3797397Y130928D01*
G01X3797085Y130837D02*
X3797082Y130844D01*
G01X3797052Y130911D02*
X3797059Y130897D01*
G01X3797026Y130924D02*
X3797019Y130937D01*
G01X3797000D02*
X3797006Y130924D01*
G01X3796865Y130928D02*
X3796862Y130934D01*
G01X3796780Y130914D02*
X3796787Y130900D01*
G01X3796731Y130928D02*
X3796724Y130941D01*
G01X3796626Y130844D02*
X3796632Y130830D01*
G01X3796347Y130928D02*
X3796344Y130934D01*
G01X3796261Y130914D02*
X3796268Y130900D01*
G01X3795842Y130857D02*
X3795835Y130870D01*
G01X3797840Y130934D02*
X3797830Y130951D01*
G01X3797170Y130934D02*
X3797161Y130951D01*
G01X3804322Y130968D02*
X3804027Y131437D01*
G01X3804159D02*
X3804405Y131051D01*
G01X3799004Y130924D02*
X3798998Y130934D01*
G01X3798250Y130891D02*
X3798243Y130900D01*
G01X3798027Y130844D02*
X3798033Y130833D01*
G01X3797748Y130904D02*
X3797741Y130914D01*
G01X3797666Y130934D02*
X3797672Y130924D01*
G01X3797377D02*
X3797370Y130934D01*
G01X3797078Y130904D02*
X3797072Y130914D01*
G01X3796934Y130891D02*
X3796928Y130900D01*
G01X3796872Y130948D02*
X3796878Y130937D01*
G01X3796773Y130891D02*
X3796767Y130900D01*
G01X3796783Y130844D02*
X3796790Y130833D01*
G01X3796718Y130917D02*
X3796704Y130937D01*
G01X3796639Y130854D02*
X3796652Y130833D01*
G01X3796354Y130948D02*
X3796360Y130937D01*
G01X3796255Y130891D02*
X3796248Y130900D01*
G01X3796265Y130844D02*
X3796271Y130833D01*
G01X3795825Y130854D02*
X3795819Y130864D01*
G01X3795746Y130847D02*
X3795753Y130837D01*
G01X3799250Y130833D02*
X3799260Y130820D01*
G01X3798335Y130937D02*
X3798325Y130951D01*
G01X3798230Y130891D02*
X3798240Y130877D01*
G01X3797735Y130833D02*
X3797745Y130820D01*
G01X3797433Y130833D02*
X3797443Y130820D01*
G01X3797019Y130937D02*
X3797009Y130951D01*
G01X3797065Y130833D02*
X3797075Y130820D01*
G01X3796915Y130891D02*
X3796924Y130877D01*
G01X3795828Y130924D02*
X3795819Y130937D01*
G01X3795878Y130833D02*
X3795887Y130820D01*
G01X3795743Y130914D02*
X3795753Y130900D01*
G01X3799270Y130833D02*
X3799277Y130827D01*
G01X3799004Y130954D02*
X3799017Y130941D01*
G01X3798916Y130817D02*
X3798903Y130830D01*
G01X3798023Y130817D02*
X3798010Y130830D01*
G01X3797810Y130941D02*
X3797820Y130931D01*
G01X3797830Y130870D02*
X3797817Y130884D01*
G01X3797728Y130897D02*
X3797741Y130884D01*
G01X3797685Y130941D02*
X3797672Y130954D01*
G01X3797761Y130830D02*
X3797754Y130837D01*
G01X3797377Y130954D02*
X3797390Y130941D01*
G01X3797452Y130833D02*
X3797459Y130827D01*
G01X3797289Y130817D02*
X3797275Y130830D01*
G01X3797141Y130941D02*
X3797151Y130931D01*
G01X3797161Y130870D02*
X3797147Y130884D01*
G01X3797059Y130897D02*
X3797072Y130884D01*
G01X3796862Y130934D02*
X3796856Y130941D01*
G01X3796724D02*
X3796714Y130951D01*
G01X3796783Y130817D02*
X3796770Y130830D01*
G01X3796632D02*
X3796642Y130820D01*
G01X3796265Y130817D02*
X3796252Y130830D01*
G01X3795838Y130941D02*
X3795828Y130951D01*
G01X3795897Y130833D02*
X3795904Y130827D01*
G01X3795835Y130870D02*
X3795825Y130880D01*
G01X3795737Y130830D02*
X3795746Y130820D01*
G01X3797092Y130830D02*
X3797085Y130837D01*
G01X3796344Y130934D02*
X3796337Y130941D01*
G01X3799260Y130820D02*
X3799273Y130810D01*
G01X3797745Y130820D02*
X3797757Y130810D01*
G01X3797443Y130820D02*
X3797456Y130810D01*
G01X3797075Y130820D02*
X3797088Y130810D01*
G01X3795887Y130820D02*
X3795901Y130810D01*
G01X3795819Y130864D02*
X3795806Y130874D01*
G01X3795733Y130897D02*
X3795746Y130887D01*
G01X3795753Y130837D02*
X3795766Y130827D01*
G01X3798998Y130934D02*
X3798988Y130941D01*
G01X3798922Y130837D02*
X3798932Y130830D01*
G01X3798306Y130944D02*
X3798315Y130937D01*
G01X3798259Y130884D02*
X3798250Y130891D01*
G01X3798033Y130833D02*
X3798043Y130827D01*
G01X3797800Y130870D02*
X3797810Y130864D01*
G01X3797757Y130897D02*
X3797748Y130904D01*
G01X3797656Y130941D02*
X3797666Y130934D01*
G01X3797370D02*
X3797361Y130941D01*
G01X3797295Y130837D02*
X3797305Y130830D01*
G01X3797131Y130870D02*
X3797141Y130864D01*
G01X3797088Y130897D02*
X3797078Y130904D01*
G01X3796990Y130944D02*
X3797000Y130937D01*
G01X3796862Y130954D02*
X3796872Y130948D01*
G01X3796944Y130884D02*
X3796934Y130891D01*
G01X3796787Y130900D02*
X3796796Y130894D01*
G01X3796704Y130937D02*
X3796695Y130944D01*
G01X3796790Y130833D02*
X3796800Y130827D01*
G01X3796652Y130833D02*
X3796662Y130827D01*
G01X3796344Y130954D02*
X3796354Y130948D01*
G01X3796268Y130900D02*
X3796278Y130894D01*
G01X3796271Y130833D02*
X3796281Y130827D01*
G01X3798325Y130951D02*
X3798309Y130961D01*
G01X3798240Y130877D02*
X3798256Y130867D01*
G01X3797830Y130951D02*
X3797813Y130961D01*
G01X3797161Y130951D02*
X3797144Y130961D01*
G01X3797009Y130951D02*
X3796993Y130961D01*
G01X3796924Y130877D02*
X3796941Y130867D01*
G01X3796714Y130951D02*
X3796698Y130961D01*
G01X3796642Y130820D02*
X3796659Y130810D01*
G01X3795828Y130951D02*
X3795812Y130961D01*
G01X3795746Y130820D02*
X3795763Y130810D01*
G01X3798991Y130961D02*
X3799004Y130954D01*
G01X3798929Y130810D02*
X3798916Y130817D01*
G01X3798037Y130810D02*
X3798023Y130817D01*
G01X3797817Y130884D02*
X3797804Y130891D01*
G01X3797672Y130954D02*
X3797659Y130961D01*
G01X3797741Y130884D02*
X3797754Y130877D01*
G01X3797364Y130961D02*
X3797377Y130954D01*
G01X3797302Y130810D02*
X3797289Y130817D01*
G01X3797147Y130884D02*
X3797134Y130891D01*
G01X3797072Y130884D02*
X3797085Y130877D01*
G01X3796849Y130961D02*
X3796862Y130954D01*
G01X3796856Y130941D02*
X3796849Y130944D01*
G01X3796796Y130810D02*
X3796783Y130817D01*
G01X3796330Y130961D02*
X3796344Y130954D01*
G01X3796337Y130941D02*
X3796330Y130944D01*
G01X3796278Y130810D02*
X3796265Y130817D01*
G01X3795819Y130937D02*
X3795806Y130944D01*
G01X3795825Y130880D02*
X3795819Y130884D01*
G01X3795753Y130900D02*
X3795766Y130894D01*
G01X3795746Y130887D02*
X3795753Y130884D01*
G01X3796790D02*
X3796773Y130891D01*
G01X3796271Y130884D02*
X3796255Y130891D01*
G01X3799277Y130827D02*
X3799287Y130824D01*
G01X3797791Y130874D02*
X3797800Y130870D01*
G01X3797771Y130827D02*
X3797761Y130830D01*
G01X3797459Y130827D02*
X3797469Y130824D01*
G01X3797121Y130874D02*
X3797131Y130870D01*
G01X3797102Y130827D02*
X3797092Y130830D01*
G01X3795904Y130827D02*
X3795914Y130824D01*
G01X3798988Y130941D02*
X3798975Y130944D01*
G01X3798932Y130830D02*
X3798945Y130827D01*
G01X3798273Y130880D02*
X3798259Y130884D01*
G01X3797797Y130944D02*
X3797810Y130941D01*
G01X3797771Y130894D02*
X3797757Y130897D01*
G01X3797134Y130891D02*
X3797121Y130894D01*
G01X3796836Y130964D02*
X3796849Y130961D01*
G01X3797305Y130830D02*
X3797318Y130827D01*
G01X3796957Y130880D02*
X3796944Y130884D01*
G01X3795806Y130944D02*
X3795793Y130948D01*
G01X3795806Y130874D02*
X3795793Y130877D01*
G01X3798293Y130948D02*
X3798306Y130944D01*
G01X3797643D02*
X3797656Y130941D01*
G01X3797804Y130891D02*
X3797791Y130894D01*
G01X3797361Y130941D02*
X3797348Y130944D01*
G01X3797128D02*
X3797141Y130941D01*
G01X3796977Y130948D02*
X3796990Y130944D01*
G01X3797102Y130894D02*
X3797088Y130897D01*
G01X3796317Y130964D02*
X3796330Y130961D01*
G01X3795766Y130894D02*
X3795779Y130891D01*
G01X3795766Y130827D02*
X3795779Y130824D01*
G01X3798975Y130964D02*
X3798991Y130961D01*
G01X3799273Y130810D02*
X3799290Y130807D01*
G01X3798309Y130961D02*
X3798293Y130964D01*
G01X3798945Y130807D02*
X3798929Y130810D01*
G01X3797813Y130961D02*
X3797797Y130964D01*
G01X3798256Y130867D02*
X3798273Y130864D01*
G01X3797659Y130961D02*
X3797643Y130964D01*
G01X3798043Y130827D02*
X3798059Y130824D01*
G01X3797348Y130964D02*
X3797364Y130961D01*
G01X3797754Y130877D02*
X3797771Y130874D01*
G01X3797144Y130961D02*
X3797128Y130964D01*
G01X3797757Y130810D02*
X3797774Y130807D01*
G01X3796993Y130961D02*
X3796977Y130964D01*
G01X3796849Y130944D02*
X3796832Y130948D01*
G01X3797456Y130810D02*
X3797472Y130807D01*
G01X3797085Y130877D02*
X3797102Y130874D01*
G01X3796695Y130944D02*
X3796678Y130948D01*
G01X3797318Y130807D02*
X3797302Y130810D01*
G01X3796941Y130867D02*
X3796957Y130864D01*
G01X3797088Y130810D02*
X3797105Y130807D01*
G01X3796330Y130944D02*
X3796314Y130948D01*
G01X3796800Y130827D02*
X3796816Y130824D01*
G01X3796662Y130827D02*
X3796678Y130824D01*
G01X3795812Y130961D02*
X3795796Y130964D01*
G01X3796281Y130827D02*
X3796298Y130824D01*
G01X3795901Y130810D02*
X3795917Y130807D01*
G01X3795763Y130810D02*
X3795779Y130807D01*
G01X3798056D02*
X3798037Y130810D01*
G01X3796698Y130961D02*
X3796678Y130964D01*
G01X3796796Y130894D02*
X3796816Y130891D01*
G01X3796278Y130894D02*
X3796298Y130891D01*
G01X3796659Y130810D02*
X3796678Y130807D01*
G01X3796819D02*
X3796796Y130810D01*
G01X3796301Y130807D02*
X3796278Y130810D01*
G01X3804519Y131437D02*
X3804618D01*
G01X3804027D02*
X3804159D01*
G01X3798368Y130964D02*
X3798387D01*
G01X3798643D02*
X3798663D01*
G01X3798854D02*
X3798873D01*
G01X3798742D02*
X3798761D01*
G01X3798945D02*
X3798975D01*
G01X3799054D02*
X3799073D01*
G01X3799100D02*
X3799218D01*
G01X3799395D02*
X3799513D01*
G01X3799592D02*
X3799618D01*
G01X3799696D02*
X3799815D01*
G01X3796074D02*
X3796094D01*
G01X3796291D02*
X3796317D01*
G01X3796389D02*
X3796409D01*
G01X3796501D02*
X3796521D01*
G01X3796809D02*
X3796836D01*
G01X3797318D02*
X3797348D01*
G01X3797941D02*
X3797961D01*
G01X3798007D02*
X3798125D01*
G01X3795796D02*
X3795776D01*
G01X3795996D02*
X3795976D01*
G01X3795894D02*
X3795871D01*
G01X3796977D02*
X3796957D01*
G01X3797128D02*
X3797102D01*
G01X3797551D02*
X3797531D01*
G01X3797449D02*
X3797426D01*
G01X3797643D02*
X3797630D01*
G01X3797797D02*
X3797771D01*
G01X3798293D02*
X3798273D01*
G01X3799369D02*
X3799349D01*
G01X3799267D02*
X3799244D01*
G01X3798273Y130948D02*
X3798293D01*
G01X3796957D02*
X3796977D01*
G01X3795793D02*
X3795779D01*
G01X3796314D02*
X3796295D01*
G01X3796832D02*
X3796813D01*
G01X3798099D02*
X3798007D01*
G01X3797102Y130944D02*
X3797128D01*
G01X3797630D02*
X3797643D01*
G01X3797771D02*
X3797797D01*
G01X3797348D02*
X3797318D01*
G01X3798975D02*
X3798945D01*
G01X3799198D02*
X3799100D01*
G01X3799493D02*
X3799395D01*
G01X3799795D02*
X3799696D01*
G01X3796363Y130928D02*
X3796347D01*
G01X3796882D02*
X3796865D01*
G01X3798322Y130924D02*
X3798342D01*
G01X3796422D02*
X3796488D01*
G01X3797006D02*
X3797026D01*
G01X3797292D02*
X3797272D01*
G01X3797154Y130921D02*
X3797174D01*
G01X3797823D02*
X3797843D01*
G01X3796426Y130911D02*
X3796485D01*
G01X3796173Y130907D02*
X3796219D01*
G01X3796547D02*
X3796593D01*
G01X3797200D02*
X3797246D01*
G01X3797869D02*
X3797915D01*
G01X3798151D02*
X3798197D01*
G01X3798919Y130897D02*
X3798948D01*
G01X3795976Y130894D02*
X3795920D01*
G01X3797026D02*
X3797003D01*
G01X3797121D02*
X3797102D01*
G01X3797531D02*
X3797476D01*
G01X3797791D02*
X3797771D01*
G01X3798342D02*
X3798319D01*
G01X3799349D02*
X3799293D01*
G01X3798761Y130891D02*
X3798854D01*
G01X3799408D02*
X3799493D01*
G01X3799710D02*
X3799795D01*
G01X3795779D02*
X3795793D01*
G01X3796298D02*
X3796311D01*
G01X3796816D02*
X3796829D01*
G01X3796219D02*
X3796173D01*
G01X3796593D02*
X3796547D01*
G01X3797246D02*
X3797200D01*
G01X3797915D02*
X3797869D01*
G01X3798197D02*
X3798151D01*
G01X3796977Y130880D02*
X3796957D01*
G01X3798293D02*
X3798273D01*
G01X3795793Y130877D02*
X3795779D01*
G01X3796311D02*
X3796298D01*
G01X3796829D02*
X3796816D01*
G01X3798948D02*
X3798899D01*
G01X3797102Y130874D02*
X3797121D01*
G01X3797771D02*
X3797791D01*
G01X3795976D02*
X3795914D01*
G01X3797531D02*
X3797469D01*
G01X3799349D02*
X3799287D01*
G01X3798854Y130870D02*
X3798761D01*
G01X3799493D02*
X3799408D01*
G01X3799795D02*
X3799710D01*
G01X3798273Y130864D02*
X3798293D01*
G01X3796957D02*
X3796977D01*
G01X3798899Y130847D02*
X3798919D01*
G01X3797272D02*
X3797292D01*
G01X3796344Y130844D02*
X3796360D01*
G01X3796862D02*
X3796878D01*
G01X3798106D02*
X3798122D01*
G01X3797082D02*
X3797062D01*
G01X3797751D02*
X3797732D01*
G01X3798945Y130827D02*
X3798975D01*
G01X3799395D02*
X3799493D01*
G01X3799696D02*
X3799795D01*
G01X3797318D02*
X3797348D01*
G01X3797121D02*
X3797102D01*
G01X3797791D02*
X3797771D01*
G01X3798591Y130824D02*
X3798643D01*
G01X3798663D02*
X3798716D01*
G01X3799287D02*
X3799349D01*
G01X3795779D02*
X3795793D01*
G01X3795914D02*
X3795976D01*
G01X3796022D02*
X3796074D01*
G01X3796094D02*
X3796147D01*
G01X3796298D02*
X3796311D01*
G01X3796816D02*
X3796829D01*
G01X3797469D02*
X3797531D01*
G01X3798059D02*
X3798072D01*
G01X3797009D02*
X3796915D01*
G01X3798325D02*
X3798230D01*
G01Y130807D02*
X3798342D01*
G01X3799290D02*
X3799369D01*
G01X3795779D02*
X3795793D01*
G01X3795917D02*
X3795996D01*
G01X3796915D02*
X3797026D01*
G01X3797105D02*
X3797121D01*
G01X3797472D02*
X3797551D01*
G01X3797676D02*
X3797695D01*
G01X3797577D02*
X3797597D01*
G01X3797774D02*
X3797791D01*
G01X3796147D02*
X3796022D01*
G01X3796307D02*
X3796301D01*
G01X3796468D02*
X3796442D01*
G01X3796826D02*
X3796819D01*
G01X3797348D02*
X3797318D01*
G01X3797961D02*
X3797941D01*
G01X3798069D02*
X3798056D01*
G01X3798387D02*
X3798368D01*
G01X3798716D02*
X3798591D01*
G01X3798873D02*
X3798854D01*
G01X3798761D02*
X3798742D01*
G01X3798975D02*
X3798945D01*
G01X3799073D02*
X3799054D01*
G01X3799218D02*
X3799198D01*
G01X3799513D02*
X3799395D01*
G01X3799670D02*
X3799651D01*
G01X3799559D02*
X3799539D01*
G01X3799815D02*
X3799696D01*
G01X3804618Y130649D02*
X3804519D01*
G01X3804159D02*
X3804027D01*
G01X3796330Y130810D02*
X3796307Y130807D01*
G01X3796849Y130810D02*
X3796826Y130807D01*
G01X3798092Y130810D02*
X3798069Y130807D01*
G01X3796678Y130964D02*
X3796659Y130961D01*
G01X3796678Y130807D02*
X3796698Y130810D01*
G01X3795776Y130964D02*
X3795759Y130961D01*
G01X3796295Y130948D02*
X3796278Y130944D01*
G01X3795793Y130807D02*
X3795809Y130810D01*
G01X3796678Y130948D02*
X3796662Y130944D01*
G01X3796813Y130948D02*
X3796796Y130944D01*
G01X3796957Y130964D02*
X3796941Y130961D01*
G01X3796311Y130824D02*
X3796327Y130827D01*
G01X3797102Y130964D02*
X3797085Y130961D01*
G01X3797302D02*
X3797318Y130964D01*
G01X3796678Y130824D02*
X3796695Y130827D01*
G01X3796977Y130864D02*
X3796993Y130867D01*
G01X3796829Y130824D02*
X3796846Y130827D01*
G01X3797630Y130964D02*
X3797613Y130961D01*
G01X3797771Y130964D02*
X3797754Y130961D01*
G01X3797364Y130810D02*
X3797348Y130807D01*
G01X3798273Y130964D02*
X3798256Y130961D01*
G01X3798072Y130824D02*
X3798089Y130827D01*
G01X3798293Y130864D02*
X3798309Y130867D01*
G01X3798929Y130961D02*
X3798945Y130964D01*
G01X3798991Y130810D02*
X3798975Y130807D01*
G01X3795779Y130948D02*
X3795766Y130944D01*
G01X3795793Y130891D02*
X3795806Y130894D01*
G01X3795779Y130877D02*
X3795766Y130874D01*
G01X3796278Y130961D02*
X3796291Y130964D01*
G01X3795793Y130824D02*
X3795806Y130827D01*
G01X3796796Y130961D02*
X3796809Y130964D01*
G01X3796944Y130944D02*
X3796957Y130948D01*
G01X3797088Y130941D02*
X3797102Y130944D01*
G01X3796990Y130884D02*
X3796977Y130880D01*
G01X3797318Y130944D02*
X3797305Y130941D01*
G01X3797617D02*
X3797630Y130944D01*
G01X3797121Y130807D02*
X3797134Y130810D01*
G01X3797757Y130941D02*
X3797771Y130944D01*
G01X3797348Y130827D02*
X3797361Y130830D01*
G01X3798259Y130944D02*
X3798273Y130948D01*
G01X3797791Y130807D02*
X3797804Y130810D01*
G01X3798306Y130884D02*
X3798293Y130880D01*
G01X3798945Y130944D02*
X3798932Y130941D01*
G01X3798975Y130827D02*
X3798988Y130830D01*
G01X3809145Y158394D02*
Y376898D01*
G01X3854421Y158394D02*
X3809145D01*
G01X3854421Y201702D02*
X3809145D01*
G01Y333591D02*
X3854421D01*
G01X3809145Y376898D02*
X3854421D01*
G01X3797570Y395653D02*
G03X3801507Y399590I0J3937D01*
G01Y483448D02*
Y399590D01*
G01X3797570Y399153D02*
Y483878D01*
G01X3796783Y399941D02*
Y483090D01*
G01X3796389Y405889D02*
Y399941D01*
G01X3795602Y399153D02*
Y404504D01*
G01X3796389Y399941D02*
X3795602Y399153D01*
G01X3797570Y400177D02*
X3796783D01*
G01X3797570Y400098D02*
X3796783D01*
G01X3797570Y399941D02*
X3796389D01*
G01X3797570Y399153D02*
X3795602D01*
G01X3796389Y403336D02*
G03X3794323Y404304I-1260J0D01*
G01X3794842Y405059D02*
Y418681D01*
G01X3794285Y405059D02*
Y418681D01*
G01X3797570Y411004D02*
X3796783D01*
G01Y408498D02*
X3797570D01*
G01X3801507Y405889D02*
X3796389D01*
G01X3794842Y405059D02*
X3794285D01*
G01X3796783Y403326D02*
X3797570D01*
G01X3796783Y402067D02*
X3797570D01*
G01Y417303D02*
X3796783D01*
G01X3797570Y415063D02*
X3801507D01*
G01Y413173D02*
X3797570D01*
G01X3797515Y424911D02*
X3797556Y424723D01*
G01X3797515Y424914D02*
X3797556Y424723D01*
G01X3796763Y420177D02*
G03X3796783Y420157I20J0D01*
G01X3797531Y421165D02*
G03X3797570Y421077I118J0D01*
G01X3797059Y421165D02*
G03X3797570Y420580I590J0D01*
G01X3796193Y420177D02*
G03X3796783Y419587I590J0D01*
G01X3797059Y424708D02*
G03X3797048Y424818I-590J-3D01*
G01X3797570Y424573D02*
G03X3797556Y424723I-787J2D01*
G01X3797570Y424573D02*
G03X3797556Y424723I-789J2D01*
G01X3797531Y424708D02*
G03X3797511Y424913I-1063J0D01*
G01X3796193Y424357D02*
G03X3796182Y424468I-591J-2D01*
G01X3796763Y424357D02*
G03X3796743Y424574I-1161J2D01*
G01X3797531Y424708D02*
Y421165D01*
G01X3797059Y424708D02*
Y421165D01*
G01X3796763Y424357D02*
Y420177D01*
G01X3796193Y424357D02*
Y420177D01*
G01X3796743Y424574D02*
X3795182Y432782D01*
G01X3794621Y432676D02*
X3796182Y424468D01*
G01X3796107Y432180D02*
X3797515Y424911D01*
G01X3797556Y424723D02*
X3794573Y440069D01*
G01X3793800Y439918D02*
X3796783Y424573D01*
G01X3795183Y432790D02*
X3796783Y424573D01*
G01X3797512Y424911D02*
X3796056Y431985D01*
G01X3795594Y431890D02*
X3797048Y424818D01*
G01X3797570Y426148D02*
X3796783D01*
G01Y425821D02*
X3797570D01*
G01Y425084D02*
X3796783D01*
G01X3797531Y424708D02*
X3797059D01*
G01X3797570Y424573D02*
X3796783D01*
G01X3796763Y424357D02*
X3796193D01*
G01X3796783Y424284D02*
X3797570D01*
G01Y423695D02*
X3796783D01*
G01X3797570Y423011D02*
X3796783D01*
G01Y422958D02*
X3797570D01*
G01X3797531Y421165D02*
X3797059D01*
G01X3796763Y420177D02*
X3796193D01*
G01X3794842Y418681D02*
X3794285D01*
G01X3796182Y424468D02*
X3796743Y424574D01*
G01X3797556Y424723D02*
X3796783Y424573D01*
G01X3794741Y433156D02*
X3794644Y432982D01*
G01X3794890Y433288D02*
X3794741Y433156D01*
G01X3795074Y433363D02*
X3794890Y433288D01*
G01X3796107Y432180D02*
G03X3796056Y431985I173J-149D01*
G01X3795074Y433363D02*
G03X3794621Y432676I127J-577D01*
G01X3796010Y432678D02*
G03X3795594Y431890I270J-646D01*
G01X3794644Y432982D02*
X3794610Y432786D01*
G01D02*
X3794621Y432676D01*
G01X3795182Y432782D02*
X3794621Y432676D01*
G01X3796056Y431985D02*
X3795594Y431890D01*
G01X3795461Y440363D02*
X3795562D01*
G01X3795275Y440355D02*
X3795461Y440363D01*
G01X3796120Y440416D02*
X3796249Y440476D01*
G01X3796004Y440379D02*
X3796120Y440416D01*
G01X3795894Y440359D02*
X3796004Y440379D01*
G01X3795782Y440354D02*
X3795894Y440359D01*
G01X3795562Y440363D02*
X3795782Y440354D01*
G01X3795079Y442562D02*
X3795067Y442502D01*
G01X3795104Y442616D02*
X3795079Y442562D01*
G01X3795138Y442659D02*
X3795104Y442616D01*
G01X3795167Y442692D02*
X3795138Y442659D01*
G01X3795199Y442734D02*
X3795167Y442692D01*
G01X3795245Y442776D02*
X3795199Y442734D01*
G01X3795300Y442796D02*
X3795245Y442776D01*
G01X3795357Y442797D02*
X3795300Y442796D01*
G01X3795417Y442785D02*
X3795357Y442797D01*
G01X3795932Y442737D02*
X3795830Y442649D01*
G01X3796053Y442777D02*
X3795932Y442737D01*
G01X3796171Y442750D02*
X3796053Y442777D01*
G01X3795193Y440357D02*
X3795275Y440355D01*
G01X3795119Y440375D02*
X3795193Y440357D01*
G01X3795066Y440420D02*
X3795119Y440375D01*
G01X3795713Y440491D02*
X3795705Y440520D01*
G01X3795724Y440466D02*
X3795713Y440491D01*
G01X3795737Y440445D02*
X3795724Y440466D01*
G01X3795752Y440430D02*
X3795737Y440445D01*
G01X3796426Y442100D02*
X3796350Y442166D01*
G01X3796473Y441998D02*
X3796426Y442100D01*
G01X3796495Y441885D02*
X3796473Y441998D01*
G01X3796510Y441762D02*
X3796495Y441885D01*
G01X3796542Y441632D02*
X3796510Y441762D01*
G01X3796593Y441506D02*
X3796542Y441632D01*
G01X3796627Y441379D02*
X3796593Y441506D01*
G01X3796642Y441236D02*
X3796627Y441379D01*
G01X3796637Y441072D02*
X3796642Y441236D01*
G01X3796603Y440900D02*
X3796637Y441072D01*
G01X3797570Y442106D02*
G03X3797177Y441712I1J-394D01*
G01Y441318D02*
G03X3797570Y440925I394J1D01*
G01X3796783Y442500D02*
G03X3796389Y441943I197J-557D01*
G01Y441088D02*
G03X3796783Y440531I591J0D01*
G01X3799145Y441515D02*
G03I-1968J0D01*
G01X3795745Y441318D02*
G03X3796139Y440925I394J1D01*
G01Y442106D02*
G03X3795745Y441712I0J-394D01*
G01X3794957Y441088D02*
G03X3795351Y440531I591J0D01*
G01Y442500D02*
G03X3794957Y441943I197J-557D01*
G01X3797556Y458409D02*
X3794554Y442964D01*
G01X3796783Y458560D02*
X3793781Y443114D01*
G01X3797568Y442893D02*
Y440137D01*
G01X3797386Y440925D02*
Y440137D01*
G01Y442893D02*
Y442106D01*
G01X3797177Y441712D02*
Y441318D01*
G01X3797045D02*
Y441712D01*
G01X3796879Y440137D02*
Y442893D01*
G01X3796828Y440137D02*
Y442893D01*
G01X3796780D02*
Y440137D01*
G01X3796704Y440531D02*
Y440137D01*
G01Y442893D02*
Y442500D01*
G01X3796485Y440137D02*
Y442893D01*
G01X3796434Y440137D02*
Y442893D01*
G01X3796389Y441088D02*
Y441943D01*
G01X3796363Y441088D02*
Y441943D01*
G01X3796323Y442893D02*
Y442106D01*
G01Y440925D02*
Y440137D01*
G01X3796139Y442106D02*
Y442893D01*
G01Y440137D02*
Y440925D01*
G01X3795982Y441318D02*
Y441712D01*
G01X3795745D02*
Y441318D01*
G01X3795641Y440531D02*
Y440137D01*
G01Y442893D02*
Y442500D01*
G01X3795351Y440137D02*
Y440531D01*
G01Y442500D02*
Y442893D01*
G01X3795300Y441088D02*
Y441943D01*
G01X3794957Y441088D02*
Y441943D01*
G01X3794771Y444080D02*
X3793998Y444230D01*
G01X3794554Y442964D02*
X3793781Y443114D01*
G01X3796783Y443681D02*
X3797570D01*
G01Y442893D02*
X3795351D01*
G01X3796783Y442597D02*
X3797570D01*
G01X3795351Y442500D02*
X3796783D01*
G01X3797568Y442303D02*
X3796780D01*
G01X3797570Y442106D02*
X3796139D01*
G01X3796389Y441943D02*
X3794957D01*
G01X3795745Y441712D02*
X3797177D01*
G01Y441318D02*
X3795745D01*
G01X3794957Y441088D02*
X3796389D01*
G01X3796139Y440925D02*
X3797570D01*
G01X3797568Y440728D02*
X3796780D01*
G01X3796783Y440531D02*
X3795351D01*
G01X3797570Y440434D02*
X3796783D01*
G01X3797570Y440137D02*
X3795351D01*
G01X3797570Y439350D02*
X3796783D01*
G01X3797570Y437632D02*
X3796783D01*
G01Y436895D02*
X3797570D01*
G01X3796783Y436798D02*
X3797570D01*
G01X3796783Y434933D02*
X3797570D01*
G01Y434769D02*
X3796783D01*
G01X3794573Y440069D02*
X3793800Y439918D01*
G01X3794790Y438953D02*
X3794017Y438803D01*
G01X3794621Y450355D02*
G03X3795056Y449672I580J-111D01*
G01X3795594Y451141D02*
G03X3795992Y450361I686J-141D01*
G01X3796182Y458563D02*
X3794621Y450355D01*
G01D02*
X3794610Y450245D01*
G01X3795168Y450251D02*
X3794621Y450355D01*
G01X3795167Y450245D02*
X3794610D01*
G01X3796783Y448262D02*
X3797570D01*
G01Y448098D02*
X3796783D01*
G01X3797570Y446233D02*
X3796783D01*
G01X3797570Y446136D02*
X3796783D01*
G01Y445399D02*
X3797570D01*
G01X3796182Y458563D02*
G03X3796193Y458674I-580J113D01*
G01X3797048Y458213D02*
G03X3797059Y458323I-579J113D01*
G01X3797556Y458409D02*
G03X3797570Y458560I-773J148D01*
G01X3797556Y458409D02*
G03X3797570Y458560I-776J148D01*
G01X3797530Y458276D02*
G03X3797531Y458323I-1062J46D01*
G01X3796743Y458457D02*
G03X3796763Y458674I-1141J215D01*
G01X3796054Y451034D02*
G03X3796091Y450872I226J-34D01*
G01X3796056Y451045D02*
X3797296Y457074D01*
G01X3797048Y458213D02*
X3795594Y451141D01*
G01X3795824Y453624D02*
X3796743Y458457D01*
G01X3797531Y461866D02*
Y458323D01*
G01X3797059Y461866D02*
Y458323D01*
G01X3796763Y462854D02*
Y458674D01*
G01X3796193Y462854D02*
Y458674D01*
G01X3797296Y457074D02*
X3796834Y457169D01*
G01X3795594Y451141D02*
X3796056Y451045D01*
G01X3797556Y458409D02*
X3796783Y458560D01*
G01X3796182Y458563D02*
X3796743Y458457D01*
G01X3797570Y460073D02*
X3796783D01*
G01X3797570Y460019D02*
X3796783D01*
G01Y459336D02*
X3797570D01*
G01Y458746D02*
X3796783D01*
G01X3796763Y458674D02*
X3796193D01*
G01X3797570Y458560D02*
X3796783D01*
G01X3797531Y458323D02*
X3797059D01*
G01X3796783Y457947D02*
X3797570D01*
G01Y457210D02*
X3796783D01*
G01Y456883D02*
X3797570D01*
G01X3796783Y462873D02*
G03X3796763Y462854I0J-20D01*
G01X3797570Y461954D02*
G03X3797531Y461866I79J-88D01*
G01X3797570Y462452D02*
G03X3797059Y461866I80J-585D01*
G01X3796783Y463444D02*
G03X3796193Y462854I0J-590D01*
G01X3796763D02*
X3796193D01*
G01X3797531Y461866D02*
X3797059D01*
G01X3796389Y483090D02*
Y477149D01*
G01D02*
X3801507D01*
G01X3796783Y474533D02*
X3797570D01*
G01Y470259D02*
X3801507D01*
G01Y467976D02*
X3797570D01*
G01X3794323Y478727D02*
G03X3796389Y479695I806J968D01*
G01X3795602Y478527D02*
Y483878D01*
G01X3796389Y483090D02*
X3795602Y483878D01*
G01X3796389Y483090D02*
X3797570D01*
G01X3796783Y482933D02*
X3797570D01*
G01Y482854D02*
X3796783D01*
G01X3797570Y480964D02*
X3796783D01*
G01Y479704D02*
X3797570D01*
G01X3801507Y483448D02*
G03X3797570Y487385I-3937J0D01*
G01X3795602Y483878D02*
X3797570D01*
G01X3822866Y-1687172D02*
Y-1777302D01*
G01X3821766Y-1732490D02*
X4235421D01*
G01X3817217Y-1166179D02*
X3816134Y-1164735D01*
X3815593Y-1163292D01*
Y-1157518D01*
X3816134Y-1156074D01*
X3817217Y-1154631D01*
G01X3824254Y-1163292D02*
Y-1154631D01*
X3826852D01*
X3827718Y-1155064D01*
X3828368Y-1156074D01*
X3828584Y-1157229D01*
X3828368Y-1158384D01*
X3827826Y-1159250D01*
X3826852Y-1159683D01*
X3824254D01*
G01X3832373Y-1163292D02*
X3835080Y-1154631D01*
X3837787Y-1163292D01*
G01X3836812Y-1160261D02*
X3833348D01*
G01X3841359Y-1163292D02*
Y-1154631D01*
X3843524D01*
X3844391Y-1155064D01*
X3845040Y-1155641D01*
X3845582Y-1156507D01*
X3846015Y-1157518D01*
X3846123Y-1158962D01*
X3846015Y-1160405D01*
X3845582Y-1161416D01*
X3845040Y-1162282D01*
X3844391Y-1162859D01*
X3843524Y-1163292D01*
X3841359D01*
G01X3852943Y-1166179D02*
X3854026Y-1164735D01*
X3854567Y-1163292D01*
Y-1157518D01*
X3854026Y-1156074D01*
X3852943Y-1154631D01*
G01X3825287Y99586D02*
G03I-1575J0D01*
G01X3825484D02*
G03I-1772J0D01*
G01X3817270Y98141D02*
X3817188Y98078D01*
G01X3815917Y98183D02*
X3815404Y97722D01*
G01X3815240D02*
X3815814Y98246D01*
G01X3820920Y98204D02*
X3820961Y98246D01*
G01X3817168Y98204D02*
X3817209Y98246D01*
G01X3815281Y98456D02*
X3815363Y98539D01*
G01X3813395Y97681D02*
X3813477Y97764D01*
G01X3812472Y97681D02*
X3812554Y97764D01*
G01X3812923Y98539D02*
X3812841Y98456D01*
G01X3812000Y98539D02*
X3811918Y98456D01*
G01X3814953Y98435D02*
X3814830Y98288D01*
G01Y98456D02*
X3814953Y98602D01*
G01X3821022Y98141D02*
X3821084Y98225D01*
G01X3817332D02*
X3817270Y98141D01*
G01X3815958Y98246D02*
X3815917Y98183D01*
G01X3815404Y98435D02*
X3815363Y98372D01*
G01X3813395Y97869D02*
X3813354Y97806D01*
G01X3812472Y97869D02*
X3812431Y97806D01*
G01X3815814Y98246D02*
X3815855Y98330D01*
G01X3813477Y97764D02*
X3813518Y97848D01*
G01X3812554Y97764D02*
X3812595Y97848D01*
G01X3814543Y98393D02*
X3814256Y97618D01*
G01X3814174Y97722D02*
X3814482Y98602D01*
G01X3818377Y97743D02*
X3818665Y98602D01*
G01X3818787D02*
X3818459Y97618D01*
G01X3821084Y98225D02*
X3821105Y98288D01*
G01X3820961Y98246D02*
X3820982Y98309D01*
G01X3817352Y98288D02*
X3817332Y98225D01*
G01X3817209Y98246D02*
X3817229Y98309D01*
G01X3812943Y98351D02*
X3812964Y98413D01*
G01X3812021Y98351D02*
X3812041Y98413D01*
G01X3820941Y98100D02*
X3821022Y98141D01*
G01X3815363Y98539D02*
X3815445Y98581D01*
G01X3813313Y97639D02*
X3813395Y97681D01*
G01X3812390Y97639D02*
X3812472Y97681D01*
G01X3813005Y98581D02*
X3812923Y98539D01*
G01X3812082Y98581D02*
X3812000Y98539D01*
G01X3815466Y98476D02*
X3815404Y98435D01*
G01X3813354Y97806D02*
X3813292Y97764D01*
G01X3812431Y97806D02*
X3812369Y97764D01*
G01X3812964Y98413D02*
X3813026Y98456D01*
G01X3812041Y98413D02*
X3812103Y98456D01*
G01X3815978Y98330D02*
X3815958Y98246D01*
G01X3815261Y98372D02*
X3815281Y98456D01*
G01X3812841D02*
X3812820Y98372D01*
G01X3811918Y98456D02*
X3811898Y98372D01*
G01X3820859Y98183D02*
X3820920Y98204D01*
G01X3817106Y98183D02*
X3817168Y98204D01*
G01X3813026Y98456D02*
X3813087Y98476D01*
G01X3812103Y98456D02*
X3812164Y98476D01*
G01X3821105Y98288D02*
Y98372D01*
G01X3820982Y98309D02*
Y98372D01*
G01X3820469Y97618D02*
Y98057D01*
G01Y98497D02*
Y98183D01*
G01X3820346Y98602D02*
Y97618D01*
G01X3820182Y98602D02*
Y98497D01*
G01X3819854D02*
Y97618D01*
G01X3819731D02*
Y98497D01*
G01X3819403D02*
Y98602D01*
G01X3819239Y98078D02*
Y97974D01*
G01X3818952D02*
Y98078D01*
G01X3818200Y92696D02*
Y97421D01*
G01X3817803Y98078D02*
Y97974D01*
G01X3817516D02*
Y98078D01*
G01X3817352Y98372D02*
Y98288D01*
G01X3817229Y98309D02*
Y98372D01*
G01X3816717Y98497D02*
Y98183D01*
G01Y98057D02*
Y97618D01*
G01X3816593D02*
Y98602D01*
G01X3816430Y98078D02*
Y97974D01*
G01X3816142D02*
Y98078D01*
G01X3815978Y98372D02*
Y98330D01*
G01Y97722D02*
Y97618D01*
G01X3815855Y98330D02*
Y98372D01*
G01X3815240Y97618D02*
Y97722D01*
G01X3815076Y98602D02*
Y97618D01*
G01X3814953D02*
Y98435D01*
G01X3814830Y98288D02*
Y98456D01*
G01X3814666Y98602D02*
Y97618D01*
G01X3814543D02*
Y98393D01*
G01X3813805D02*
Y97618D01*
G01X3813682D02*
Y98602D01*
G01X3813518Y97848D02*
Y97953D01*
G01X3813395Y97932D02*
Y97869D01*
G01X3812943Y98309D02*
Y98351D01*
G01X3812820Y98372D02*
Y98288D01*
G01X3812595Y97848D02*
Y97953D01*
G01X3812472Y97932D02*
Y97869D01*
G01X3812021Y98309D02*
Y98351D01*
G01X3811898Y98372D02*
Y98288D01*
G01X3811672Y97743D02*
Y97618D01*
G01X3811057Y98602D02*
Y97743D01*
G01X3810934Y97618D02*
Y98602D01*
G01X3815958Y98456D02*
X3815978Y98372D01*
G01X3812820Y98288D02*
X3812841Y98204D01*
G01X3812759Y97890D02*
X3812780Y97806D01*
G01X3811898Y98288D02*
X3811918Y98204D01*
G01X3811836Y97890D02*
X3811857Y97806D01*
G01X3821105Y98372D02*
X3821084Y98435D01*
G01X3820982Y98372D02*
X3820961Y98435D01*
G01X3817332D02*
X3817352Y98372D01*
G01X3817229D02*
X3817209Y98435D01*
G01X3813456Y98372D02*
X3813435Y98435D01*
G01X3812964Y98246D02*
X3812943Y98309D01*
G01X3812902Y97827D02*
X3812882Y97890D01*
G01X3812533Y98372D02*
X3812513Y98435D01*
G01X3812041Y98246D02*
X3812021Y98309D01*
G01X3811980Y97827D02*
X3811959Y97890D01*
G01X3818295Y97618D02*
X3817967Y98602D01*
G01X3818090D02*
X3818377Y97743D01*
G01X3813866Y98602D02*
X3814174Y97722D01*
G01X3814092Y97618D02*
X3813805Y98393D01*
G01X3820817Y98057D02*
X3820982Y97618D01*
G01X3821125D02*
X3820941Y98100D01*
G01X3813313Y98413D02*
X3813333Y98372D01*
G01X3813518Y97953D02*
X3813477Y98037D01*
G01X3812390Y98413D02*
X3812410Y98372D01*
G01X3812595Y97953D02*
X3812554Y98037D01*
G01X3812780Y97806D02*
X3812841Y97702D01*
G01X3811857Y97806D02*
X3811918Y97702D01*
G01X3815855Y98372D02*
X3815814Y98435D01*
G01X3813354Y97995D02*
X3813395Y97932D01*
G01X3812431Y97995D02*
X3812472Y97932D01*
G01X3821084Y98435D02*
X3821022Y98518D01*
G01X3817270D02*
X3817332Y98435D01*
G01X3813435D02*
X3813374Y98518D01*
G01X3812513Y98435D02*
X3812451Y98518D01*
G01X3820961Y98435D02*
X3820920Y98476D01*
G01X3817209Y98435D02*
X3817168Y98476D01*
G01X3815876Y98539D02*
X3815958Y98456D01*
G01X3813272D02*
X3813313Y98413D01*
G01X3813477Y98037D02*
X3813395Y98120D01*
G01X3812841Y98204D02*
X3812923Y98120D01*
G01X3812349Y98456D02*
X3812390Y98413D01*
G01X3812964Y97764D02*
X3812902Y97827D01*
G01X3812554Y98037D02*
X3812472Y98120D01*
G01X3811918Y98204D02*
X3812000Y98120D01*
G01X3812041Y97764D02*
X3811980Y97827D01*
G01X3821022Y98518D02*
X3820941Y98581D01*
G01X3817188D02*
X3817270Y98518D01*
G01X3813374D02*
X3813292Y98581D01*
G01X3812451Y98518D02*
X3812369Y98581D01*
G01X3815814Y98435D02*
X3815753Y98476D01*
G01X3813292Y98037D02*
X3813354Y97995D01*
G01X3813026Y98204D02*
X3812964Y98246D01*
G01X3812369Y98037D02*
X3812431Y97995D01*
G01X3812103Y98204D02*
X3812041Y98246D01*
G01X3812841Y97702D02*
X3812943Y97639D01*
G01X3811918Y97702D02*
X3812021Y97639D01*
G01X3815794Y98581D02*
X3815876Y98539D01*
G01X3813395Y98120D02*
X3813313Y98162D01*
G01X3812923Y98120D02*
X3813005Y98078D01*
G01X3812472Y98120D02*
X3812390Y98162D01*
G01X3812000Y98120D02*
X3812082Y98078D01*
G01X3820920Y98476D02*
X3820859Y98497D01*
G01X3817168Y98476D02*
X3817106Y98497D01*
G01X3813210Y98476D02*
X3813272Y98456D01*
G01X3812287Y98476D02*
X3812349Y98456D01*
G01X3813087Y98183D02*
X3813026Y98204D01*
G01X3812164Y98183D02*
X3812103Y98204D01*
G01X3813210Y98057D02*
X3813292Y98037D01*
G01X3813005Y98078D02*
X3813087Y98057D01*
G01X3812287D02*
X3812369Y98037D01*
G01X3812082Y98078D02*
X3812164Y98057D01*
G01X3813046Y97743D02*
X3812964Y97764D01*
G01X3812123Y97743D02*
X3812041Y97764D01*
G01X3820941Y98581D02*
X3820838Y98602D01*
G01X3817085D02*
X3817188Y98581D01*
G01X3815753Y98476D02*
X3815650Y98497D01*
G01X3813292Y98581D02*
X3813189Y98602D01*
G01X3812369Y98581D02*
X3812267Y98602D01*
G01X3813313Y98162D02*
X3813210Y98183D01*
G01X3812390Y98162D02*
X3812287Y98183D01*
G01X3812943Y97639D02*
X3813046Y97618D01*
G01X3812021Y97639D02*
X3812123Y97618D01*
G01X3815670Y98602D02*
X3815794Y98581D01*
G01X3819403Y98602D02*
X3820182D01*
G01X3817967D02*
X3818090D01*
G01X3818665D02*
X3818787D01*
G01X3816593D02*
X3817085D01*
G01X3815589D02*
X3815670D01*
G01X3814953D02*
X3815076D01*
G01X3813682D02*
X3813866D01*
G01X3814482D02*
X3814666D01*
G01X3810934D02*
X3811057D01*
G01X3812267D02*
X3812164D01*
G01X3813189D02*
X3813087D01*
G01X3820838D02*
X3820346D01*
G01X3817106Y98497D02*
X3816717D01*
G01X3815650D02*
X3815568D01*
G01X3820859D02*
X3820469D01*
G01X3820182D02*
X3819854D01*
G01X3819731D02*
X3819403D01*
G01X3813087Y98476D02*
X3813210D01*
G01X3812164D02*
X3812287D01*
G01X3813333Y98372D02*
X3813456D01*
G01X3812410D02*
X3812533D01*
G01X3815363D02*
X3815261D01*
G01X3820469Y98183D02*
X3820859D01*
G01X3816717D02*
X3817106D01*
G01X3812287D02*
X3812164D01*
G01X3813210D02*
X3813087D01*
G01X3818952Y98078D02*
X3819239D01*
G01X3817516D02*
X3817803D01*
G01X3816142D02*
X3816430D01*
G01X3820469Y98057D02*
X3820817D01*
G01X3813087D02*
X3813210D01*
G01X3812164D02*
X3812287D01*
G01X3817085D02*
X3816717D01*
G01X3816430Y97974D02*
X3816142D01*
G01X3819239D02*
X3818952D01*
G01X3817803D02*
X3817516D01*
G01X3811959Y97890D02*
X3811836D01*
G01X3812882D02*
X3812759D01*
G01X3811057Y97743D02*
X3811672D01*
G01X3812287D02*
X3812123D01*
G01X3813210D02*
X3813046D01*
G01X3815404Y97722D02*
X3815978D01*
G01X3820346Y97618D02*
X3820469D01*
G01X3820982D02*
X3821125D01*
G01X3813046D02*
X3813210D01*
G01X3812123D02*
X3812287D01*
G01X3811672D02*
X3810934D01*
G01X3816717D02*
X3816593D01*
G01X3815978D02*
X3815240D01*
G01X3815076D02*
X3814953D01*
G01X3814256D02*
X3814092D01*
G01X3813805D02*
X3813682D01*
G01X3814666D02*
X3814543D01*
G01X3819854D02*
X3819731D01*
G01X3818459D02*
X3818295D01*
G01X3815445Y98581D02*
X3815589Y98602D01*
G01X3815568Y98497D02*
X3815466Y98476D01*
G01X3812287Y97618D02*
X3812390Y97639D01*
G01X3813210Y97618D02*
X3813313Y97639D01*
G01X3817188Y98078D02*
X3817085Y98057D01*
G01X3812164Y98602D02*
X3812082Y98581D01*
G01X3813087Y98602D02*
X3813005Y98581D01*
G01X3812369Y97764D02*
X3812287Y97743D01*
G01X3813292Y97764D02*
X3813210Y97743D01*
G01X3822531Y115334D02*
Y105492D01*
G01X3817807D02*
Y115334D01*
G01X3812689D02*
Y105492D01*
G01X3822531D02*
X3817807D01*
G01X3820687Y109525D02*
X3820769Y109609D01*
G01X3820606Y110405D02*
X3820687Y110489D01*
G01X3819621Y110907D02*
X3819785Y111075D01*
G01X3820974Y109567D02*
X3820893Y109441D01*
G01X3820933Y110489D02*
X3820852Y110363D01*
G01X3819867Y110865D02*
X3819785Y110740D01*
G01X3820769Y109609D02*
X3820810Y109693D01*
G01X3820687Y110489D02*
X3820769Y110656D01*
G01X3821015Y109693D02*
X3820974Y109567D01*
G01X3820769Y109357D02*
X3820606Y109274D01*
G01Y109483D02*
X3820687Y109525D01*
G01X3819785Y111075D02*
X3819949Y111159D01*
G01X3820893Y109441D02*
X3820769Y109357D01*
G01X3819990Y110949D02*
X3819867Y110865D01*
G01X3820852Y110363D02*
X3820687Y110237D01*
G01X3820974Y110656D02*
X3820933Y110489D01*
G01X3819580Y110740D02*
X3819621Y110907D01*
G01X3820359Y110321D02*
X3820606Y110405D01*
G01X3821350Y114350D02*
Y106476D01*
G01X3821015Y109860D02*
Y109693D01*
G01X3820974Y110740D02*
Y110656D01*
G01X3820810Y109693D02*
Y109860D01*
G01X3820769Y110656D02*
Y110740D01*
G01X3820195Y110154D02*
Y110321D01*
G01X3818988Y106476D02*
Y114350D01*
G01X3811507D02*
Y106476D01*
G01X3820933Y110907D02*
X3820974Y110740D01*
G01Y110028D02*
X3821015Y109860D01*
G01X3819580Y109567D02*
X3819539Y109693D01*
G01X3820810Y109860D02*
X3820728Y110028D01*
G01X3819744Y109693D02*
X3819785Y109609D01*
G01X3820769Y110740D02*
X3820687Y110865D01*
G01X3820893Y110154D02*
X3820974Y110028D01*
G01X3819662Y109441D02*
X3819580Y109567D01*
G01X3820769Y111075D02*
X3820933Y110907D01*
G01X3819785Y109609D02*
X3819867Y109525D01*
G01X3820687Y110865D02*
X3820564Y110949D01*
G01X3820728Y110028D02*
X3820606Y110111D01*
G01X3819785Y109357D02*
X3819662Y109441D01*
G01X3820606Y111159D02*
X3820769Y111075D01*
G01X3819867Y109525D02*
X3819949Y109483D01*
G01Y109274D02*
X3819785Y109357D01*
G01X3820687Y110237D02*
X3820893Y110154D01*
G01X3820113Y109232D02*
X3819949Y109274D01*
G01X3820564Y110949D02*
X3820359Y110991D01*
G01X3819949Y109483D02*
X3820154Y109441D01*
G01X3820606Y110111D02*
X3820359Y110154D01*
G01X3820318Y111200D02*
X3820606Y111159D01*
G01X3817807Y115334D02*
X3822531D01*
G01X3821350Y114350D02*
X3818988D01*
G01X3820236Y111200D02*
X3820318D01*
G01X3820359Y110991D02*
X3820195D01*
G01X3819785Y110740D02*
X3819580D01*
G01X3820195Y110321D02*
X3820359D01*
G01Y110154D02*
X3820195D01*
G01X3819539Y109693D02*
X3819744D01*
G01X3820154Y109441D02*
X3820400D01*
G01X3820441Y109232D02*
X3820113D01*
G01X3819949Y111159D02*
X3820236Y111200D01*
G01X3820195Y110991D02*
X3819990Y110949D01*
G01X3820400Y109441D02*
X3820606Y109483D01*
G01Y109274D02*
X3820441Y109232D01*
G01X3835917Y180048D02*
G03I-6299J0D01*
G01X3823870Y242303D02*
Y243779D01*
G01D02*
X3828645D01*
G01X3835681Y242303D02*
X3823870D01*
G01Y250669D02*
Y252145D01*
G01D02*
X3835681D01*
G01X3828645Y250669D02*
X3823870D01*
G01Y264448D02*
X3824121Y262972D01*
G01X3825126Y264448D02*
X3825378Y263218D01*
G01X3824121Y262972D02*
X3824875Y261742D01*
G01X3825378Y263218D02*
X3825880Y262480D01*
G01X3824875Y261742D02*
X3825629Y261004D01*
G01X3825880Y262480D02*
X3827388Y261496D01*
G01X3825629Y261004D02*
X3826634Y260511D01*
G01X3825880Y266417D02*
X3825378Y265679D01*
G01X3824875Y267155D02*
X3824121Y265925D01*
G01X3825378Y265679D02*
X3825126Y264448D01*
G01X3824121Y265925D02*
X3823870Y264448D01*
G01X3825629Y267893D02*
X3824875Y267155D01*
G01X3827388Y267401D02*
X3825880Y266417D01*
G01X3826634Y268385D02*
X3825629Y267893D01*
G01X3835917Y355245D02*
G03I-6299J0D01*
G01X3819126Y424209D02*
Y418681D01*
G01Y430492D02*
Y425717D01*
G01X3817649Y418681D02*
Y430492D01*
G01X3819126Y425717D02*
X3826015D01*
G01Y424209D02*
X3819126D01*
G01Y418681D02*
X3817649D01*
G01Y430492D02*
X3819126D01*
G01X3826015Y425717D02*
Y430492D01*
G01Y418681D02*
Y424209D01*
G01X3827492Y418681D02*
X3826015D01*
G01Y430492D02*
X3827492D01*
G01X3810720Y517696D02*
Y490137D01*
G01X3838811Y-1699843D02*
Y-1719843D01*
G01X3833061Y-1699843D02*
X3844561D01*
G01X3854561Y-1719843D02*
Y-1699843D01*
G01Y-1709509D02*
X3855811Y-1707843D01*
X3857061Y-1706843D01*
X3859061Y-1706510D01*
X3860561Y-1706843D01*
X3862311Y-1708176D01*
X3863061Y-1710177D01*
Y-1719843D01*
G01X3878811Y-1706510D02*
Y-1719843D01*
G01Y-1701177D02*
X3878311Y-1700843D01*
Y-1700176D01*
X3878811Y-1699843D01*
X3879311Y-1700176D01*
Y-1700843D01*
X3878811Y-1701177D01*
G01X3902811Y-1708176D02*
X3901061Y-1706843D01*
X3899561Y-1706510D01*
X3897561Y-1707177D01*
X3896061Y-1708510D01*
X3895061Y-1710843D01*
X3894811Y-1713177D01*
X3895061Y-1715510D01*
X3896061Y-1717510D01*
X3897561Y-1719176D01*
X3899561Y-1719843D01*
X3901311Y-1719176D01*
X3902811Y-1717843D01*
G01X3914561Y-1719843D02*
Y-1699843D01*
G01X3922561Y-1706510D02*
X3914561Y-1714176D01*
G01X3917811Y-1711176D02*
X3923061Y-1719843D01*
G01X3934561D02*
Y-1706510D01*
G01Y-1709843D02*
X3935561Y-1708176D01*
X3937061Y-1706843D01*
X3939061Y-1706510D01*
X3940811Y-1706843D01*
X3942311Y-1708176D01*
X3943061Y-1710510D01*
Y-1719843D01*
G01X3955061Y-1710843D02*
X3963061D01*
X3962311Y-1708510D01*
X3961061Y-1707177D01*
X3959311Y-1706510D01*
X3957561Y-1706843D01*
X3956061Y-1707843D01*
X3955061Y-1710177D01*
X3954561Y-1712177D01*
Y-1714176D01*
X3955061Y-1716177D01*
X3956311Y-1718177D01*
X3957811Y-1719510D01*
X3959561Y-1719843D01*
X3961311Y-1719176D01*
X3963061Y-1717177D01*
G01X3975061Y-1717510D02*
X3976311Y-1718843D01*
X3978061Y-1719843D01*
X3979561D01*
X3981061Y-1719176D01*
X3982061Y-1718177D01*
X3982561Y-1716844D01*
X3982311Y-1714843D01*
X3981311Y-1713843D01*
X3976811Y-1711843D01*
X3975811Y-1709509D01*
X3976311Y-1707843D01*
X3977311Y-1706843D01*
X3978811Y-1706510D01*
X3980311Y-1706843D01*
X3981811Y-1707843D01*
G01X3995061Y-1717510D02*
X3996311Y-1718843D01*
X3998061Y-1719843D01*
X3999561D01*
X4001061Y-1719176D01*
X4002061Y-1718177D01*
X4002561Y-1716844D01*
X4002311Y-1714843D01*
X4001311Y-1713843D01*
X3996811Y-1711843D01*
X3995811Y-1709509D01*
X3996311Y-1707843D01*
X3997311Y-1706843D01*
X3998811Y-1706510D01*
X4000311Y-1706843D01*
X4001811Y-1707843D01*
G01X3832911Y-1181075D02*
X3831828Y-1179631D01*
X3831287Y-1178188D01*
Y-1172414D01*
X3831828Y-1170970D01*
X3832911Y-1169527D01*
G01X3839623Y-1178188D02*
Y-1169527D01*
X3844603Y-1178188D01*
Y-1169527D01*
G01X3848609Y-1178188D02*
Y-1169527D01*
X3851207D01*
X3852073Y-1169960D01*
X3852723Y-1170970D01*
X3852939Y-1172125D01*
X3852723Y-1173280D01*
X3852181Y-1174146D01*
X3851207Y-1174579D01*
X3848609D01*
G01X3859435Y-1169527D02*
Y-1178188D01*
G01X3856945Y-1169527D02*
X3861925D01*
G01X3865822Y-1178188D02*
Y-1169527D01*
G01X3870370D02*
Y-1178188D01*
G01Y-1173858D02*
X3865822D01*
G01X3877298Y-1181075D02*
X3878381Y-1179631D01*
X3878922Y-1178188D01*
Y-1172414D01*
X3878381Y-1170970D01*
X3877298Y-1169527D01*
G01X3853841Y-1134634D02*
X3840080Y-1119585D01*
G01D02*
X3836930D01*
G01X3836639Y-1089796D02*
X3833490D01*
G01X3858748Y-1079602D02*
X3836639Y-1089796D01*
G01X3837433Y-1061188D02*
X3834284D01*
G01X3850866Y-1069027D02*
X3837433Y-1061188D01*
G01X3834170Y-992688D02*
X3833087Y-991244D01*
X3832546Y-989801D01*
Y-984027D01*
X3833087Y-982583D01*
X3834170Y-981140D01*
G01X3840882Y-989801D02*
Y-981140D01*
X3845862Y-989801D01*
Y-981140D01*
G01X3849868Y-989801D02*
Y-981140D01*
X3852466D01*
X3853332Y-981573D01*
X3853982Y-982583D01*
X3854198Y-983738D01*
X3853982Y-984893D01*
X3853440Y-985759D01*
X3852466Y-986192D01*
X3849868D01*
G01X3860694Y-981140D02*
Y-989801D01*
G01X3858204Y-981140D02*
X3863184D01*
G01X3867081Y-989801D02*
Y-981140D01*
G01X3871629D02*
Y-989801D01*
G01Y-985471D02*
X3867081D01*
G01X3878557Y-992688D02*
X3879640Y-991244D01*
X3880181Y-989801D01*
Y-984027D01*
X3879640Y-982583D01*
X3878557Y-981140D01*
G01X3829027Y106476D02*
Y92696D01*
G01X3832613Y158394D02*
X3854421Y180202D01*
G01X3833555Y180048D02*
X3959539D01*
G01X3835681Y243779D02*
Y242303D01*
G01X3830152Y250669D02*
Y243779D01*
G01X3828645D02*
Y250669D01*
G01X3830152Y243779D02*
X3835681D01*
G01Y252145D02*
Y250669D01*
G01D02*
X3830152D01*
G01X3833670Y262480D02*
X3834173Y263218D01*
G01X3834676Y261742D02*
X3835430Y262972D01*
G01X3834173Y263218D02*
X3834424Y264448D01*
G01X3835430Y262972D02*
X3835681Y264448D01*
G01X3833922Y261004D02*
X3834676Y261742D01*
G01X3831660Y258051D02*
Y254114D01*
G01X3830655D02*
Y258051D01*
G01X3828645D02*
Y254114D01*
G01X3827639D02*
Y258051D01*
G01X3832163Y261496D02*
X3833670Y262480D01*
G01X3832917Y260511D02*
X3833922Y261004D01*
G01X3832163Y260265D02*
X3832917Y260511D01*
G01X3826634D02*
X3827388Y260265D01*
G01D02*
X3828645Y260019D01*
G01X3827388Y261496D02*
X3828896Y261250D01*
G01D02*
X3830655D01*
G01X3828645Y260019D02*
X3830906D01*
G01X3830655Y258051D02*
X3831660D01*
G01X3827639D02*
X3828645D01*
G01X3831660Y254114D02*
X3830655D01*
G01X3828645D02*
X3827639D01*
G01X3830655Y261250D02*
X3832163Y261496D01*
G01X3830906Y260019D02*
X3832163Y260265D01*
G01X3835681Y264448D02*
X3835430Y265925D01*
G01X3834424Y264448D02*
X3834173Y265679D01*
G01X3835430Y265925D02*
X3834676Y267155D01*
G01X3827388Y268631D02*
X3826634Y268385D01*
G01X3834173Y265679D02*
X3833670Y266417D01*
G01X3834676Y267155D02*
X3833922Y267893D01*
G01X3833670Y266417D02*
X3832163Y267401D01*
G01X3833922Y267893D02*
X3832917Y268385D01*
G01D02*
X3832163Y268631D01*
G01D02*
X3830906Y268878D01*
G01X3832163Y267401D02*
X3830655Y267647D01*
G01X3830906Y268878D02*
X3828645D01*
G01X3830655Y267647D02*
X3828896D01*
G01D02*
X3827388Y267401D01*
G01X3828645Y268878D02*
X3827388Y268631D01*
G01X3828896Y274291D02*
X3828645Y273799D01*
G01X3828896Y278228D02*
X3828645Y277736D01*
G01X3827639Y274291D02*
X3827891Y275029D01*
G01X3827639Y278228D02*
X3827891Y278966D01*
G01X3829147Y274537D02*
X3828896Y274291D01*
G01X3827891Y275029D02*
X3828645Y275767D01*
G01X3829147Y278474D02*
X3828896Y278228D01*
G01X3827891Y278966D02*
X3828393Y279458D01*
G01X3835681Y272076D02*
Y270846D01*
G01Y276013D02*
Y274783D01*
G01Y279950D02*
Y278720D01*
G01X3828645Y273799D02*
Y273307D01*
G01Y277736D02*
Y276998D01*
G01X3827639Y277244D02*
Y278228D01*
G01Y270846D02*
Y272076D01*
G01Y273307D02*
Y274291D01*
G01X3827891Y276506D02*
X3827639Y277244D01*
G01X3828645Y273307D02*
X3828896Y272568D01*
G01X3827891D02*
X3827639Y273307D01*
G01X3828393Y279458D02*
X3829650Y279950D01*
G01Y274783D02*
X3829147Y274537D01*
G01X3829650Y278720D02*
X3829147Y278474D01*
G01X3828645Y276998D02*
X3828896Y276506D01*
G01D02*
X3829147Y276259D01*
G01X3828645Y275767D02*
X3827891Y276506D01*
G01X3828896Y272568D02*
X3829398Y272076D01*
G01X3828393D02*
X3827891Y272568D01*
G01X3829147Y276259D02*
X3829650Y276013D01*
G01Y279950D02*
X3835681D01*
G01Y278720D02*
X3829650D01*
G01Y276013D02*
X3835681D01*
G01Y274783D02*
X3829650D01*
G01X3827639Y272076D02*
X3828393D01*
G01X3829398D02*
X3835681D01*
G01Y270846D02*
X3827639D01*
G01X3828896Y285364D02*
X3828645Y284872D01*
G01X3827639Y285364D02*
X3827891Y286102D01*
G01X3829147Y285610D02*
X3828896Y285364D01*
G01X3827891Y286102D02*
X3828645Y286840D01*
G01X3835681Y283149D02*
Y281919D01*
G01Y287086D02*
Y285856D01*
G01X3828645Y284872D02*
Y284380D01*
G01X3827639D02*
Y285364D01*
G01Y281919D02*
Y283149D01*
G01X3828645Y284380D02*
X3828896Y283641D01*
G01X3827891D02*
X3827639Y284380D01*
G01X3829650Y285856D02*
X3829147Y285610D01*
G01X3828896Y283641D02*
X3829398Y283149D01*
G01X3828393D02*
X3827891Y283641D01*
G01X3835681Y285856D02*
X3829650D01*
G01X3827639Y283149D02*
X3828393D01*
G01X3829398D02*
X3835681D01*
G01Y281919D02*
X3827639D01*
G01X3828896Y289301D02*
X3828645Y288809D01*
G01X3827639Y289301D02*
X3827891Y290039D01*
G01X3829147Y289547D02*
X3828896Y289301D01*
G01X3827891Y290039D02*
X3828393Y290531D01*
G01X3835681Y291023D02*
Y289793D01*
G01X3828645Y288809D02*
Y288070D01*
G01X3827639Y288317D02*
Y289301D01*
G01X3827891Y287578D02*
X3827639Y288317D01*
G01X3829650Y289793D02*
X3829147Y289547D01*
G01X3828645Y288070D02*
X3828896Y287578D01*
G01X3828393Y290531D02*
X3829650Y291023D01*
G01X3828896Y287578D02*
X3829147Y287332D01*
G01X3828645Y286840D02*
X3827891Y287578D01*
G01X3829147Y287332D02*
X3829650Y287086D01*
G01Y291023D02*
X3835681D01*
G01Y289793D02*
X3829650D01*
G01Y287086D02*
X3835681D01*
G01X3833555Y355245D02*
X3959539D01*
G01X3838319Y430492D02*
Y418681D01*
G01X3836842D02*
Y428481D01*
G01X3835366Y426722D02*
Y428733D01*
G01X3833397Y423707D02*
Y422702D01*
G01Y426722D02*
Y425717D01*
G01X3829460D02*
Y426722D01*
G01Y422702D02*
Y423707D01*
G01X3827492Y430492D02*
Y418681D01*
G01X3836842Y428481D02*
X3835366Y426722D01*
G01X3829460D02*
X3833397D01*
G01Y425717D02*
X3829460D01*
G01Y423707D02*
X3833397D01*
G01Y422702D02*
X3829460D01*
G01X3838319Y418681D02*
X3836842D01*
G01X3835366Y428733D02*
X3836842Y430492D01*
G01D02*
X3838319D01*
G01X3842256Y428481D02*
X3841763Y427728D01*
G01X3840533D02*
X3840779Y428733D01*
G01X3840287Y418681D02*
Y419937D01*
G01X3848407Y425466D02*
X3842256Y419937D01*
G01X3840287D02*
X3847177Y426220D01*
G01X3842994Y428984D02*
X3842256Y428481D01*
G01X3841763Y427728D02*
X3840533D01*
G01X3842256Y419937D02*
X3849145D01*
G01Y418681D02*
X3840287D01*
G01X3840779Y428733D02*
X3841763Y429738D01*
G01D02*
X3842748Y430241D01*
G01X3838469Y1025080D02*
X3834128Y1032574D01*
X3836470Y1033931D01*
X3837437Y1033990D01*
X3838195Y1033762D01*
X3838961Y1032871D01*
X3839352Y1031763D01*
X3839152Y1030813D01*
X3838713Y1030058D01*
X3836371Y1028702D01*
G01X3838713Y1030058D02*
X3842216Y1027250D01*
G01X3921849Y1070869D02*
X3837492Y1022013D01*
G01X3842128Y1028700D02*
X3843051Y1028401D01*
X3843924Y1028406D01*
X3844840Y1028770D01*
X3845538Y1029508D01*
X3845905Y1030387D01*
X3845867Y1031533D01*
X3845382Y1032587D01*
X3844615Y1033477D01*
X3843785Y1033831D01*
X3842840Y1033950D01*
X3842112Y1033696D01*
X3841528Y1033191D01*
X3840975Y1032203D01*
X3839375Y1035613D01*
X3841904Y1037078D01*
G01X3852479Y1032861D02*
X3852220Y1032877D01*
X3852075Y1033127D01*
X3852190Y1033361D01*
X3852450Y1033344D01*
X3852594Y1033094D01*
X3852479Y1032861D01*
G01X3855489Y1044947D02*
X3854884Y1044263D01*
X3854684Y1043313D01*
X3854743Y1042346D01*
X3855041Y1041184D01*
X3855598Y1040005D01*
X3856343Y1038935D01*
X3857203Y1038099D01*
X3858012Y1037566D01*
X3858935Y1037267D01*
X3859830Y1037452D01*
X3860434Y1038136D01*
X3860635Y1039086D01*
X3860576Y1040052D01*
X3860278Y1041214D01*
X3859720Y1042393D01*
X3858976Y1043463D01*
X3858116Y1044300D01*
X3857307Y1044832D01*
X3856383Y1045131D01*
X3855489Y1044947D01*
G01X3862984Y1049288D02*
X3862379Y1048604D01*
X3862179Y1047654D01*
X3862238Y1046687D01*
X3862536Y1045525D01*
X3863093Y1044346D01*
X3863838Y1043276D01*
X3864698Y1042440D01*
X3865507Y1041907D01*
X3866430Y1041608D01*
X3867325Y1041793D01*
X3867929Y1042477D01*
X3868130Y1043427D01*
X3868071Y1044393D01*
X3867773Y1045555D01*
X3867215Y1046734D01*
X3866471Y1047804D01*
X3865611Y1048641D01*
X3864802Y1049173D01*
X3863878Y1049472D01*
X3862984Y1049288D01*
G01X3880216Y-1146256D02*
G03I-15748J0D01*
G01X3859104Y-1142953D02*
X3847620Y-1135883D01*
G01X3870767Y-1146256D02*
G03I-6299J0D01*
G01X3847620Y-1135883D02*
X3844470D01*
G01X3880216Y-1076964D02*
G03I-15748J0D01*
G01X3870767D02*
G03I-6299J0D01*
G01X3857413Y90925D02*
X3855445Y88956D01*
G01X3853870Y107460D02*
Y88956D01*
G01D02*
X3919421D01*
G01X3853870Y97027D02*
X3857413D01*
G01X3853870Y90925D02*
X3858397D01*
G01Y104704D02*
Y89941D01*
G01X3857413Y104704D02*
Y90925D01*
G01X3858397Y89941D02*
X3869913D01*
G01X3915878Y104704D02*
X3857413D01*
G01X3919421Y107460D02*
X3853870D01*
G01X3857118Y114153D02*
Y107460D01*
G01X3859874Y114153D02*
X3857118D01*
G01X3854421Y376898D02*
Y158394D01*
G01X3849145Y427225D02*
X3848899Y426220D01*
G01X3855051Y418681D02*
Y424712D01*
G01X3852344Y426722D02*
Y425968D01*
G01Y424963D02*
Y418681D01*
G01X3851114D02*
Y426722D01*
G01X3848899Y428733D02*
X3849145Y427728D01*
G01X3848899Y426220D02*
X3848407Y425466D01*
G01X3847177Y426220D02*
X3847669Y427225D01*
G01X3849145Y419937D02*
Y418681D01*
G01Y427728D02*
Y427225D01*
G01X3847669D02*
Y427728D01*
G01X3855051Y424712D02*
X3854805Y425215D01*
G01X3856035Y425717D02*
X3856773Y426471D01*
G01X3852836Y425466D02*
X3852344Y424963D01*
G01Y425968D02*
X3852836Y426471D01*
G01X3847669Y427728D02*
X3847177Y428481D01*
G01X3855297Y426471D02*
X3856035Y425717D01*
G01X3854805Y425215D02*
X3854559Y425466D01*
G01X3847177Y428481D02*
X3846439Y428984D01*
G01X3853574Y425717D02*
X3852836Y425466D01*
G01Y426471D02*
X3853574Y426722D01*
G01X3854559Y425466D02*
X3854067Y425717D01*
G01X3854559Y426722D02*
X3855297Y426471D01*
G01X3851114Y426722D02*
X3852344D01*
G01X3853574D02*
X3854559D01*
G01X3854067Y425717D02*
X3853574D01*
G01X3852344Y418681D02*
X3851114D01*
G01X3856281D02*
X3855051D01*
G01X3847915Y429738D02*
X3848899Y428733D01*
G01X3846931Y430241D02*
X3847915Y429738D01*
G01X3846439Y428984D02*
X3845208Y429235D01*
G01X3845454Y430492D02*
X3846931Y430241D01*
G01X3844470Y430492D02*
X3845454D01*
G01X3845208Y429235D02*
X3844224D01*
G01X3842748Y430241D02*
X3844470Y430492D01*
G01X3844224Y429235D02*
X3842994Y428984D01*
G01X3858988Y418681D02*
Y424712D01*
G01X3856281D02*
Y418681D01*
G01X3856527Y425215D02*
X3856281Y424712D01*
G01X3858988D02*
X3858742Y425215D01*
G01X3856773Y425466D02*
X3856527Y425215D01*
G01X3858742D02*
X3858496Y425466D01*
G01X3857265Y425717D02*
X3856773Y425466D01*
G01Y426471D02*
X3857511Y426722D01*
G01X3858496Y425466D02*
X3858004Y425717D01*
G01X3858496Y426722D02*
X3859234Y426471D01*
G01X3857511Y426722D02*
X3858496D01*
G01X3858004Y425717D02*
X3857265D01*
G01X3860218Y418681D02*
X3858988D01*
G01X3875885Y-1768551D02*
Y-1748551D01*
X3880885D01*
X3882885Y-1749551D01*
X3884385Y-1750884D01*
X3885635Y-1752884D01*
X3886635Y-1755218D01*
X3886885Y-1758551D01*
X3886635Y-1761885D01*
X3885635Y-1764218D01*
X3884385Y-1766218D01*
X3882885Y-1767551D01*
X3880885Y-1768551D01*
X3875885D01*
G01X3905885D02*
Y-1755218D01*
G01Y-1757551D02*
X3904885Y-1756218D01*
X3903385Y-1755551D01*
X3901635Y-1755218D01*
X3899885Y-1755885D01*
X3898385Y-1757218D01*
X3897385Y-1759218D01*
X3896885Y-1761885D01*
X3897385Y-1764551D01*
X3898385Y-1766551D01*
X3899885Y-1767884D01*
X3901635Y-1768551D01*
X3903385Y-1768218D01*
X3904885Y-1767218D01*
X3905885Y-1765885D01*
G01X3921385Y-1748551D02*
Y-1768551D01*
G01X3917885Y-1755218D02*
X3924885D01*
G01X3937635Y-1759551D02*
X3945635D01*
X3944885Y-1757218D01*
X3943635Y-1755885D01*
X3941885Y-1755218D01*
X3940135Y-1755551D01*
X3938635Y-1756551D01*
X3937635Y-1758885D01*
X3937135Y-1760885D01*
Y-1762884D01*
X3937635Y-1764885D01*
X3938885Y-1766885D01*
X3940385Y-1768218D01*
X3942135Y-1768551D01*
X3943885Y-1767884D01*
X3945635Y-1765885D01*
G01X3871751Y-305709D02*
Y-864366D01*
G01X3887500D02*
X3871751D01*
G01X3887500Y-324996D02*
G03X3867814Y-305311I-19685J0D01*
G01X3863968Y104704D02*
Y88956D01*
G01X3871488Y90531D02*
X3871882Y92307D01*
G01X3863614Y90531D02*
X3864007Y92307D01*
G01X3871882Y89941D02*
Y104704D01*
G01X3869913D02*
Y89941D01*
G01X3866173Y107460D02*
Y99193D01*
G01X3864007Y104704D02*
Y92307D01*
G01X3862078Y89941D02*
Y104704D01*
G01X3862039Y92307D02*
Y104704D01*
G01X3869913Y92307D02*
X3870307Y90531D01*
G01X3862039Y92307D02*
X3862433Y90531D01*
G01X3863968Y99193D02*
X3877826D01*
G01Y98208D02*
X3863968D01*
G01X3877826Y97815D02*
X3863968D01*
G01X3864007Y92307D02*
X3862039D01*
G01X3871882D02*
X3869913D01*
G01Y90925D02*
X3871882D01*
G01X3863968D02*
X3862078D01*
G01X3863614Y90531D02*
X3862433D01*
G01X3871488D02*
X3870307D01*
G01X3871882Y89941D02*
X3885661D01*
G01X3863968Y89638D02*
X3877826D01*
G01X3862061Y112545D02*
G03X3861291Y113169I-770J-163D01*
G01X3864756D02*
G03X3863985Y112545I-1J-788D01*
G01X3872630Y113169D02*
G03X3871859Y112545I-1J-788D01*
G01X3869935D02*
G03X3869165Y113169I-770J-163D01*
G01X3871488Y114744D02*
X3871882Y115137D01*
G01X3870307Y113563D02*
X3869913Y113169D01*
G01X3863614Y114744D02*
X3864007Y115137D01*
G01X3862433Y113563D02*
X3862039Y113169D01*
G01X3871882Y123011D02*
Y112628D01*
G01X3871488Y113563D02*
Y114744D01*
G01X3870307D02*
Y113563D01*
G01X3869913Y112628D02*
Y123011D01*
G01X3867748Y114153D02*
Y108248D01*
G01X3866173Y114153D02*
Y108248D01*
G01X3864007Y123011D02*
Y112628D01*
G01X3863614Y113563D02*
Y114744D01*
G01X3862433D02*
Y113563D01*
G01X3862039Y112628D02*
Y123011D01*
G01X3859874Y114153D02*
Y108248D01*
G01X3870307Y114744D02*
X3869913Y115137D01*
G01X3871882Y113169D02*
X3871488Y113563D01*
G01X3862433Y114744D02*
X3862039Y115137D01*
G01X3864007Y113169D02*
X3863614Y113563D01*
G01X3864007Y115137D02*
X3862039D01*
G01X3871882D02*
X3869913D01*
G01X3863614Y114744D02*
X3862433D01*
G01X3871488D02*
X3870307D01*
G01X3867748Y114153D02*
X3866173D01*
G01X3870307Y113563D02*
X3871488D01*
G01X3862433D02*
X3863614D01*
G01X3866173Y113169D02*
X3859874D01*
G01X3874047D02*
X3867748D01*
G01X3864007Y112628D02*
X3862039D01*
G01X3871882D02*
X3869913D01*
G01X3863985Y112545D02*
X3862061D01*
G01X3871859D02*
X3869935D01*
G01X3866173Y112462D02*
X3859874D01*
G01X3874047D02*
X3867748D01*
G01X3866173Y108248D02*
X3859874D01*
G01X3874047D02*
X3867748D01*
G01X3870307Y121437D02*
X3869913Y121043D01*
G01X3862433Y121437D02*
X3862039Y121043D01*
G01X3871488Y121437D02*
Y122618D01*
G01X3870307D02*
Y121437D01*
G01X3863614D02*
Y122618D01*
G01X3862433D02*
Y121437D01*
G01X3871882Y121043D02*
X3871488Y121437D01*
G01X3864007Y121043D02*
X3863614Y121437D01*
G01X3870307D02*
X3871488D01*
G01X3862433D02*
X3863614D01*
G01X3864007Y121043D02*
X3862039D01*
G01X3871882D02*
X3869913D01*
G01X3864007Y120059D02*
X3862039D01*
G01X3871882D02*
X3869913D01*
G01X3874047Y114153D02*
Y108248D01*
G01X3875622Y114153D02*
X3874047D01*
G01X3871488Y122618D02*
X3871882Y123011D01*
G01X3863614Y122618D02*
X3864007Y123011D01*
G01X3870307Y122618D02*
X3869913Y123011D01*
G01X3862433Y122618D02*
X3862039Y123011D01*
G01X3864007D02*
X3862039D01*
G01X3871882D02*
X3869913D01*
G01X3863614Y122618D02*
X3862433D01*
G01X3871488D02*
X3870307D01*
G01X3864067Y187146D02*
X3955149Y219492D01*
G01X3863974Y331082D02*
Y218484D01*
G01D02*
X3924500D01*
G01X3863974Y322157D02*
X3872900Y331082D01*
G01X3910956D02*
X3863974D01*
G01X3864159Y360335D02*
X3979121Y397571D01*
G01X3871291Y424712D02*
Y418681D01*
G01X3870061D02*
Y424712D01*
G01X3867354D02*
Y418681D01*
G01X3866124D02*
Y424712D01*
G01X3863417Y426722D02*
Y425968D01*
G01Y424963D02*
Y418681D01*
G01X3862187D02*
Y426722D01*
G01X3860218Y424712D02*
Y418681D01*
G01X3870799Y425968D02*
X3871291Y424712D01*
G01X3867600Y425215D02*
X3867354Y424712D01*
G01X3859726Y425968D02*
X3860218Y424712D01*
G01X3870061D02*
X3869815Y425215D01*
G01X3866124Y424712D02*
X3865878Y425215D01*
G01X3867846Y425466D02*
X3867600Y425215D01*
G01X3867108Y425717D02*
X3867846Y426471D01*
G01X3863909Y425466D02*
X3863417Y424963D01*
G01Y425968D02*
X3863909Y426471D01*
G01X3870307D02*
X3870799Y425968D01*
G01X3869815Y425215D02*
X3869569Y425466D01*
G01X3866370Y426471D02*
X3867108Y425717D01*
G01X3865878Y425215D02*
X3865632Y425466D01*
G01X3859234Y426471D02*
X3859726Y425968D01*
G01X3868338Y425717D02*
X3867846Y425466D01*
G01Y426471D02*
X3868584Y426722D01*
G01X3864647Y425717D02*
X3863909Y425466D01*
G01Y426471D02*
X3864647Y426722D01*
G01X3869569Y425466D02*
X3869076Y425717D01*
G01X3865632Y425466D02*
X3865139Y425717D01*
G01X3869569Y426722D02*
X3870307Y426471D01*
G01X3865632Y426722D02*
X3866370Y426471D01*
G01X3868584Y426722D02*
X3869569D01*
G01X3864647D02*
X3865632D01*
G01X3862187D02*
X3863417D01*
G01X3869076Y425717D02*
X3868338D01*
G01X3865139D02*
X3864647D01*
G01X3863417Y418681D02*
X3862187D01*
G01X3867354D02*
X3866124D01*
G01X3871291D02*
X3870061D01*
G01X3883563Y-1293500D02*
G03X3887500Y-1289563I0J3937D01*
G01D02*
Y-324996D01*
G01X3883799Y-645429D02*
Y-646413D01*
G01X3875925D02*
Y-645429D01*
G01X3883799Y-646413D02*
X3875925D01*
G01X3876092Y-632633D02*
X3876595Y-633454D01*
G01X3883799Y-639852D02*
Y-640836D01*
G01X3881118Y-635915D02*
Y-638539D01*
G01X3880448D02*
Y-635915D01*
G01X3880113Y-640836D02*
Y-645429D01*
G01X3879108D02*
Y-640836D01*
G01Y-635915D02*
Y-638539D01*
G01X3878438D02*
Y-635915D01*
G01X3875925Y-640836D02*
Y-639852D01*
G01X3876595Y-633454D02*
X3877098Y-633946D01*
G01X3877265Y-632962D02*
X3878270Y-633618D01*
G01X3877098Y-633946D02*
X3877768Y-634274D01*
G01X3883129Y-633454D02*
X3883631Y-632633D01*
G01X3877768Y-634274D02*
X3878270Y-634438D01*
G01D02*
X3879108Y-634602D01*
G01X3878270Y-633618D02*
X3879275Y-633782D01*
G01X3882626Y-633946D02*
X3883129Y-633454D01*
G01X3879275Y-633782D02*
X3880448D01*
G01X3879108Y-634602D02*
X3880616D01*
G01X3880448Y-635915D02*
X3881118D01*
G01X3878438D02*
X3879108D01*
G01X3881118Y-638539D02*
X3880448D01*
G01X3879108D02*
X3878438D01*
G01X3875925Y-639852D02*
X3883799D01*
G01X3879108Y-640836D02*
X3875925D01*
G01X3883799D02*
X3880113D01*
G01Y-645429D02*
X3883799D01*
G01X3875925D02*
X3879108D01*
G01X3881453Y-633618D02*
X3882459Y-632962D01*
G01X3880448Y-633782D02*
X3881453Y-633618D01*
G01X3880616Y-634602D02*
X3881453Y-634438D01*
G01X3881956Y-634274D02*
X3882626Y-633946D01*
G01X3881453Y-634438D02*
X3881956Y-634274D01*
G01X3883799Y-631649D02*
X3883631Y-630665D01*
G01X3875925Y-631649D02*
X3876092Y-632633D01*
G01X3882961Y-631649D02*
X3882794Y-630829D01*
G01X3876763Y-631649D02*
X3876930Y-632470D01*
G01X3883631Y-630665D02*
X3883129Y-629845D01*
G01X3882794Y-630829D02*
X3882459Y-630337D01*
G01X3876930Y-632470D02*
X3877265Y-632962D01*
G01X3883129Y-629845D02*
X3882626Y-629353D01*
G01X3882794Y-632470D02*
X3882961Y-631649D01*
G01X3876930Y-630829D02*
X3876763Y-631649D01*
G01X3883631Y-632633D02*
X3883799Y-631649D01*
G01X3876092Y-630665D02*
X3875925Y-631649D01*
G01X3882459Y-630337D02*
X3881453Y-629681D01*
G01X3882626Y-629353D02*
X3881956Y-629025D01*
G01D02*
X3881453Y-628861D01*
G01X3882459Y-632962D02*
X3882794Y-632470D01*
G01X3876595Y-629845D02*
X3876092Y-630665D01*
G01X3877265Y-630337D02*
X3876930Y-630829D01*
G01X3881453Y-629681D02*
X3880448Y-629517D01*
G01X3877098Y-629353D02*
X3876595Y-629845D01*
G01X3880448Y-629517D02*
X3879275D01*
G01X3878270Y-629681D02*
X3877265Y-630337D01*
G01X3879275Y-629517D02*
X3878270Y-629681D01*
G01X3877768Y-629025D02*
X3877098Y-629353D01*
G01X3878270Y-628861D02*
X3877768Y-629025D01*
G01X3879108Y-618362D02*
X3879275Y-618854D01*
G01X3878605D02*
X3878438Y-618362D01*
G01X3878605Y-623611D02*
X3878438Y-623119D01*
G01X3879108Y-625744D02*
X3879275Y-626236D01*
G01X3878605D02*
X3878438Y-625744D01*
G01X3879108Y-623283D02*
X3879275Y-623611D01*
G01X3883799Y-626564D02*
Y-627384D01*
G01Y-623939D02*
Y-624759D01*
G01Y-619182D02*
Y-620002D01*
G01Y-621315D02*
Y-622135D01*
G01Y-616557D02*
Y-617378D01*
G01X3879108Y-625416D02*
Y-625744D01*
G01Y-622791D02*
Y-623283D01*
G01Y-618034D02*
Y-618362D01*
G01X3878438D02*
Y-617706D01*
G01Y-620002D02*
Y-619182D01*
G01Y-623119D02*
Y-622463D01*
G01Y-627384D02*
Y-626564D01*
G01Y-625744D02*
Y-625088D01*
G01X3879108Y-616722D02*
X3878605Y-616229D01*
G01X3879275Y-618854D02*
X3879611Y-619182D01*
G01X3878940D02*
X3878605Y-618854D01*
G01X3879275Y-623611D02*
X3879443Y-623775D01*
G01X3879108Y-624104D02*
X3878605Y-623611D01*
G01X3879275Y-626236D02*
X3879611Y-626564D01*
G01X3878940D02*
X3878605Y-626236D01*
G01X3878438Y-625088D02*
X3878605Y-624596D01*
G01X3878438Y-622463D02*
X3878605Y-621971D01*
G01X3878438Y-617706D02*
X3878605Y-617214D01*
G01X3879443Y-623775D02*
X3879778Y-623939D01*
G01X3879275Y-625088D02*
X3879108Y-625416D01*
G01X3879275Y-622463D02*
X3879108Y-622791D01*
G01X3879275Y-617706D02*
X3879108Y-618034D01*
G01X3881453Y-628861D02*
X3880616Y-628696D01*
G01X3879443Y-624924D02*
X3879275Y-625088D01*
G01X3878605Y-624596D02*
X3879108Y-624104D01*
G01X3879443Y-622299D02*
X3879275Y-622463D01*
G01X3878605Y-621971D02*
X3878940Y-621643D01*
G01X3879443Y-617542D02*
X3879275Y-617706D01*
G01X3878605Y-617214D02*
X3879108Y-616722D01*
G01X3883799Y-617378D02*
X3879778D01*
G01X3878438Y-619182D02*
X3878940D01*
G01X3879611D02*
X3883799D01*
G01Y-620002D02*
X3878438D01*
G01X3879778Y-621315D02*
X3883799D01*
G01Y-622135D02*
X3879778D01*
G01Y-623939D02*
X3883799D01*
G01Y-624759D02*
X3879778D01*
G01X3878438Y-626564D02*
X3878940D01*
G01X3879611D02*
X3883799D01*
G01Y-627384D02*
X3878438D01*
G01X3880616Y-628696D02*
X3879108D01*
G01D02*
X3878270Y-628861D01*
G01X3879778Y-624759D02*
X3879443Y-624924D01*
G01X3879778Y-622135D02*
X3879443Y-622299D01*
G01X3879778Y-617378D02*
X3879443Y-617542D01*
G01X3878940Y-621643D02*
X3879778Y-621315D01*
G01X3878605Y-616229D02*
X3878438Y-615737D01*
G01X3879108Y-615901D02*
X3879275Y-616229D01*
G01X3883799Y-613933D02*
Y-614753D01*
G01X3879108Y-615409D02*
Y-615901D01*
G01X3878438Y-615737D02*
Y-615081D01*
G01X3879275Y-616229D02*
X3879443Y-616393D01*
G01X3878438Y-615081D02*
X3878605Y-614589D01*
G01X3879443Y-616393D02*
X3879778Y-616557D01*
G01X3879275Y-615081D02*
X3879108Y-615409D01*
G01X3879443Y-614917D02*
X3879275Y-615081D01*
G01X3878605Y-614589D02*
X3878940Y-614261D01*
G01X3879778Y-613933D02*
X3883799D01*
G01Y-614753D02*
X3879778D01*
G01Y-616557D02*
X3883799D01*
G01X3879778Y-614753D02*
X3879443Y-614917D01*
G01X3878940Y-614261D02*
X3879778Y-613933D01*
G01X3897571Y-24744D02*
X3898581Y-24094D01*
X3899159Y-23228D01*
X3899303Y-22254D01*
X3899159Y-21388D01*
X3898437Y-20521D01*
X3897571Y-19980D01*
X3896705Y-19872D01*
X3895694Y-20088D01*
X3894973Y-20846D01*
X3894684Y-21604D01*
Y-22579D01*
G01Y-21604D02*
X3894251Y-20955D01*
X3893529Y-20413D01*
X3892663Y-20197D01*
X3891797Y-20413D01*
X3891075Y-20955D01*
X3890642Y-21929D01*
X3890786Y-22903D01*
X3891364Y-23878D01*
G01X3899303Y-12402D02*
X3890642D01*
X3896849Y-16408D01*
Y-10994D01*
G01X3898293Y-6881D02*
X3899014Y-6123D01*
X3899303Y-5257D01*
X3899014Y-4390D01*
X3898148Y-3633D01*
X3896849Y-3091D01*
X3895550Y-2875D01*
X3893962D01*
X3892663Y-3091D01*
X3891508Y-3633D01*
X3890931Y-4282D01*
X3890642Y-5040D01*
X3890931Y-5906D01*
X3891508Y-6556D01*
X3892374Y-6989D01*
X3893529Y-7205D01*
X3894539Y-6989D01*
X3895550Y-6447D01*
X3896127Y-5798D01*
X3896272Y-5040D01*
X3895983Y-4174D01*
X3895261Y-3524D01*
X3893962Y-2875D01*
G01X3899592Y3621D02*
X3899447Y3404D01*
X3899159D01*
X3899014Y3621D01*
X3899159Y3838D01*
X3899447D01*
X3899592Y3621D01*
G01X3899303Y12065D02*
X3897427Y12282D01*
X3895839Y12607D01*
X3894395Y13040D01*
X3892807Y13581D01*
X3890642Y14447D01*
Y10117D01*
G01X3898004Y18561D02*
X3898726Y19211D01*
X3899159Y19969D01*
X3899303Y20943D01*
X3899014Y21917D01*
X3898437Y22675D01*
X3897427Y23217D01*
X3896272Y23325D01*
X3895117Y23108D01*
X3894395Y22567D01*
X3893818Y21809D01*
X3893673Y21051D01*
X3893818Y20293D01*
X3894395Y19319D01*
X3890642Y19644D01*
Y22567D01*
G01X3879952Y88956D02*
G03X3881921Y90925I0J1969D01*
G01X3877826Y88956D02*
Y104704D01*
G01X3887236Y90531D02*
X3887630Y92307D01*
G01X3879362Y90531D02*
X3879756Y92307D01*
G01X3887630Y104704D02*
Y89941D01*
G01X3885661D02*
Y104704D01*
G01X3881921D02*
Y90925D01*
G01X3879756Y104704D02*
Y92307D01*
G01X3879716Y89941D02*
Y104704D01*
G01X3877787Y92307D02*
Y104704D01*
G01X3875622Y99193D02*
Y107460D01*
G01X3885661Y92307D02*
X3886055Y90531D01*
G01X3877787Y92307D02*
X3878181Y90531D01*
G01X3879756Y92307D02*
X3877787D01*
G01X3887630D02*
X3885661D01*
G01Y90925D02*
X3887630D01*
G01X3879716D02*
X3877826D01*
G01X3879362Y90531D02*
X3878181D01*
G01X3887236D02*
X3886055D01*
G01X3887630Y89941D02*
X3901409D01*
G01X3891370Y90925D02*
G03X3893338Y88956I1969J0D01*
G01X3891370Y104704D02*
Y90925D01*
G01X3880504Y113169D02*
G03X3879733Y112545I-1J-788D01*
G01X3877809D02*
G03X3877039Y113169I-770J-163D01*
G01X3888378D02*
G03X3887607Y112545I-1J-788D01*
G01X3885683D02*
G03X3884913Y113169I-770J-163D01*
G01X3887236Y114744D02*
X3887630Y115137D01*
G01X3886055Y113563D02*
X3885661Y113169D01*
G01X3879362Y114744D02*
X3879756Y115137D01*
G01X3878181Y113563D02*
X3877787Y113169D01*
G01X3887630Y123011D02*
Y112628D01*
G01X3887236Y113563D02*
Y114744D01*
G01X3886055D02*
Y113563D01*
G01X3885661Y112628D02*
Y123011D01*
G01X3883496Y114153D02*
Y108248D01*
G01X3881921Y114153D02*
Y108248D01*
G01X3879756Y123011D02*
Y112628D01*
G01X3879362Y113563D02*
Y114744D01*
G01X3878181D02*
Y113563D01*
G01X3877787Y112628D02*
Y123011D01*
G01X3875622Y114153D02*
Y108248D01*
G01X3886055Y114744D02*
X3885661Y115137D01*
G01X3887630Y113169D02*
X3887236Y113563D01*
G01X3878181Y114744D02*
X3877787Y115137D01*
G01X3879756Y113169D02*
X3879362Y113563D01*
G01X3879756Y115137D02*
X3877787D01*
G01X3887630D02*
X3885661D01*
G01X3879362Y114744D02*
X3878181D01*
G01X3887236D02*
X3886055D01*
G01X3883496Y114153D02*
X3881921D01*
G01X3886055Y113563D02*
X3887236D01*
G01X3878181D02*
X3879362D01*
G01X3881921Y113169D02*
X3875622D01*
G01X3889795D02*
X3883496D01*
G01X3879756Y112628D02*
X3877787D01*
G01X3887630D02*
X3885661D01*
G01X3879733Y112545D02*
X3877809D01*
G01X3887607D02*
X3885683D01*
G01X3881921Y112462D02*
X3875622D01*
G01X3889795D02*
X3883496D01*
G01X3881921Y108248D02*
X3875622D01*
G01X3889795D02*
X3883496D01*
G01X3886055Y121437D02*
X3885661Y121043D01*
G01X3878181Y121437D02*
X3877787Y121043D01*
G01X3887236Y121437D02*
Y122618D01*
G01X3886055D02*
Y121437D01*
G01X3879362D02*
Y122618D01*
G01X3878181D02*
Y121437D01*
G01X3887630Y121043D02*
X3887236Y121437D01*
G01X3879756Y121043D02*
X3879362Y121437D01*
G01X3886055D02*
X3887236D01*
G01X3878181D02*
X3879362D01*
G01X3879756Y121043D02*
X3877787D01*
G01X3887630D02*
X3885661D01*
G01X3879756Y120059D02*
X3877787D01*
G01X3887630D02*
X3885661D01*
G01X3891370Y114153D02*
Y108248D01*
G01X3889795Y114153D02*
Y108248D01*
G01X3891370Y114153D02*
X3889795D01*
G01X3897669Y113169D02*
X3891370D01*
G01X3897669Y112462D02*
X3891370D01*
G01X3897669Y108248D02*
X3891370D01*
G01X3887236Y122618D02*
X3887630Y123011D01*
G01X3879362Y122618D02*
X3879756Y123011D01*
G01X3886055Y122618D02*
X3885661Y123011D01*
G01X3878181Y122618D02*
X3877787Y123011D01*
G01X3879756D02*
X3877787D01*
G01X3887630D02*
X3885661D01*
G01X3879362Y122618D02*
X3878181D01*
G01X3887236D02*
X3886055D01*
G01X3892157Y134111D02*
X3891132Y133444D01*
G01X3891637Y136200D02*
Y133444D01*
G01X3891441D02*
Y136200D01*
G01X3890624Y133444D02*
Y136200D01*
G01X3890610D02*
Y133444D01*
G01X3890609Y136200D02*
Y133444D01*
G01X3890266D02*
Y136200D01*
G01X3889532Y133444D02*
Y136200D01*
G01X3889434D02*
Y133444D01*
G01X3889428Y136200D02*
Y133444D01*
G01Y136200D02*
X3893249D01*
G01X3889428Y133444D02*
X3892224D01*
G01X3891637Y153917D02*
Y151161D01*
G01X3891441D02*
Y153917D01*
G01X3890624Y151161D02*
Y153917D01*
G01X3890610D02*
Y151161D01*
G01X3890609Y153917D02*
Y151161D01*
G01X3890266D02*
Y153917D01*
G01X3889532Y151161D02*
Y153917D01*
G01X3889434D02*
Y151161D01*
G01X3889428Y153917D02*
Y151161D01*
G01X3891132Y153917D02*
X3892157Y153250D01*
G01X3889428Y153917D02*
X3892224D01*
G01X3889428Y151161D02*
X3893249D01*
G01X3892157Y170332D02*
X3891132Y169665D01*
G01X3891637Y172421D02*
Y169665D01*
G01X3891441D02*
Y172421D01*
G01X3890624Y169665D02*
Y172421D01*
G01X3890610D02*
Y169665D01*
G01X3890609Y172421D02*
Y169665D01*
G01X3890266D02*
Y172421D01*
G01X3889532Y169665D02*
Y172421D01*
G01X3889434D02*
Y169665D01*
G01X3889428Y172421D02*
Y169665D01*
G01D02*
X3892224D01*
G01X3889428Y172421D02*
X3893249D01*
G01X3891637Y190137D02*
Y187381D01*
G01X3891441D02*
Y190137D01*
G01X3890624Y187381D02*
Y190137D01*
G01X3890610D02*
Y187381D01*
G01X3890609Y190137D02*
Y187381D01*
G01X3890266D02*
Y190137D01*
G01X3889532Y187381D02*
Y190137D01*
G01X3889434D02*
Y187381D01*
G01X3889428Y190137D02*
Y187381D01*
G01D02*
X3893249D01*
G01X3891132Y190137D02*
X3892157Y189470D01*
G01X3889428Y190137D02*
X3892224D01*
G01X3883712Y246909D02*
Y248385D01*
G01X3895523Y246909D02*
X3883712D01*
G01X3888487Y248385D02*
Y255275D01*
G01X3883712Y248385D02*
X3888487D01*
G01X3889995Y255275D02*
Y248385D01*
G01D02*
X3895523D01*
G01X3888487Y262657D02*
Y258720D01*
G01X3887482D02*
Y262657D01*
G01X3883712Y255275D02*
Y256752D01*
G01X3887482Y262657D02*
X3888487D01*
G01Y258720D02*
X3887482D01*
G01X3883712Y256752D02*
X3895523D01*
G01X3888487Y255275D02*
X3883712D01*
G01X3885220Y270285D02*
X3884969Y269055D01*
G01X3883964Y270531D02*
X3883712Y269055D01*
G01D02*
X3883964Y267578D01*
G01X3884969Y269055D02*
X3885220Y267824D01*
G01X3883964Y267578D02*
X3884717Y266348D01*
G01X3885220Y267824D02*
X3885723Y267086D01*
G01X3884717Y266348D02*
X3885471Y265610D01*
G01X3885723Y267086D02*
X3887230Y266102D01*
G01X3885471Y265610D02*
X3886477Y265118D01*
G01D02*
X3887230Y264872D01*
G01D02*
X3888487Y264626D01*
G01X3887230Y266102D02*
X3888738Y265856D01*
G01D02*
X3890497D01*
G01X3888487Y264626D02*
X3890749D01*
G01X3891503Y262657D02*
Y258720D01*
G01X3890497D02*
Y262657D01*
G01D02*
X3891503D01*
G01Y258720D02*
X3890497D01*
G01X3895523Y255275D02*
X3889995D01*
G01X3890497Y265856D02*
X3892005Y266102D01*
G01X3890749Y264626D02*
X3892005Y264872D01*
G01X3884717Y271761D02*
X3883964Y270531D01*
G01X3888738Y278897D02*
X3888487Y278405D01*
G01X3887482Y278897D02*
X3887733Y279635D01*
G01X3885471Y272500D02*
X3884717Y271761D01*
G01X3888990Y279143D02*
X3888738Y278897D01*
G01X3887733Y279635D02*
X3888487Y280374D01*
G01X3885723Y271023D02*
X3885220Y270285D01*
G01X3888487Y278405D02*
Y277913D01*
G01X3887482Y275452D02*
Y276683D01*
G01Y277913D02*
Y278897D01*
G01X3887230Y272007D02*
X3885723Y271023D01*
G01X3888487Y277913D02*
X3888738Y277175D01*
G01X3887733D02*
X3887482Y277913D01*
G01X3886477Y272992D02*
X3885471Y272500D01*
G01X3887230Y273238D02*
X3886477Y272992D01*
G01X3888487Y280374D02*
X3887733Y281112D01*
G01X3888738Y277175D02*
X3889241Y276683D01*
G01X3888236D02*
X3887733Y277175D01*
G01X3887482Y276683D02*
X3888236D01*
G01X3895523Y275452D02*
X3887482D01*
G01X3890749Y273484D02*
X3888487D01*
G01X3890497Y272254D02*
X3888738D01*
G01D02*
X3887230Y272007D01*
G01X3888487Y273484D02*
X3887230Y273238D01*
G01X3888738Y282834D02*
X3888487Y282342D01*
G01X3887482Y282834D02*
X3887733Y283572D01*
G01X3888990Y283080D02*
X3888738Y282834D01*
G01X3887733Y283572D02*
X3888236Y284065D01*
G01X3888487Y282342D02*
Y281604D01*
G01X3887482Y281850D02*
Y282834D01*
G01X3887733Y281112D02*
X3887482Y281850D01*
G01X3888487Y281604D02*
X3888738Y281112D01*
G01X3888236Y284065D02*
X3889492Y284557D01*
G01X3888738Y281112D02*
X3888990Y280866D01*
G01X3889492Y279389D02*
X3888990Y279143D01*
G01Y280866D02*
X3889492Y280620D01*
G01X3892005Y273238D02*
X3890749Y273484D01*
G01X3892005Y272007D02*
X3890497Y272254D01*
G01X3889492Y280620D02*
X3895523D01*
G01Y279389D02*
X3889492D01*
G01X3889241Y276683D02*
X3895523D01*
G01X3889492Y283326D02*
X3888990Y283080D01*
G01X3889492Y284557D02*
X3895523D01*
G01Y283326D02*
X3889492D01*
G01X3888738Y289970D02*
X3888487Y289478D01*
G01X3888738Y293907D02*
X3888487Y293415D01*
G01X3887482Y289970D02*
X3887733Y290708D01*
G01X3887482Y293907D02*
X3887733Y294645D01*
G01X3888990Y290216D02*
X3888738Y289970D01*
G01X3887733Y290708D02*
X3888487Y291446D01*
G01Y293415D02*
Y292677D01*
G01Y289478D02*
Y288986D01*
G01X3887482Y292923D02*
Y293907D01*
G01Y288986D02*
Y289970D01*
G01Y286525D02*
Y287756D01*
G01X3888990Y294153D02*
X3888738Y293907D01*
G01X3887733Y294645D02*
X3888236Y295137D01*
G01X3887733Y292185D02*
X3887482Y292923D01*
G01X3888487Y288986D02*
X3888738Y288248D01*
G01X3887733D02*
X3887482Y288986D01*
G01X3888487Y292677D02*
X3888738Y292185D01*
G01X3888236Y295137D02*
X3889492Y295630D01*
G01X3888738Y292185D02*
X3888990Y291939D01*
G01X3888487Y291446D02*
X3887733Y292185D01*
G01X3888738Y288248D02*
X3889241Y287756D01*
G01X3888236D02*
X3887733Y288248D01*
G01X3887482Y287756D02*
X3888236D01*
G01X3895523Y286525D02*
X3887482D01*
G01X3889492Y290462D02*
X3888990Y290216D01*
G01X3889492Y294399D02*
X3888990Y294153D01*
G01Y291939D02*
X3889492Y291693D01*
G01Y295630D02*
X3895523D01*
G01Y294399D02*
X3889492D01*
G01Y291693D02*
X3895523D01*
G01Y290462D02*
X3889492D01*
G01X3889241Y287756D02*
X3895523D01*
G01X3893747Y-1843488D02*
X3894602Y-1842348D01*
X3895600Y-1841777D01*
X3896741Y-1841587D01*
X3898167Y-1841967D01*
X3899165Y-1842918D01*
X3899451Y-1844058D01*
X3899308Y-1845199D01*
X3898738Y-1846150D01*
X3895886Y-1848051D01*
X3894602Y-1849382D01*
X3893747Y-1851283D01*
X3893461Y-1852994D01*
X3899451D01*
G01X3907864Y-1841587D02*
X3906723Y-1841967D01*
X3905868Y-1842918D01*
X3905297Y-1844058D01*
X3904869Y-1845580D01*
X3904727Y-1847291D01*
X3904869Y-1849002D01*
X3905297Y-1850523D01*
X3905868Y-1851663D01*
X3906723Y-1852614D01*
X3907864Y-1852994D01*
X3909005Y-1852614D01*
X3909860Y-1851663D01*
X3910431Y-1850523D01*
X3910859Y-1849002D01*
X3911001Y-1847291D01*
X3910859Y-1845580D01*
X3910431Y-1844058D01*
X3909860Y-1842918D01*
X3909005Y-1841967D01*
X3907864Y-1841587D01*
G01X3901468Y235807D02*
Y28521D01*
G01X3895464Y104704D02*
Y88956D01*
G01X3902984Y90531D02*
X3903378Y92307D01*
G01X3895110Y90531D02*
X3895504Y92307D01*
G01X3903378Y104704D02*
Y89941D01*
G01X3901409Y104704D02*
Y89941D01*
G01X3897669Y107460D02*
Y99193D01*
G01X3895504Y104704D02*
Y92307D01*
G01X3893574Y89941D02*
Y104704D01*
G01X3893535Y92307D02*
Y104704D01*
G01X3901409Y92307D02*
X3901803Y90531D01*
G01X3893535Y92307D02*
X3893929Y90531D01*
G01X3909322Y99193D02*
X3895464D01*
G01Y98208D02*
X3909322D01*
G01X3895464Y97815D02*
X3909322D01*
G01X3895504Y92307D02*
X3893535D01*
G01X3903378D02*
X3901409D01*
G01Y90925D02*
X3903378D01*
G01X3895464D02*
X3893574D01*
G01X3895110Y90531D02*
X3893929D01*
G01X3902984D02*
X3901803D01*
G01X3903378Y89941D02*
X3914893D01*
G01X3895464Y89638D02*
X3909322D01*
G01X3907118Y99193D02*
Y107460D01*
G01X3896252Y113169D02*
G03X3895482Y112545I0J-787D01*
G01X3893557D02*
G03X3892787Y113169I-770J-163D01*
G01X3904126D02*
G03X3903356Y112545I0J-787D01*
G01X3901431D02*
G03X3900661Y113169I-770J-163D01*
G01X3902984Y114744D02*
X3903378Y115137D01*
G01X3901803Y113563D02*
X3901409Y113169D01*
G01X3895110Y114744D02*
X3895504Y115137D01*
G01X3893929Y113563D02*
X3893535Y113169D01*
G01X3903378Y123011D02*
Y112628D01*
G01X3902984Y113563D02*
Y114744D01*
G01X3901803D02*
Y113563D01*
G01X3901409Y112628D02*
Y123011D01*
G01X3899244Y114153D02*
Y108248D01*
G01X3897669Y114153D02*
Y108248D01*
G01X3895504Y123011D02*
Y112628D01*
G01X3895110Y113563D02*
Y114744D01*
G01X3893929D02*
Y113563D01*
G01X3893535Y112628D02*
Y123011D01*
G01X3901803Y114744D02*
X3901409Y115137D01*
G01X3903378Y113169D02*
X3902984Y113563D01*
G01X3893929Y114744D02*
X3893535Y115137D01*
G01X3895504Y113169D02*
X3895110Y113563D01*
G01X3895504Y115137D02*
X3893535D01*
G01X3903378D02*
X3901409D01*
G01X3895110Y114744D02*
X3893929D01*
G01X3902984D02*
X3901803D01*
G01X3899244Y114153D02*
X3897669D01*
G01X3901803Y113563D02*
X3902984D01*
G01X3893929D02*
X3895110D01*
G01X3905543Y113169D02*
X3899244D01*
G01X3895504Y112628D02*
X3893535D01*
G01X3903378D02*
X3901409D01*
G01X3895482Y112545D02*
X3893557D01*
G01X3903356D02*
X3901431D01*
G01X3905543Y112462D02*
X3899244D01*
G01X3905543Y108248D02*
X3899244D01*
G01X3901803Y121437D02*
X3901409Y121043D01*
G01X3893929Y121437D02*
X3893535Y121043D01*
G01X3902984Y121437D02*
Y122618D01*
G01X3901803D02*
Y121437D01*
G01X3895110D02*
Y122618D01*
G01X3893929D02*
Y121437D01*
G01X3903378Y121043D02*
X3902984Y121437D01*
G01X3895504Y121043D02*
X3895110Y121437D01*
G01X3901803D02*
X3902984D01*
G01X3893929D02*
X3895110D01*
G01X3895504Y121043D02*
X3893535D01*
G01X3903378D02*
X3901409D01*
G01X3895504Y120059D02*
X3893535D01*
G01X3903378D02*
X3901409D01*
G01X3907118Y114153D02*
Y108248D01*
G01X3905543Y114153D02*
Y108248D01*
G01X3907118Y114153D02*
X3905543D01*
G01X3907118Y113169D02*
X3913417D01*
G01Y112462D02*
X3907118D01*
G01Y108248D02*
X3913417D01*
G01X3892157Y133051D02*
G03X3893732Y131476I1575J0D01*
G01X3902984Y122618D02*
X3903378Y123011D01*
G01X3895110Y122618D02*
X3895504Y123011D01*
G01X3898615Y132657D02*
X3898456Y132067D01*
G01Y136988D02*
Y132263D01*
G01X3894322Y137775D02*
Y132263D01*
G01X3892748Y137775D02*
Y132067D01*
G01X3901803Y122618D02*
X3901409Y123011D01*
G01X3893929Y122618D02*
X3893535Y123011D01*
G01X3910109Y132657D02*
X3898615D01*
G01X3914401Y132263D02*
X3894322D01*
G01X3898456Y132067D02*
X3892748D01*
G01X3914992Y131476D02*
X3893732D01*
G01X3895504Y123011D02*
X3893535D01*
G01X3903378D02*
X3901409D01*
G01X3895110Y122618D02*
X3893929D01*
G01X3902984D02*
X3901803D01*
G01X3909845Y143681D02*
G03I-5483J0D01*
G01X3910633D02*
G03I-6271J0D01*
G01X3911252D02*
G03I-6890J0D01*
G01X3911645D02*
G03I-7283J0D01*
G01X3896389Y135216D02*
G03I-492J0D01*
G01X3897570D02*
G03I-1673J0D01*
G01X3897669D02*
G03I-1772J0D01*
G01X3903916Y133520D02*
X3903653Y133252D01*
G01Y133855D02*
X3903522Y133654D01*
G01X3904047Y133788D02*
X3903916Y133520D01*
G01X3903719Y134123D02*
X3903653Y133855D01*
G01X3903522Y133654D02*
X3903325Y133520D01*
G01X3904113Y134123D02*
X3904047Y133788D01*
G01X3903653Y133252D02*
X3903391Y133118D01*
G01X3893249Y134111D02*
X3892224Y133444D01*
G01X3905031Y136200D02*
Y133051D01*
G01X3904637D02*
Y136200D01*
G01X3904113Y135128D02*
Y134123D01*
G01X3903719Y135128D02*
Y134123D01*
G01X3901882Y133453D02*
Y135798D01*
G01X3901488Y133051D02*
Y136200D01*
G01X3893338Y149428D02*
Y137933D01*
G01X3893249Y134111D02*
Y136200D01*
G01X3892945Y149586D02*
Y137775D01*
G01X3892157Y154311D02*
Y133051D01*
G01X3904047Y135463D02*
X3904113Y135128D01*
G01X3903653Y135396D02*
X3903719Y135128D01*
G01X3903916Y135731D02*
X3904047Y135463D01*
G01X3903522Y135597D02*
X3903653Y135396D01*
G01X3903916Y135731D02*
X3903653Y136000D01*
G01X3903325Y135731D02*
X3903522Y135597D01*
G01X3903391Y136133D02*
X3903653Y136000D01*
G01X3903325Y135731D02*
X3903063Y135798D01*
G01X3903391Y136133D02*
X3903063Y136200D01*
G01X3894322Y137775D02*
X3892945D01*
G01X3910267Y136988D02*
X3898456D01*
G01X3901488Y136200D02*
X3903063D01*
G01X3904637D02*
X3905031D01*
G01X3901882Y135798D02*
X3903063D01*
G01X3892157Y134111D02*
X3893249D01*
G01X3903063Y133453D02*
X3901882D01*
G01X3903063Y133051D02*
X3901488D01*
G01X3905031D02*
X3904637D01*
G01X3903391Y133118D02*
X3903063Y133051D01*
G01X3903325Y133520D02*
X3903063Y133453D01*
G01X3892748Y137775D02*
X3893338Y137933D01*
G01X3907525Y133587D02*
X3907393Y133453D01*
G01X3907919Y133587D02*
X3907722Y133319D01*
G01X3907984Y133788D02*
X3907919Y133587D01*
G01X3907590Y133788D02*
X3907525Y133587D01*
G01X3907722Y133319D02*
X3907459Y133118D01*
G01X3907984Y134056D02*
Y133788D01*
G01X3907590Y133989D02*
Y133788D01*
G01X3905950Y133386D02*
Y134391D01*
G01Y136200D02*
Y134793D01*
G01X3905556Y133051D02*
Y136200D01*
G01X3907393Y133453D02*
X3907196Y133386D01*
G01X3907919Y134257D02*
X3907984Y134056D01*
G01X3907525Y134190D02*
X3907590Y133989D01*
G01X3907722Y134525D02*
X3907919Y134257D01*
G01X3907525Y134190D02*
X3907393Y134324D01*
G01X3907722Y134525D02*
X3907459Y134726D01*
G01X3907393Y134324D02*
X3907196Y134391D01*
G01X3907459Y134726D02*
X3907131Y134793D01*
G01X3905556Y136200D02*
X3905950D01*
G01Y134793D02*
X3907131D01*
G01X3905950Y134391D02*
X3907196D01*
G01Y133386D02*
X3905950D01*
G01X3907131Y133051D02*
X3905556D01*
G01X3907459Y133118D02*
X3907131Y133051D01*
G01X3900602Y140314D02*
X3901212Y140925D01*
G01X3893515Y140314D02*
X3894126Y140925D01*
G01X3897669Y146437D02*
X3898280Y147048D01*
G01X3901212Y146437D02*
Y140925D01*
G01X3900602Y140314D02*
Y147048D01*
G01X3898280D02*
Y140314D01*
G01X3897669Y140925D02*
Y146437D01*
G01X3894126D02*
Y140925D01*
G01X3893515Y140314D02*
Y147048D01*
G01X3900602D02*
X3901212Y146437D01*
G01X3893515Y147048D02*
X3894126Y146437D01*
G01X3898280Y140314D02*
X3897669Y140925D01*
G01X3893338Y149428D02*
X3892748Y149586D01*
G01X3915779Y147618D02*
X3892945D01*
G01X3900602Y147048D02*
X3908122D01*
G01X3893515D02*
X3898280D01*
G01X3897669Y146437D02*
X3894126D01*
G01X3907511D02*
X3901212D01*
G01Y140925D02*
X3907511D01*
G01X3894126D02*
X3897669D01*
G01X3898280Y140314D02*
X3893515D01*
G01X3908122D02*
X3900602D01*
G01X3915779Y139744D02*
X3892945D01*
G01X3901742Y154901D02*
Y154704D01*
G01X3896389Y152145D02*
G03I-492J0D01*
G01X3893732Y155885D02*
G03X3892157Y154311I0J-1575D01*
G01X3897570Y152145D02*
G03I-1673J0D01*
G01X3897669D02*
G03I-1772J0D01*
G01X3902092Y152289D02*
X3902035Y152222D01*
G01X3901715Y153328D02*
X3901658Y153261D01*
G01X3902206Y152222D02*
X3902130Y152088D01*
G01X3901620Y153462D02*
X3901545Y153328D01*
G01X3901658Y153261D02*
X3901620Y153161D01*
G01X3905736Y153328D02*
X3905264Y151988D01*
G01X3905679Y153563D02*
X3905207Y152189D01*
G01X3901545Y153328D02*
X3901507Y153194D01*
G01X3902130Y152088D02*
X3902054Y152021D01*
G01X3901696Y153529D02*
X3901620Y153462D01*
G01X3903659Y153362D02*
X3903395Y151988D01*
G01X3903583Y153563D02*
X3903282Y151988D01*
G01X3903130Y153563D02*
X3902828Y151988D01*
G01X3902923Y153026D02*
X3902753Y152122D01*
G01X3903017Y153563D02*
X3902942Y153161D01*
G01X3902111Y152390D02*
X3902092Y152289D01*
G01X3901620Y153161D02*
X3901601Y153026D01*
G01X3902224Y152390D02*
X3902206Y152222D01*
G01X3901507Y153194D02*
X3901488Y153026D01*
G01X3902206Y153328D02*
X3902224Y153161D01*
G01X3901488Y152524D02*
X3901507Y152356D01*
G01X3901740Y154704D02*
X3901744Y154901D01*
G01X3905207Y153563D02*
Y152189D01*
G01X3905094Y151988D02*
Y153563D01*
G01X3901601Y153026D02*
Y152524D01*
G01X3901488D02*
Y153026D01*
G01X3898456Y155098D02*
Y150374D01*
G01X3894322Y155098D02*
Y149586D01*
G01X3893249Y151161D02*
Y153250D01*
G01X3892748Y155295D02*
Y149586D01*
G01X3901601Y152524D02*
X3901620Y152390D01*
G01X3902489Y153563D02*
X3902564Y153161D01*
G01X3902583Y153026D02*
X3902753Y152122D01*
G01X3902092Y153261D02*
X3902111Y153161D01*
G01X3903735Y153563D02*
X3904037Y151988D01*
G01X3902375Y153563D02*
X3902677Y151988D01*
G01X3903659Y153362D02*
X3903923Y151988D01*
G01X3902054Y152021D02*
X3901960Y151988D01*
G01X3901790Y153563D02*
X3901696Y153529D01*
G01X3902035Y152222D02*
X3901960Y152189D01*
G01X3901790Y153362D02*
X3901715Y153328D01*
G01X3898456Y155295D02*
X3898615Y154704D01*
G01X3901545Y152222D02*
X3901507Y152356D01*
G01X3901620Y152390D02*
X3901658Y152289D01*
G01X3902130Y153462D02*
X3902206Y153328D01*
G01X3901545Y152222D02*
X3901620Y152088D01*
G01X3902092Y153261D02*
X3902035Y153328D01*
G01X3901715Y152222D02*
X3901658Y152289D01*
G01X3902054Y153529D02*
X3902130Y153462D01*
G01X3901620Y152088D02*
X3901696Y152021D01*
G01X3892224Y153917D02*
X3893249Y153250D01*
G01X3902035Y153328D02*
X3901960Y153362D01*
G01X3901715Y152222D02*
X3901790Y152189D01*
G01X3902054Y153529D02*
X3901960Y153563D01*
G01X3901696Y152021D02*
X3901790Y151988D01*
G01X3906982Y154901D02*
X3901742D01*
G01X3901740Y154704D02*
X3898615D01*
G01X3901790Y153563D02*
X3901960D01*
G01X3902375D02*
X3902489D01*
G01X3903017D02*
X3903130D01*
G01X3903583D02*
X3903735D01*
G01X3905094D02*
X3905207D01*
G01X3901960Y153362D02*
X3901790D01*
G01X3892157Y153250D02*
X3893249D01*
G01X3902564Y153161D02*
X3902942D01*
G01X3902224D02*
X3902111D01*
G01X3902583Y153026D02*
X3902923D01*
G01X3902111Y152390D02*
X3902224D01*
G01X3901790Y152189D02*
X3901960D01*
G01Y151988D02*
X3901790D01*
G01X3902828D02*
X3902677D01*
G01X3904037D02*
X3903923D01*
G01X3903395D02*
X3903282D01*
G01X3905264D02*
X3905094D01*
G01X3910267Y150374D02*
X3898456D01*
G01X3894322Y149586D02*
X3892945D01*
G01X3908122Y147048D02*
X3907511Y146437D01*
G01X3908122Y147048D02*
Y140314D01*
G01X3907511Y140925D02*
Y146437D01*
G01Y140925D02*
X3908122Y140314D01*
G01X3906982Y154704D02*
Y154901D01*
G01X3906585Y152289D02*
X3906529Y152222D01*
G01X3906227Y153328D02*
X3906170Y153261D01*
G01X3906698Y152222D02*
X3906623Y152088D01*
G01X3906132Y153462D02*
X3906057Y153328D01*
G01X3906623Y152390D02*
X3906585Y152289D01*
G01X3906170Y153261D02*
X3906132Y153161D01*
G01X3906736Y152356D02*
X3906698Y152222D01*
G01X3906057Y153328D02*
X3906019Y153194D01*
G01X3906623Y152088D02*
X3906548Y152021D01*
G01X3906208Y153529D02*
X3906132Y153462D01*
G01X3906642Y152524D02*
X3906623Y152390D01*
G01X3906132Y153161D02*
X3906113Y153026D01*
G01X3906755Y152524D02*
X3906736Y152356D01*
G01X3906019Y153194D02*
X3906000Y153026D01*
G01X3906736Y153194D02*
X3906755Y153026D01*
G01X3906000Y152524D02*
X3906019Y152356D01*
G01X3906755Y153026D02*
Y152524D01*
G01X3906642Y153026D02*
Y152524D01*
G01X3906113D02*
Y153026D01*
G01X3906000Y152524D02*
Y153026D01*
G01X3905849Y153563D02*
Y151988D01*
G01X3905736D02*
Y153328D01*
G01X3906980Y154901D02*
X3906983Y154704D01*
G01X3906623Y153161D02*
X3906642Y153026D01*
G01X3906113Y152524D02*
X3906132Y152390D01*
G01X3906548Y152021D02*
X3906453Y151988D01*
G01X3906302Y153563D02*
X3906208Y153529D01*
G01X3906529Y152222D02*
X3906453Y152189D01*
G01X3906302Y153362D02*
X3906227Y153328D01*
G01X3906736Y153194D02*
X3906698Y153328D01*
G01X3906057Y152222D02*
X3906019Y152356D01*
G01X3906585Y153261D02*
X3906623Y153161D01*
G01X3906132Y152390D02*
X3906170Y152289D01*
G01X3906623Y153462D02*
X3906698Y153328D01*
G01X3906132Y152088D02*
X3906057Y152222D01*
G01X3906529Y153328D02*
X3906585Y153261D01*
G01X3906170Y152289D02*
X3906227Y152222D01*
G01X3906623Y153462D02*
X3906548Y153529D01*
G01X3906208Y152021D02*
X3906132Y152088D01*
G01X3906453Y153362D02*
X3906529Y153328D01*
G01X3906302Y152189D02*
X3906227Y152222D01*
G01X3906453Y153563D02*
X3906548Y153529D01*
G01X3906208Y152021D02*
X3906302Y151988D01*
G01X3910109Y154704D02*
X3906983D01*
G01X3906302Y153563D02*
X3906453D01*
G01X3905679D02*
X3905849D01*
G01X3906302Y153362D02*
X3906453D01*
G01Y152189D02*
X3906302D01*
G01X3905849Y151988D02*
X3905736D01*
G01X3906453D02*
X3906302D01*
G01X3914992Y155885D02*
X3893732D01*
G01X3898456Y155295D02*
X3892748D01*
G01X3914401Y155098D02*
X3894322D01*
G01X3896389Y171437D02*
G03I-492J0D01*
G01X3892157Y169271D02*
G03X3893732Y167696I1575J0D01*
G01X3897570Y171437D02*
G03I-1673J0D01*
G01X3897669D02*
G03I-1772J0D01*
G01X3903653Y170076D02*
X3903522Y169874D01*
G01X3904047Y170008D02*
X3903916Y169741D01*
G01D02*
X3903653Y169472D01*
G01X3898615Y168878D02*
X3898456Y168287D01*
G01X3903719Y170344D02*
X3903653Y170076D01*
G01X3904113Y170344D02*
X3904047Y170008D01*
G01X3893249Y170332D02*
X3892224Y169665D01*
G01X3903522Y169874D02*
X3903325Y169741D01*
G01X3905031Y172421D02*
Y169271D01*
G01X3904637D02*
Y172421D01*
G01X3904113Y171349D02*
Y170344D01*
G01X3903719Y171349D02*
Y170344D01*
G01X3901882Y169673D02*
Y172019D01*
G01X3901488Y169271D02*
Y172421D01*
G01X3898456Y173208D02*
Y168484D01*
G01X3894322Y173996D02*
Y168484D01*
G01X3893249Y170332D02*
Y172421D01*
G01X3892748Y173996D02*
Y168287D01*
G01X3892157Y190531D02*
Y169271D01*
G01X3904047Y171684D02*
X3904113Y171349D01*
G01X3903653Y171617D02*
X3903719Y171349D01*
G01X3903653Y169472D02*
X3903391Y169338D01*
G01X3892157Y170332D02*
X3893249D01*
G01X3903063Y169673D02*
X3901882D01*
G01X3903063Y169271D02*
X3901488D01*
G01X3905031D02*
X3904637D01*
G01X3910109Y168878D02*
X3898615D01*
G01X3914401Y168484D02*
X3894322D01*
G01X3898456Y168287D02*
X3892748D01*
G01X3914992Y167696D02*
X3893732D01*
G01X3903391Y169338D02*
X3903063Y169271D01*
G01X3903325Y169741D02*
X3903063Y169673D01*
G01X3907919Y169807D02*
X3907722Y169539D01*
G01X3907984Y170008D02*
X3907919Y169807D01*
G01X3907590Y170008D02*
X3907525Y169807D01*
G01X3907722Y169539D02*
X3907459Y169338D01*
G01X3907525Y169807D02*
X3907393Y169673D01*
G01X3907984Y170276D02*
Y170008D01*
G01X3907590Y170209D02*
Y170008D01*
G01X3905950Y169606D02*
Y170611D01*
G01Y172421D02*
Y171014D01*
G01X3905556Y169271D02*
Y172421D01*
G01X3907919Y170478D02*
X3907984Y170276D01*
G01X3907525Y170411D02*
X3907590Y170209D01*
G01X3907393Y169673D02*
X3907196Y169606D01*
G01X3907722Y170746D02*
X3907919Y170478D01*
G01X3907525Y170411D02*
X3907393Y170544D01*
G01X3907722Y170746D02*
X3907459Y170946D01*
G01X3907393Y170544D02*
X3907196Y170611D01*
G01X3907459Y170946D02*
X3907131Y171014D01*
G01X3905950D02*
X3907131D01*
G01X3905950Y170611D02*
X3907196D01*
G01Y169606D02*
X3905950D01*
G01X3907131Y169271D02*
X3905556D01*
G01X3907459Y169338D02*
X3907131Y169271D01*
G01X3910103Y179901D02*
G03I-5741J0D01*
G01X3910890D02*
G03I-6528J0D01*
G01X3911252D02*
G03I-6890J0D01*
G01X3911645D02*
G03I-7283J0D01*
G01X3900602Y176534D02*
X3901212Y177145D01*
G01X3893515Y176534D02*
X3894126Y177145D01*
G01X3901212Y182657D02*
Y177145D01*
G01X3900602Y176534D02*
Y183268D01*
G01X3898280D02*
Y176534D01*
G01X3897669Y177145D02*
Y182657D01*
G01X3894126D02*
Y177145D01*
G01X3893515Y176534D02*
Y183268D01*
G01X3893338Y185648D02*
Y174154D01*
G01X3892945Y185807D02*
Y173996D01*
G01X3903916Y171952D02*
X3904047Y171684D01*
G01X3903522Y171818D02*
X3903653Y171617D01*
G01X3903916Y171952D02*
X3903653Y172220D01*
G01X3898280Y176534D02*
X3897669Y177145D01*
G01X3903522Y171818D02*
X3903325Y171952D01*
G01X3903391Y172354D02*
X3903653Y172220D01*
G01X3903325Y171952D02*
X3903063Y172019D01*
G01X3903391Y172354D02*
X3903063Y172421D01*
G01X3901212Y177145D02*
X3907511D01*
G01X3894126D02*
X3897669D01*
G01X3898280Y176534D02*
X3893515D01*
G01X3908122D02*
X3900602D01*
G01X3915779Y175964D02*
X3892945D01*
G01X3894322Y173996D02*
X3892945D01*
G01X3910267Y173208D02*
X3898456D01*
G01X3901488Y172421D02*
X3903063D01*
G01X3904637D02*
X3905031D01*
G01X3901882Y172019D02*
X3903063D01*
G01X3892748Y173996D02*
X3893338Y174154D01*
G01X3897570Y188366D02*
G03I-1673J0D01*
G01X3897669D02*
G03I-1772J0D01*
G01Y182657D02*
X3898280Y183268D01*
G01X3898456Y191318D02*
Y186594D01*
G01X3894322Y191318D02*
Y185807D01*
G01X3893249Y187381D02*
Y189470D01*
G01X3892748Y191515D02*
Y185807D01*
G01X3900602Y183268D02*
X3901212Y182657D01*
G01X3893515Y183268D02*
X3894126Y182657D01*
G01X3893338Y185648D02*
X3892748Y185807D01*
G01X3910267Y186594D02*
X3898456D01*
G01X3894322Y185807D02*
X3892945D01*
G01X3915779Y183838D02*
X3892945D01*
G01X3900602Y183268D02*
X3908122D01*
G01X3893515D02*
X3898280D01*
G01X3897669Y182657D02*
X3894126D01*
G01X3907511D02*
X3901212D01*
G01X3908122Y183268D02*
Y176534D01*
G01X3907511Y177145D02*
Y182657D01*
G01Y177145D02*
X3908122Y176534D01*
G01X3905556Y172421D02*
X3905950D01*
G01X3908122Y183268D02*
X3907511Y182657D01*
G01X3901742Y191122D02*
Y190925D01*
G01X3896389Y188366D02*
G03I-492J0D01*
G01X3893732Y192106D02*
G03X3892157Y190531I0J-1575D01*
G01X3902206Y188443D02*
X3902130Y188309D01*
G01X3901620Y189683D02*
X3901545Y189548D01*
G01X3901658Y189481D02*
X3901620Y189381D01*
G01X3905736Y189548D02*
X3905264Y188208D01*
G01X3905679Y189783D02*
X3905207Y188409D01*
G01X3902130Y188309D02*
X3902054Y188242D01*
G01X3901696Y189750D02*
X3901620Y189683D01*
G01X3902092Y188510D02*
X3902035Y188443D01*
G01X3901715Y189548D02*
X3901658Y189481D01*
G01X3901545Y189548D02*
X3901507Y189415D01*
G01X3903659Y189582D02*
X3903395Y188208D01*
G01X3903583Y189783D02*
X3903282Y188208D01*
G01X3903130Y189783D02*
X3902828Y188208D01*
G01X3902923Y189247D02*
X3902753Y188343D01*
G01X3903017Y189783D02*
X3902942Y189381D01*
G01X3902111Y188610D02*
X3902092Y188510D01*
G01X3901620Y189381D02*
X3901601Y189247D01*
G01X3902224Y188610D02*
X3902206Y188443D01*
G01X3901507Y189415D02*
X3901488Y189247D01*
G01X3902206Y189548D02*
X3902224Y189381D01*
G01X3901488Y188744D02*
X3901507Y188577D01*
G01X3901740Y190925D02*
X3901744Y191122D01*
G01X3905207Y189783D02*
Y188409D01*
G01X3905094Y188208D02*
Y189783D01*
G01X3901601Y189247D02*
Y188744D01*
G01X3901488D02*
Y189247D01*
G01X3901601Y188744D02*
X3901620Y188610D01*
G01X3902489Y189783D02*
X3902564Y189381D01*
G01X3902583Y189247D02*
X3902753Y188343D01*
G01X3902092Y189481D02*
X3902111Y189381D01*
G01X3903735Y189783D02*
X3904037Y188208D01*
G01X3902375Y189783D02*
X3902677Y188208D01*
G01X3903659Y189582D02*
X3903923Y188208D01*
G01X3898456Y191515D02*
X3898615Y190925D01*
G01X3902035Y188443D02*
X3901960Y188409D01*
G01X3901790Y189582D02*
X3901715Y189548D01*
G01X3901507Y188577D02*
X3901545Y188443D01*
G01X3901620Y188610D02*
X3901658Y188510D01*
G01X3901960Y188208D02*
X3902054Y188242D01*
G01X3901790Y189783D02*
X3901696Y189750D01*
G01X3902130Y189683D02*
X3902206Y189548D01*
G01X3901545Y188443D02*
X3901620Y188309D01*
G01X3902092Y189481D02*
X3902035Y189548D01*
G01X3901715Y188443D02*
X3901658Y188510D01*
G01X3902054Y189750D02*
X3902130Y189683D01*
G01X3901620Y188309D02*
X3901696Y188242D01*
G01X3892224Y190137D02*
X3893249Y189470D01*
G01X3902035Y189548D02*
X3901960Y189582D01*
G01X3901715Y188443D02*
X3901790Y188409D01*
G01X3902054Y189750D02*
X3901960Y189783D01*
G01X3901696Y188242D02*
X3901790Y188208D01*
G01X3914992Y192106D02*
X3893732D01*
G01X3898456Y191515D02*
X3892748D01*
G01X3914401Y191318D02*
X3894322D01*
G01X3906982Y191122D02*
X3901742D01*
G01X3901740Y190925D02*
X3898615D01*
G01X3901790Y189783D02*
X3901960D01*
G01X3902375D02*
X3902489D01*
G01X3903017D02*
X3903130D01*
G01X3903583D02*
X3903735D01*
G01X3905094D02*
X3905207D01*
G01X3901960Y189582D02*
X3901790D01*
G01X3892157Y189470D02*
X3893249D01*
G01X3902564Y189381D02*
X3902942D01*
G01X3902224D02*
X3902111D01*
G01X3902583Y189247D02*
X3902923D01*
G01X3902111Y188610D02*
X3902224D01*
G01X3901790Y188409D02*
X3901960D01*
G01Y188208D02*
X3901790D01*
G01X3902828D02*
X3902677D01*
G01X3904037D02*
X3903923D01*
G01X3903395D02*
X3903282D01*
G01X3905264D02*
X3905094D01*
G01X3905149Y200964D02*
G03I-787J0D01*
G01X3905543D02*
G03I-1181J0D01*
G01X3907315Y206279D02*
G03I-2953J0D01*
G01X3908199D02*
G03I-3837J0D01*
G01X3908299D02*
G03I-3937J0D01*
G01X3908496D02*
G03I-4134J0D01*
G01X3910229D02*
G03I-5867J0D01*
G01X3910267D02*
G03I-5905J0D01*
G01X3895110Y200964D02*
G03X3895897Y200177I787J0D01*
G01X3899433D02*
G03X3899421Y200059I577J-118D01*
G01X3897531Y199586D02*
G03X3896769Y200177I-762J-196D01*
G01X3897767D02*
X3897570Y199980D01*
G01X3905346Y202933D02*
Y205050D01*
G01X3905070Y204763D02*
Y203413D01*
G01X3904460Y209626D02*
Y202933D01*
G01X3904263Y209626D02*
Y202933D01*
G01X3903653Y204763D02*
Y203413D01*
G01X3903378Y205050D02*
Y202933D01*
G01X3900011Y200177D02*
Y199586D01*
G01X3899834Y200295D02*
Y199389D01*
G01X3899421Y200177D02*
Y199586D01*
G01X3899249Y202933D02*
Y200964D01*
G01X3898653Y200019D02*
Y200964D01*
G01X3898594Y202982D02*
Y201013D01*
G01X3898437Y199586D02*
Y200177D01*
G01X3898206Y203305D02*
Y201337D01*
G01X3898157Y203346D02*
Y201378D01*
G01X3897770Y203669D02*
Y201700D01*
G01X3897531Y199586D02*
Y200177D01*
G01X3897472Y200019D02*
Y199389D01*
G01X3897115Y203917D02*
Y201948D01*
G01X3896488Y211397D02*
Y201161D01*
G01X3896291Y211594D02*
Y200964D01*
G01X3896094Y200177D02*
Y199586D01*
G01X3895504Y200177D02*
Y199586D01*
G01X3895110Y199389D02*
Y213169D01*
G01X3892748Y203917D02*
Y201948D01*
G01X3901842Y200177D02*
X3897157Y204862D01*
G01X3896488Y203853D02*
X3900754Y199586D01*
G01X3897464Y199980D02*
X3897267Y200177D01*
G01X3898653Y202933D02*
X3897472Y203917D01*
G01Y201948D02*
X3898653Y200964D01*
G01X3898299Y200295D02*
X3896921Y200807D01*
G01X3897472Y200098D02*
X3895543Y200807D01*
G01X3897472Y203917D02*
X3892748D01*
G01X3904460Y203437D02*
X3904263D01*
G01X3903378Y202933D02*
X3898653D01*
G01X3909474D02*
X3903378D01*
G01X3892748Y201948D02*
X3897472D01*
G01X3896488Y201161D02*
X3912236D01*
G01X3896291Y200964D02*
X3912433D01*
G01X3896921Y200807D02*
X3895110D01*
G01X3899834Y200295D02*
X3898299D01*
G01X3895504Y200177D02*
X3913220D01*
G01X3899834Y200098D02*
X3897472D01*
G01X3895110Y200019D02*
X3898653D01*
G01X3897464Y199980D02*
X3899421D01*
G01X3895504Y199586D02*
X3900754D01*
G01X3907969D02*
X3900754D01*
G01X3897472Y199389D02*
X3895110D01*
G01X3908889D02*
X3899834D01*
G01X3906982Y190925D02*
Y191122D01*
G01X3906698Y188443D02*
X3906623Y188309D01*
G01X3906132Y189683D02*
X3906057Y189548D01*
G01X3906623Y188610D02*
X3906585Y188510D01*
G01X3906170Y189481D02*
X3906132Y189381D01*
G01X3906623Y188309D02*
X3906548Y188242D01*
G01X3906208Y189750D02*
X3906132Y189683D01*
G01X3906585Y188510D02*
X3906529Y188443D01*
G01X3906227Y189548D02*
X3906170Y189481D01*
G01X3906736Y188577D02*
X3906698Y188443D01*
G01X3906057Y189548D02*
X3906019Y189415D01*
G01X3906642Y188744D02*
X3906623Y188610D01*
G01X3906132Y189381D02*
X3906113Y189247D01*
G01X3906755Y188744D02*
X3906736Y188577D01*
G01X3906019Y189415D02*
X3906000Y189247D01*
G01X3906736Y189415D02*
X3906755Y189247D01*
G01X3906000Y188744D02*
X3906019Y188577D01*
G01X3906623Y189381D02*
X3906642Y189247D01*
G01X3906132Y188610D02*
X3906113Y188744D01*
G01X3906755Y189247D02*
Y188744D01*
G01X3906642Y189247D02*
Y188744D01*
G01X3906113D02*
Y189247D01*
G01X3906000Y188744D02*
Y189247D01*
G01X3905849Y189783D02*
Y188208D01*
G01X3905736D02*
Y189548D01*
G01X3906980Y191122D02*
X3906983Y190925D01*
G01X3906736Y189415D02*
X3906698Y189548D01*
G01X3906019Y188577D02*
X3906057Y188443D01*
G01X3906529D02*
X3906453Y188409D01*
G01X3906302Y189582D02*
X3906227Y189548D01*
G01X3906585Y189481D02*
X3906623Y189381D01*
G01X3906132Y188610D02*
X3906170Y188510D01*
G01X3906548Y188242D02*
X3906453Y188208D01*
G01X3906302Y189783D02*
X3906208Y189750D01*
G01X3906623Y189683D02*
X3906698Y189548D01*
G01X3906057Y188443D02*
X3906132Y188309D01*
G01X3906529Y189548D02*
X3906585Y189481D01*
G01X3906170Y188510D02*
X3906227Y188443D01*
G01X3906623Y189683D02*
X3906548Y189750D01*
G01X3906208Y188242D02*
X3906132Y188309D01*
G01X3906453Y189582D02*
X3906529Y189548D01*
G01X3906302Y188409D02*
X3906227Y188443D01*
G01X3906453Y189783D02*
X3906548Y189750D01*
G01X3906208Y188242D02*
X3906302Y188208D01*
G01X3910109Y190925D02*
X3906983D01*
G01X3906302Y189783D02*
X3906453D01*
G01X3905679D02*
X3905849D01*
G01X3906302Y189582D02*
X3906453D01*
G01Y188409D02*
X3906302D01*
G01X3905849Y188208D02*
X3905736D01*
G01X3906453D02*
X3906302D01*
G01X3907969Y199586D02*
X3912236Y203853D01*
G01X3911567Y204862D02*
X3906882Y200177D01*
G01X3907969Y199586D02*
X3913220D01*
G01X3905149Y211594D02*
G03I-787J0D01*
G01X3905543D02*
G03I-1181J0D01*
G01X3905149Y206279D02*
G03I-787J0D01*
G01X3905211D02*
G03I-849J0D01*
G01X3905278D02*
G03I-916J0D01*
G01X3905657D02*
G03I-1295J0D01*
G01X3905346Y205050D02*
G03X3905822Y205689I-984J1230D01*
G01X3902902D02*
G03X3903378Y205050I1460J591D01*
G01X3905822Y206870D02*
G03X3902902I-1460J-591D01*
G01X3906035Y206279D02*
G03I-1673J0D01*
G01X3899421Y212500D02*
G03X3899433Y212381I591J-1D01*
G01X3896769D02*
G03X3897531Y212972I-1J788D01*
G01X3895897Y212381D02*
G03X3895110Y211594I0J-787D01*
G01X3902590Y209626D02*
X3900425Y207460D01*
G01X3900622Y209626D02*
X3898456Y207460D01*
G01X3901842Y212381D02*
X3897157Y207696D01*
G01X3900754Y212972D02*
X3896488Y208706D01*
G01X3897689Y212381D02*
X3897885Y212578D01*
G01X3898653Y209626D02*
X3897472Y208641D01*
G01Y210610D02*
X3898653Y211594D01*
G01X3905070Y207795D02*
Y209146D01*
G01X3903653Y207795D02*
Y209146D01*
G01X3902787Y207854D02*
Y204704D01*
G01X3902196Y206870D02*
Y205689D01*
G01X3902000Y210807D02*
Y211397D01*
G01Y205098D02*
Y207460D01*
G01X3900425D02*
Y205295D01*
G01X3900011Y212972D02*
Y212381D01*
G01X3899913Y207460D02*
Y205098D01*
G01X3899834Y212263D02*
Y213169D01*
G01X3899637Y206870D02*
Y205885D01*
G01X3899421Y212972D02*
Y212381D01*
G01X3899249Y208253D02*
Y207460D01*
G01Y211594D02*
Y209626D01*
G01X3898653Y212539D02*
Y211594D01*
G01X3898594Y211545D02*
Y209576D01*
G01X3898437Y212381D02*
Y212972D01*
G01X3898417Y205098D02*
Y207460D01*
G01X3898206Y211222D02*
Y209253D01*
G01X3898157Y211181D02*
Y209212D01*
G01X3897826Y205885D02*
Y206870D01*
G01X3897770Y210858D02*
Y208889D01*
G01X3897531Y212381D02*
Y212972D01*
G01X3897472Y213169D02*
Y212539D01*
G01X3897354Y212972D02*
Y212381D01*
G01X3897236Y207460D02*
Y205098D01*
G01X3897157Y207696D02*
Y204862D01*
G01X3897115Y210610D02*
Y208641D01*
G01X3896763Y212381D02*
Y215137D01*
G01X3896448Y207460D02*
Y205295D01*
G01X3896094Y212381D02*
Y212972D01*
G01Y208248D02*
Y204311D01*
G01X3895504Y215137D02*
Y212381D01*
G01X3892748Y208641D02*
Y210610D01*
G01X3897472Y212460D02*
X3895543Y211752D01*
G01X3898299Y212263D02*
X3896921Y211752D01*
G01X3897964Y212578D02*
X3898161Y212381D01*
G01X3896763Y213563D02*
X3895504D01*
G01X3897472Y213169D02*
X3895110D01*
G01X3908889D02*
X3899834D01*
G01X3900754Y212972D02*
X3895504D01*
G01X3907969D02*
X3900754D01*
G01X3897531Y212578D02*
X3899421D01*
G01X3895110Y212539D02*
X3898653D01*
G01X3899834Y212460D02*
X3897472D01*
G01X3896769Y212381D02*
X3895504D01*
G01X3913220D02*
X3896776D01*
G01D02*
X3896769D01*
G01X3898299Y212263D02*
X3899834D01*
G01X3895110Y211752D02*
X3896921D01*
G01X3896291Y211594D02*
X3912433D01*
G01X3902000Y211397D02*
X3896488D01*
G01X3906724Y210807D02*
X3902000D01*
G01X3897472Y210610D02*
X3892748D01*
G01X3902590Y209626D02*
X3906133D01*
G01X3898653D02*
X3899249D01*
G01D02*
X3902590D01*
G01X3897472Y208641D02*
X3892748D01*
G01X3912630Y208248D02*
X3896094D01*
G01X3905937Y207854D02*
X3902787D01*
G01X3902000Y207460D02*
X3896448D01*
G01X3905937D02*
X3902787D01*
G01X3902846Y206988D02*
X3901496D01*
G01X3899637Y206870D02*
X3897826D01*
G01X3902902D02*
X3902196D01*
G01X3899637Y205885D02*
X3897826D01*
G01X3902902Y205689D02*
X3902196D01*
G01X3902846Y205570D02*
X3901496D01*
G01X3900425Y205295D02*
X3896448D01*
G01X3902787Y205098D02*
X3905937D01*
G01X3897236D02*
X3898417D01*
G01X3899913D02*
X3902000D01*
G01X3902787Y204704D02*
X3905937D01*
G01X3905346Y204445D02*
X3903378D01*
G01X3905346Y204415D02*
X3903378D01*
G01X3896094Y204311D02*
X3912630D01*
G01X3892703Y218484D02*
X3924500Y250281D01*
G01X3896763Y215137D02*
X3895504D01*
G01X3908299Y207460D02*
Y205295D01*
G01X3906724Y207460D02*
Y205098D01*
G01Y211397D02*
Y210807D01*
G01X3906527Y206870D02*
Y205689D01*
G01X3905937Y204704D02*
Y207854D01*
G01X3912236Y208706D02*
X3907969Y212972D01*
G01X3911567Y207696D02*
X3906882Y212381D01*
G01X3910267Y207460D02*
X3908102Y209626D01*
G01X3908299Y207460D02*
X3906133Y209626D01*
G01X3913220Y212972D02*
X3907969D01*
G01X3912236Y211397D02*
X3906724D01*
G01X3906133Y209626D02*
X3909474D01*
G01X3906724Y207460D02*
X3910267D01*
G01X3905878Y206988D02*
X3907228D01*
G01X3906527Y206870D02*
X3905822D01*
G01X3906527Y205689D02*
X3905822D01*
G01X3905878Y205570D02*
X3907228D01*
G01X3912275Y205295D02*
X3908299D01*
G01X3906724Y205098D02*
X3908811D01*
G01X3907767Y239744D02*
G03I-6299J0D01*
G01X3895523Y248385D02*
Y246909D01*
G01X3905405Y239744D02*
X3948905D01*
G01X3895523Y256752D02*
Y255275D01*
G01X3893513Y267086D02*
X3894015Y267824D01*
G01X3894518Y266348D02*
X3895272Y267578D01*
G01X3894015Y267824D02*
X3894267Y269055D01*
G01X3895272Y267578D02*
X3895523Y269055D01*
G01X3893764Y265610D02*
X3894518Y266348D01*
G01X3895523Y269055D02*
X3895272Y270531D01*
G01X3894267Y269055D02*
X3894015Y270285D01*
G01X3892005Y266102D02*
X3893513Y267086D01*
G01X3892759Y265118D02*
X3893764Y265610D01*
G01X3892005Y264872D02*
X3892759Y265118D01*
G01X3895523Y276683D02*
Y275452D01*
G01Y280620D02*
Y279389D01*
G01X3895272Y270531D02*
X3894518Y271761D01*
G01X3894015Y270285D02*
X3893513Y271023D01*
G01X3894518Y271761D02*
X3893764Y272500D01*
G01X3893513Y271023D02*
X3892005Y272007D01*
G01X3893764Y272500D02*
X3892759Y272992D01*
G01D02*
X3892005Y273238D01*
G01X3895523Y284557D02*
Y283326D01*
G01Y287756D02*
Y286525D01*
G01Y291693D02*
Y290462D01*
G01Y295630D02*
Y294399D01*
G01X3907767Y309035D02*
G03I-6299J0D01*
G01X3905405D02*
X3959539D01*
G01X3908752Y1080291D02*
G03X3904815Y1080689I-3938J-19287D01*
G01X3924500Y1061004D02*
G03X3904815Y1080689I-19685J0D01*
G01X3893747Y1448225D02*
X3894602Y1449365D01*
X3895600Y1449936D01*
X3896741Y1450126D01*
X3898167Y1449746D01*
X3899165Y1448795D01*
X3899451Y1447655D01*
X3899308Y1446514D01*
X3898738Y1445563D01*
X3895886Y1443662D01*
X3894602Y1442331D01*
X3893747Y1440430D01*
X3893461Y1438719D01*
X3899451D01*
G01X3907864Y1450126D02*
X3906723Y1449746D01*
X3905868Y1448795D01*
X3905297Y1447655D01*
X3904869Y1446133D01*
X3904727Y1444422D01*
X3904869Y1442711D01*
X3905297Y1441190D01*
X3905868Y1440050D01*
X3906723Y1439099D01*
X3907864Y1438719D01*
X3909005Y1439099D01*
X3909860Y1440050D01*
X3910431Y1441190D01*
X3910859Y1442711D01*
X3911001Y1444422D01*
X3910859Y1446133D01*
X3910431Y1447655D01*
X3909860Y1448795D01*
X3909005Y1449746D01*
X3907864Y1450126D01*
G01X3920602Y-24744D02*
X3921612Y-24094D01*
X3922190Y-23228D01*
X3922334Y-22254D01*
X3922190Y-21388D01*
X3921468Y-20521D01*
X3920602Y-19980D01*
X3919736Y-19872D01*
X3918725Y-20088D01*
X3918004Y-20846D01*
X3917715Y-21604D01*
Y-22579D01*
G01Y-21604D02*
X3917282Y-20955D01*
X3916560Y-20413D01*
X3915694Y-20197D01*
X3914828Y-20413D01*
X3914106Y-20955D01*
X3913673Y-21929D01*
X3913817Y-22903D01*
X3914395Y-23878D01*
G01X3921035Y-16083D02*
X3921757Y-15433D01*
X3922190Y-14675D01*
X3922334Y-13701D01*
X3922045Y-12727D01*
X3921468Y-11969D01*
X3920458Y-11427D01*
X3919303Y-11319D01*
X3918148Y-11536D01*
X3917426Y-12077D01*
X3916849Y-12835D01*
X3916704Y-13593D01*
X3916849Y-14351D01*
X3917426Y-15325D01*
X3913673Y-15000D01*
Y-12077D01*
G01X3921035Y-7422D02*
X3921757Y-6772D01*
X3922190Y-6014D01*
X3922334Y-5040D01*
X3922045Y-4066D01*
X3921468Y-3308D01*
X3920458Y-2766D01*
X3919303Y-2658D01*
X3918148Y-2875D01*
X3917426Y-3416D01*
X3916849Y-4174D01*
X3916704Y-4932D01*
X3916849Y-5690D01*
X3917426Y-6664D01*
X3913673Y-6339D01*
Y-3416D01*
G01X3922623Y3621D02*
X3922478Y3404D01*
X3922190D01*
X3922045Y3621D01*
X3922190Y3838D01*
X3922478D01*
X3922623Y3621D01*
G01X3918725Y10225D02*
X3917715Y10983D01*
X3917137Y11632D01*
X3916849Y12499D01*
X3917137Y13256D01*
X3917715Y13798D01*
X3918581Y14231D01*
X3919591Y14339D01*
X3920458Y14231D01*
X3921324Y13798D01*
X3922045Y13148D01*
X3922334Y12390D01*
X3922045Y11524D01*
X3921179Y10766D01*
X3919880Y10333D01*
X3918437Y10225D01*
X3916560Y10441D01*
X3915549Y10766D01*
X3914539Y11308D01*
X3913817Y12065D01*
X3913673Y12823D01*
X3913962Y13581D01*
X3914683Y14123D01*
G01X3913673Y20943D02*
X3913962Y20077D01*
X3914683Y19427D01*
X3915549Y18994D01*
X3916704Y18669D01*
X3918004Y18561D01*
X3919303Y18669D01*
X3920458Y18994D01*
X3921324Y19427D01*
X3922045Y20077D01*
X3922334Y20943D01*
X3922045Y21809D01*
X3921324Y22459D01*
X3920458Y22892D01*
X3919303Y23217D01*
X3918004Y23325D01*
X3916704Y23217D01*
X3915549Y22892D01*
X3914683Y22459D01*
X3913962Y21809D01*
X3913673Y20943D01*
G01X3924500Y92500D02*
Y28521D01*
G01X3919421Y107460D02*
Y88956D01*
G01X3909322D02*
Y104704D01*
G01X3917846Y88956D02*
X3915878Y90925D01*
G01X3920563Y92500D02*
G03X3924500Y96437I0J3937D01*
G01X3910858Y90531D02*
X3911252Y92307D01*
G01X3915878Y104704D02*
Y90925D01*
G01X3914893Y104704D02*
Y89941D01*
G01X3911252Y104704D02*
Y92307D01*
G01X3911212Y104704D02*
Y89941D01*
G01X3909283Y92307D02*
Y104704D01*
G01Y92307D02*
X3909677Y90531D01*
G01X3915878Y97027D02*
X3919421D01*
G01X3911252Y92307D02*
X3909283D01*
G01X3914893Y90925D02*
X3919421D01*
G01X3911212D02*
X3909322D01*
G01X3910858Y90531D02*
X3909677D01*
G01X3924500Y96437D02*
Y1061004D01*
G01X3912000Y113169D02*
G03X3911230Y112545I0J-787D01*
G01X3909305D02*
G03X3908535Y113169I-770J-163D01*
G01X3910858Y114744D02*
X3911252Y115137D01*
G01X3909677Y113563D02*
X3909283Y113169D01*
G01X3916173Y114153D02*
Y107460D01*
G01X3913417Y114153D02*
Y108248D01*
G01X3911252Y123011D02*
Y112628D01*
G01X3910858Y113563D02*
Y114744D01*
G01X3909677D02*
Y113563D01*
G01X3909283Y112628D02*
Y123011D01*
G01X3909677Y114744D02*
X3909283Y115137D01*
G01X3911252Y113169D02*
X3910858Y113563D01*
G01X3911252Y115137D02*
X3909283D01*
G01X3910858Y114744D02*
X3909677D01*
G01X3916173Y114153D02*
X3913417D01*
G01X3909677Y113563D02*
X3910858D01*
G01X3911252Y112628D02*
X3909283D01*
G01X3911230Y112545D02*
X3909305D01*
G01X3909677Y121437D02*
X3909283Y121043D01*
G01X3910858Y121437D02*
Y122618D01*
G01X3909677D02*
Y121437D01*
G01X3911252Y121043D02*
X3910858Y121437D01*
G01X3909677D02*
X3910858D01*
G01X3911252Y121043D02*
X3909283D01*
G01X3911252Y120059D02*
X3909283D01*
G01X3914992Y131476D02*
G03X3916567Y133051I0J1575D01*
G01X3910858Y122618D02*
X3911252Y123011D01*
G01X3910391Y128354D02*
X3909796Y127645D01*
G01Y128456D02*
X3910391Y129165D01*
G01X3915976Y137775D02*
Y132067D01*
G01X3914401Y137775D02*
Y132263D01*
G01X3910987Y129165D02*
Y124401D01*
G01X3910391D02*
Y128354D01*
G01X3910267Y136988D02*
Y132263D01*
G01X3909796Y127645D02*
Y128456D01*
G01X3910267Y132067D02*
X3910109Y132657D01*
G01X3909677Y122618D02*
X3909283Y123011D01*
G01X3915976Y132067D02*
X3910267D01*
G01X3910391Y129165D02*
X3910987D01*
G01Y124401D02*
X3910391D01*
G01X3911252Y123011D02*
X3909283D01*
G01X3910858Y122618D02*
X3909677D01*
G01X3913319Y135216D02*
G03I-492J0D01*
G01X3914500D02*
G03I-1673J0D01*
G01X3914598D02*
G03I-1771J0D01*
G01X3919296Y136200D02*
Y133444D01*
G01X3919290D02*
Y136200D01*
G01X3919193D02*
Y133444D01*
G01X3918458Y136200D02*
Y133444D01*
G01X3918115Y136200D02*
Y133444D01*
G01X3918114D02*
Y136200D01*
G01X3918100D02*
Y133444D01*
G01X3917282Y136200D02*
Y133444D01*
G01X3917087D02*
Y136200D01*
G01X3916567Y154311D02*
Y133051D01*
G01X3915779Y149586D02*
Y137775D01*
G01X3915474Y134111D02*
Y136200D01*
G01X3915433Y135572D02*
Y134929D01*
G01X3915385Y149428D02*
Y137933D01*
G01X3910283Y134929D02*
Y135572D01*
G01X3914666Y136216D02*
X3915433Y135572D01*
G01X3914556D02*
X3913789Y136216D01*
G01X3917591Y133444D02*
X3916567Y134111D01*
G01X3916499Y133444D02*
X3915474Y134111D01*
G01X3915385Y137933D02*
X3915976Y137775D01*
G01X3915779D02*
X3914401D01*
G01X3913789Y136216D02*
X3914666D01*
G01X3915474Y136200D02*
X3919296D01*
G01X3910283Y135572D02*
X3914556D01*
G01X3915433Y134929D02*
X3910283D01*
G01X3916567Y134111D02*
X3915474D01*
G01X3916499Y133444D02*
X3919296D01*
G01X3910444Y140314D02*
X3911055Y140925D01*
G01X3915209Y147048D02*
X3914598Y146437D01*
G01X3915209Y147048D02*
Y140314D01*
G01X3914598Y140925D02*
Y146437D01*
G01X3911055D02*
Y140925D01*
G01X3910444Y140314D02*
Y147048D01*
G01D02*
X3911055Y146437D01*
G01X3914598Y140925D02*
X3915209Y140314D01*
G01X3910444Y147048D02*
X3915209D01*
G01X3914598Y146437D02*
X3911055D01*
G01Y140925D02*
X3914598D01*
G01X3915209Y140314D02*
X3910444D01*
G01X3915976Y149586D02*
X3915385Y149428D01*
G01X3913319Y152145D02*
G03I-492J0D01*
G01X3916567Y154311D02*
G03X3914992Y155885I-1575J-1D01*
G01X3914500Y152145D02*
G03I-1673J0D01*
G01X3914598D02*
G03I-1771J0D01*
G01X3910109Y154704D02*
X3910267Y155295D01*
G01X3919296Y153917D02*
Y151161D01*
G01X3919290D02*
Y153917D01*
G01X3919193D02*
Y151161D01*
G01X3918458Y153917D02*
Y151161D01*
G01X3918115Y153917D02*
Y151161D01*
G01X3918114D02*
Y153917D01*
G01X3918100D02*
Y151161D01*
G01X3917282Y153917D02*
Y151161D01*
G01X3917087D02*
Y153917D01*
G01X3915976Y155295D02*
Y149586D01*
G01X3915474Y151161D02*
Y153250D01*
G01X3914401Y155098D02*
Y149586D01*
G01X3916567Y153250D02*
X3917591Y153917D01*
G01X3915474Y153250D02*
X3916499Y153917D01*
G01X3910267Y155098D02*
Y150374D01*
G01X3919296Y153917D02*
X3916499D01*
G01X3916567Y153250D02*
X3915474D01*
G01Y151161D02*
X3919296D01*
G01X3915779Y149586D02*
X3914401D01*
G01X3915976Y155295D02*
X3910267D01*
G01X3913319Y171437D02*
G03I-492J0D01*
G01X3914992Y167696D02*
G03X3916567Y169271I0J1575D01*
G01X3914500Y171437D02*
G03I-1673J0D01*
G01X3914598D02*
G03I-1771J0D01*
G01X3919296Y172421D02*
Y169665D01*
G01X3919290D02*
Y172421D01*
G01X3919193D02*
Y169665D01*
G01X3918458Y172421D02*
Y169665D01*
G01X3918115Y172421D02*
Y169665D01*
G01X3918114D02*
Y172421D01*
G01X3918100D02*
Y169665D01*
G01X3917282Y172421D02*
Y169665D01*
G01X3917087D02*
Y172421D01*
G01X3916567Y190531D02*
Y169271D01*
G01X3915976Y173996D02*
Y168287D01*
G01X3915474Y170332D02*
Y172421D01*
G01X3915433Y171793D02*
Y171149D01*
G01X3914401Y173996D02*
Y168484D01*
G01X3910283Y171149D02*
Y171793D01*
G01X3910267Y173208D02*
Y168484D01*
G01Y168287D02*
X3910109Y168878D01*
G01X3917591Y169665D02*
X3916567Y170332D01*
G01X3916499Y169665D02*
X3915474Y170332D01*
G01X3915433Y171149D02*
X3910283D01*
G01X3916567Y170332D02*
X3915474D01*
G01X3916499Y169665D02*
X3919296D01*
G01X3915976Y168287D02*
X3910267D01*
G01X3910444Y176534D02*
X3911055Y177145D01*
G01X3915779Y185807D02*
Y173996D01*
G01X3915385Y185648D02*
Y174154D01*
G01X3915209Y183268D02*
Y176534D01*
G01X3914598Y177145D02*
Y182657D01*
G01X3911055D02*
Y177145D01*
G01X3910444Y176534D02*
Y183268D01*
G01X3914598Y177145D02*
X3915209Y176534D01*
G01X3914666Y172437D02*
X3915433Y171793D01*
G01X3914556D02*
X3913789Y172437D01*
G01X3915385Y174154D02*
X3915976Y173996D01*
G01X3911055Y177145D02*
X3914598D01*
G01X3915209Y176534D02*
X3910444D01*
G01X3915779Y173996D02*
X3914401D01*
G01X3913789Y172437D02*
X3914666D01*
G01X3915474Y172421D02*
X3919296D01*
G01X3910283Y171793D02*
X3914556D01*
G01X3914500Y188366D02*
G03I-1673J0D01*
G01X3914598D02*
G03I-1771J0D01*
G01X3915209Y183268D02*
X3914598Y182657D01*
G01X3919296Y190137D02*
Y187381D01*
G01X3919290D02*
Y190137D01*
G01X3919193D02*
Y187381D01*
G01X3918458Y190137D02*
Y187381D01*
G01X3918115Y190137D02*
Y187381D01*
G01X3918114D02*
Y190137D01*
G01X3918100D02*
Y187381D01*
G01X3917282Y190137D02*
Y187381D01*
G01X3917087D02*
Y190137D01*
G01X3915976Y191515D02*
Y185807D01*
G01X3915474Y187381D02*
Y189470D01*
G01X3914401Y191318D02*
Y185807D01*
G01X3910267Y191318D02*
Y186594D01*
G01X3910444Y183268D02*
X3911055Y182657D01*
G01X3915474Y187381D02*
X3919296D01*
G01X3915779Y185807D02*
X3914401D01*
G01X3910444Y183268D02*
X3915209D01*
G01X3914598Y182657D02*
X3911055D01*
G01X3915976Y185807D02*
X3915385Y185648D01*
G01X3913319Y188366D02*
G03I-492J0D01*
G01X3916567Y190531D02*
G03X3914992Y192106I-1575J0D01*
G01X3910109Y190925D02*
X3910267Y191515D01*
G01X3916567Y189470D02*
X3917591Y190137D01*
G01X3915474Y189470D02*
X3916499Y190137D01*
G01X3915976Y191515D02*
X3910267D01*
G01X3919296Y190137D02*
X3916499D01*
G01X3916567Y189470D02*
X3915474D01*
G01X3912826Y200177D02*
G03X3913614Y200964I1J787D01*
G01X3909303Y200059D02*
G03X3909291Y200177I-591J0D01*
G01X3911955D02*
G03X3911193Y199586I0J-787D01*
G01X3911429Y200177D02*
X3911232Y199980D01*
G01X3917630Y201651D02*
X3917152Y201082D01*
G01Y201732D02*
X3917630Y202301D01*
G01D02*
Y201651D01*
G01X3917152Y204901D02*
Y201732D01*
G01X3916675Y201082D02*
Y204901D01*
G01X3915976Y203917D02*
Y201948D01*
G01X3913614Y213169D02*
Y199389D01*
G01X3913220Y200177D02*
Y199586D01*
G01X3912630D02*
Y200177D01*
G01X3912433Y200964D02*
Y211594D01*
G01X3912236Y201161D02*
Y211397D01*
G01X3911252Y201948D02*
X3910070Y200964D01*
G01X3911252Y203917D02*
X3910070Y202933D01*
G01X3911609Y203917D02*
Y201948D01*
G01X3911252Y200019D02*
Y199389D01*
G01X3911193Y200177D02*
Y199586D01*
G01X3910954Y203669D02*
Y201700D01*
G01X3910567Y203346D02*
Y201378D01*
G01X3910517Y203305D02*
Y201337D01*
G01X3910287Y200177D02*
Y199586D01*
G01X3910130Y202982D02*
Y201013D01*
G01X3910070Y200019D02*
Y200964D01*
G01X3909474Y202933D02*
Y200964D01*
G01X3909303Y200177D02*
Y199586D01*
G01X3908889Y200295D02*
Y199389D01*
G01X3908712Y199586D02*
Y200177D01*
G01X3913181Y200807D02*
X3911252Y200098D01*
G01X3911803Y200807D02*
X3910425Y200295D01*
G01X3911114Y199980D02*
X3910917Y200177D01*
G01X3915976Y203917D02*
X3911252D01*
G01X3909474Y202933D02*
X3910070D01*
G01X3915976Y201948D02*
X3911252D01*
G01X3917152Y201082D02*
X3916675D01*
G01X3913614Y200807D02*
X3911803D01*
G01X3910425Y200295D02*
X3908889D01*
G01Y200098D02*
X3911252D01*
G01X3913614Y200019D02*
X3910070D01*
G01X3909303Y199980D02*
X3912842D01*
G01X3913614Y199389D02*
X3911252D01*
G01X3909291Y212381D02*
G03X3909303Y212500I-579J118D01*
G01X3911193Y212972D02*
G03X3911955Y212381I763J196D01*
G01X3913614Y211594D02*
G03X3912826Y212381I-787J0D01*
G01X3910956D02*
X3911153Y212578D01*
G01X3915976Y208641D02*
Y210610D01*
G01X3913220Y212972D02*
Y212381D01*
G01X3912630D02*
Y212972D01*
G01Y204311D02*
Y208248D01*
G01X3912275Y207460D02*
Y205295D01*
G01X3911609Y210610D02*
Y208641D01*
G01X3911567Y204862D02*
Y207696D01*
G01X3911488Y205098D02*
Y207460D01*
G01X3911252Y213169D02*
Y212539D01*
G01X3911193Y212972D02*
Y212381D01*
G01X3910954Y210858D02*
Y208889D01*
G01X3910897Y206870D02*
Y205885D01*
G01X3910567Y211181D02*
Y209212D01*
G01X3910517Y211222D02*
Y209253D01*
G01X3910307Y207460D02*
Y205098D01*
G01X3910287Y212972D02*
Y212381D01*
G01X3910130Y211545D02*
Y209576D01*
G01X3910070Y211594D02*
Y212539D01*
G01X3909474Y207460D02*
Y208253D01*
G01Y211594D02*
Y209626D01*
G01X3909303Y212972D02*
Y212381D01*
G01X3909086Y205885D02*
Y206870D01*
G01X3908889Y213169D02*
Y212263D01*
G01X3908811Y205098D02*
Y207460D01*
G01X3908712Y212381D02*
Y212972D01*
G01X3911429Y212381D02*
X3911232Y212578D01*
G01X3911252Y210610D02*
X3910070Y211594D01*
G01X3911252Y208641D02*
X3910070Y209626D01*
G01X3910425Y212263D02*
X3911803Y211752D01*
G01X3913181D02*
X3911252Y212460D01*
G01X3913614Y213169D02*
X3911252D01*
G01X3912842Y212578D02*
X3909303D01*
G01X3913614Y212539D02*
X3910070D01*
G01X3911252Y212460D02*
X3908889D01*
G01Y212263D02*
X3910425D01*
G01X3911803Y211752D02*
X3913614D01*
G01X3915976Y210610D02*
X3911252D01*
G01X3909474Y209626D02*
X3910070D01*
G01X3915976Y208641D02*
X3911252D01*
G01X3910267Y207460D02*
X3912275D01*
G01X3909086Y206870D02*
X3910897D01*
G01Y205885D02*
X3909086D01*
G01X3910307Y205098D02*
X3911488D01*
G01X3916675Y204901D02*
X3917152D01*
G01X3924500Y218484D02*
Y346830D01*
G01X3910956D02*
Y331082D01*
G01X3924500Y346830D02*
X3910956D01*
G01X3908752Y1080291D02*
Y521633D01*
G01X3914067Y745492D02*
Y746476D01*
G01X3921941Y745492D02*
X3914067D01*
G01X3921941Y746476D02*
Y745492D01*
G01X3919260Y755991D02*
Y753366D01*
G01X3918590D02*
Y755991D01*
G01X3918255Y751069D02*
Y746476D01*
G01X3917250D02*
Y751069D01*
G01Y755991D02*
Y753366D01*
G01X3916580D02*
Y755991D01*
G01X3914067Y751069D02*
Y752054D01*
G01X3918590Y755991D02*
X3919260D01*
G01X3916580D02*
X3917250D01*
G01X3919260Y753366D02*
X3918590D01*
G01X3917250D02*
X3916580D01*
G01X3914067Y752054D02*
X3921941D01*
G01X3917250Y751069D02*
X3914067D01*
G01X3921941D02*
X3918255D01*
G01Y746476D02*
X3921941D01*
G01X3914067D02*
X3917250D01*
G01X3921941Y760256D02*
X3921773Y761240D01*
G01X3914067Y760256D02*
X3914234Y759271D01*
G01X3921103Y760256D02*
X3920935Y761076D01*
G01X3914904Y760256D02*
X3915072Y759435D01*
G01X3921773Y761240D02*
X3921270Y762060D01*
G01X3914234Y759271D02*
X3914737Y758451D01*
G01X3920935Y761076D02*
X3920600Y761568D01*
G01X3915072Y759435D02*
X3915407Y758943D01*
G01X3921270Y762060D02*
X3920768Y762552D01*
G01X3914737Y758451D02*
X3915239Y757959D01*
G01X3920935Y759435D02*
X3921103Y760256D01*
G01X3915072Y761076D02*
X3914904Y760256D01*
G01X3921773Y759271D02*
X3921941Y760256D01*
G01X3914234Y761240D02*
X3914067Y760256D01*
G01X3920600Y761568D02*
X3919595Y762224D01*
G01X3915407Y758943D02*
X3916412Y758287D01*
G01X3915239Y757959D02*
X3915909Y757631D01*
G01D02*
X3916412Y757467D01*
G01X3921270Y758451D02*
X3921773Y759271D01*
G01X3914737Y762060D02*
X3914234Y761240D01*
G01X3920600Y758943D02*
X3920935Y759435D01*
G01X3915407Y761568D02*
X3915072Y761076D01*
G01X3916412Y757467D02*
X3917250Y757303D01*
G01X3919595Y762224D02*
X3918590Y762388D01*
G01X3916412Y758287D02*
X3917417Y758123D01*
G01X3920768Y757959D02*
X3921270Y758451D01*
G01X3915239Y762552D02*
X3914737Y762060D01*
G01X3917417Y758123D02*
X3918590D01*
G01X3917250Y757303D02*
X3918757D01*
G01X3919595Y758287D02*
X3920600Y758943D01*
G01X3916412Y762224D02*
X3915407Y761568D01*
G01X3917417Y762388D02*
X3916412Y762224D01*
G01X3918590Y758123D02*
X3919595Y758287D01*
G01X3918757Y757303D02*
X3919595Y757467D01*
G01X3920098Y757631D02*
X3920768Y757959D01*
G01X3919595Y757467D02*
X3920098Y757631D01*
G01X3921941Y752054D02*
Y751069D01*
G01X3917250Y773543D02*
X3917417Y773051D01*
G01X3916747D02*
X3916580Y773543D01*
G01X3916747Y768294D02*
X3916580Y768786D01*
G01X3917250Y766161D02*
X3917417Y765669D01*
G01X3916747D02*
X3916580Y766161D01*
G01X3917250Y768622D02*
X3917417Y768294D01*
G01X3917250Y766489D02*
Y766161D01*
G01Y769114D02*
Y768622D01*
G01X3916580Y771902D02*
Y772723D01*
G01Y766161D02*
Y766817D01*
G01Y768786D02*
Y769442D01*
G01Y764520D02*
Y765341D01*
G01X3917417Y773051D02*
X3917752Y772723D01*
G01X3917082D02*
X3916747Y773051D01*
G01X3917417Y768294D02*
X3917585Y768130D01*
G01X3917250Y767802D02*
X3916747Y768294D01*
G01X3917417Y765669D02*
X3917752Y765341D01*
G01X3917082D02*
X3916747Y765669D01*
G01X3916580Y766817D02*
X3916747Y767309D01*
G01X3916580Y769442D02*
X3916747Y769934D01*
G01X3917585Y768130D02*
X3917920Y767965D01*
G01X3920768Y762552D02*
X3920098Y762880D01*
G01X3917417Y766817D02*
X3917250Y766489D01*
G01X3917417Y769442D02*
X3917250Y769114D01*
G01X3920098Y762880D02*
X3919595Y763044D01*
G01D02*
X3918757Y763208D01*
G01X3916580Y772723D02*
X3917082D01*
G01X3917752D02*
X3921941D01*
G01X3917585Y766981D02*
X3917417Y766817D01*
G01X3916747Y767309D02*
X3917250Y767802D01*
G01X3917585Y769606D02*
X3917417Y769442D01*
G01X3916747Y769934D02*
X3917082Y770262D01*
G01X3921941Y771902D02*
X3916580D01*
G01X3917920Y770590D02*
X3921941D01*
G01Y769770D02*
X3917920D01*
G01Y767965D02*
X3921941D01*
G01Y767145D02*
X3917920D01*
G01X3916580Y765341D02*
X3917082D01*
G01X3917752D02*
X3921941D01*
G01Y764520D02*
X3916580D01*
G01X3918757Y763208D02*
X3917250D01*
G01X3918590Y762388D02*
X3917417D01*
G01X3917250Y763208D02*
X3916412Y763044D01*
G01X3915909Y762880D02*
X3915239Y762552D01*
G01X3917920Y767145D02*
X3917585Y766981D01*
G01X3917920Y769770D02*
X3917585Y769606D01*
G01X3917082Y770262D02*
X3917920Y770590D01*
G01X3916412Y763044D02*
X3915909Y762880D01*
G01X3916747Y775676D02*
X3916580Y776168D01*
G01X3917250Y776004D02*
X3917417Y775676D01*
G01X3917250Y773871D02*
Y773543D01*
G01Y776496D02*
Y776004D01*
G01X3916580Y776168D02*
Y776824D01*
G01Y773543D02*
Y774199D01*
G01X3917417Y775676D02*
X3917585Y775511D01*
G01X3917250Y775183D02*
X3916747Y775676D01*
G01X3916580Y774199D02*
X3916747Y774691D01*
G01X3916580Y776824D02*
X3916747Y777316D01*
G01X3917585Y775511D02*
X3917920Y775347D01*
G01X3917417Y774199D02*
X3917250Y773871D01*
G01X3917417Y776824D02*
X3917250Y776496D01*
G01X3917920Y777972D02*
X3921941D01*
G01Y777152D02*
X3917920D01*
G01Y775347D02*
X3921941D01*
G01Y774527D02*
X3917920D01*
G01X3917585Y774363D02*
X3917417Y774199D01*
G01X3916747Y774691D02*
X3917250Y775183D01*
G01X3917585Y776988D02*
X3917417Y776824D01*
G01X3916747Y777316D02*
X3917082Y777644D01*
G01X3917920Y774527D02*
X3917585Y774363D01*
G01X3917920Y777152D02*
X3917585Y776988D01*
G01X3917082Y777644D02*
X3917920Y777972D01*
G01X3921941Y765341D02*
Y764520D01*
G01Y770590D02*
Y769770D01*
G01Y767965D02*
Y767145D01*
G01Y772723D02*
Y771902D01*
G01Y775347D02*
Y774527D01*
G01Y777972D02*
Y777152D01*
G01X3934257Y321298D02*
X3985604Y337591D01*
G01X3955149Y219492D02*
X3966960D01*
G01X3954102Y243641D02*
X3954752Y242631D01*
X3955618Y242053D01*
X3956592Y241909D01*
X3957458Y242053D01*
X3958325Y242775D01*
X3958866Y243641D01*
X3958974Y244507D01*
X3958758Y245518D01*
X3958000Y246239D01*
X3957242Y246528D01*
X3956267D01*
G01X3957242D02*
X3957891Y246961D01*
X3958433Y247683D01*
X3958649Y248549D01*
X3958433Y249415D01*
X3957891Y250137D01*
X3956917Y250570D01*
X3955943Y250426D01*
X3954968Y249848D01*
G01X3964928Y241909D02*
X3965145Y243785D01*
X3965470Y245373D01*
X3965903Y246817D01*
X3966444Y248405D01*
X3967310Y250570D01*
X3962980D01*
G01X3973806Y241620D02*
X3973589Y241765D01*
Y242053D01*
X3973806Y242198D01*
X3974023Y242053D01*
Y241765D01*
X3973806Y241620D01*
G01X3983766Y241909D02*
Y250570D01*
X3979760Y244363D01*
X3985174D01*
G01X3991128Y250570D02*
X3990262Y250281D01*
X3989612Y249560D01*
X3989179Y248694D01*
X3988854Y247539D01*
X3988746Y246239D01*
X3988854Y244940D01*
X3989179Y243785D01*
X3989612Y242919D01*
X3990262Y242198D01*
X3991128Y241909D01*
X3991994Y242198D01*
X3992644Y242919D01*
X3993077Y243785D01*
X3993402Y244940D01*
X3993510Y246239D01*
X3993402Y247539D01*
X3993077Y248694D01*
X3992644Y249560D01*
X3991994Y250281D01*
X3991128Y250570D01*
G01X3965061Y189431D02*
X3965711Y190296D01*
X3966468Y190730D01*
X3967335Y190874D01*
X3968417Y190585D01*
X3969175Y189864D01*
X3969392Y188998D01*
X3969283Y188131D01*
X3968850Y187410D01*
X3966685Y185966D01*
X3965711Y184956D01*
X3965061Y183512D01*
X3964844Y182213D01*
X3969392D01*
G01X3973722Y189431D02*
X3974372Y190296D01*
X3975129Y190730D01*
X3975996Y190874D01*
X3977078Y190585D01*
X3977836Y189864D01*
X3978053Y188998D01*
X3977944Y188131D01*
X3977511Y187410D01*
X3975346Y185966D01*
X3974372Y184956D01*
X3973722Y183512D01*
X3973505Y182213D01*
X3978053D01*
G01X3984440Y181924D02*
X3984223Y182069D01*
Y182357D01*
X3984440Y182502D01*
X3984657Y182357D01*
Y182069D01*
X3984440Y181924D01*
G01X3991044Y189431D02*
X3991694Y190296D01*
X3992451Y190730D01*
X3993318Y190874D01*
X3994400Y190585D01*
X3995158Y189864D01*
X3995375Y188998D01*
X3995266Y188131D01*
X3994833Y187410D01*
X3992668Y185966D01*
X3991694Y184956D01*
X3991044Y183512D01*
X3990827Y182213D01*
X3995375D01*
G01X4003061D02*
Y190874D01*
X3999055Y184667D01*
X4004469D01*
G01X3967718Y215161D02*
Y223822D01*
X3972698Y215161D01*
Y223822D01*
G01X3978869Y215161D02*
X3978219Y215305D01*
X3977570Y215883D01*
X3977137Y216893D01*
X3976920Y218048D01*
X3977137Y219203D01*
X3977570Y220213D01*
X3978219Y220791D01*
X3978869Y220935D01*
X3979519Y220791D01*
X3980168Y220213D01*
X3980601Y219203D01*
X3980710Y218048D01*
X3980601Y216893D01*
X3980168Y215883D01*
X3979519Y215305D01*
X3978869Y215161D01*
G01X3996191Y223822D02*
Y215161D01*
G01X3994675Y220935D02*
X3997707D01*
G01X4003336Y215161D02*
Y220935D01*
G01Y219780D02*
X4003878Y220358D01*
X4004419Y220791D01*
X4005177Y220935D01*
X4005718Y220791D01*
X4006368Y220358D01*
G01X4015462Y215161D02*
Y220935D01*
G01Y219925D02*
X4015029Y220502D01*
X4014379Y220791D01*
X4013621Y220935D01*
X4012863Y220646D01*
X4012214Y220069D01*
X4011781Y219203D01*
X4011564Y218048D01*
X4011781Y216893D01*
X4012214Y216027D01*
X4012863Y215450D01*
X4013621Y215161D01*
X4014379Y215305D01*
X4015029Y215738D01*
X4015462Y216316D01*
G01X4023906Y220213D02*
X4023148Y220791D01*
X4022499Y220935D01*
X4021633Y220646D01*
X4020983Y220069D01*
X4020550Y219058D01*
X4020442Y218048D01*
X4020550Y217037D01*
X4020983Y216171D01*
X4021633Y215450D01*
X4022499Y215161D01*
X4023257Y215450D01*
X4023906Y216027D01*
G01X4029211Y219058D02*
X4032676D01*
X4032351Y220069D01*
X4031809Y220646D01*
X4031052Y220935D01*
X4030294Y220791D01*
X4029644Y220358D01*
X4029211Y219347D01*
X4028994Y218481D01*
Y217615D01*
X4029211Y216749D01*
X4029752Y215883D01*
X4030402Y215305D01*
X4031160Y215161D01*
X4031918Y215450D01*
X4032676Y216316D01*
G01X4050106Y215161D02*
Y220935D01*
G01Y219925D02*
X4049673Y220502D01*
X4049023Y220791D01*
X4048265Y220935D01*
X4047507Y220646D01*
X4046858Y220069D01*
X4046425Y219203D01*
X4046208Y218048D01*
X4046425Y216893D01*
X4046858Y216027D01*
X4047507Y215450D01*
X4048265Y215161D01*
X4049023Y215305D01*
X4049673Y215738D01*
X4050106Y216316D01*
G01X4056818Y223822D02*
Y215161D01*
G01X4055302Y220935D02*
X4058334D01*
G01X4072516Y216171D02*
X4073057Y215594D01*
X4073815Y215161D01*
X4074465D01*
X4075114Y215450D01*
X4075547Y215883D01*
X4075764Y216460D01*
X4075656Y217326D01*
X4075223Y217759D01*
X4073274Y218625D01*
X4072841Y219636D01*
X4073057Y220358D01*
X4073490Y220791D01*
X4074140Y220935D01*
X4074790Y220791D01*
X4075439Y220358D01*
G01X4080960Y220935D02*
Y216893D01*
X4081394Y215883D01*
X4082043Y215305D01*
X4082801Y215161D01*
X4083559Y215305D01*
X4084208Y215883D01*
X4084642Y216893D01*
G01Y215161D02*
Y220935D01*
G01X4089946Y215161D02*
Y220935D01*
G01Y219780D02*
X4090488Y220358D01*
X4091029Y220791D01*
X4091787Y220935D01*
X4092328Y220791D01*
X4092978Y220358D01*
G01X4099473Y215161D02*
Y222523D01*
X4099690Y223244D01*
X4100123Y223678D01*
X4100773Y223822D01*
X4101422Y223533D01*
X4101747Y222812D01*
G01X4100448Y220358D02*
X4098282D01*
G01X4110733Y215161D02*
Y220935D01*
G01Y219925D02*
X4110300Y220502D01*
X4109650Y220791D01*
X4108892Y220935D01*
X4108134Y220646D01*
X4107485Y220069D01*
X4107052Y219203D01*
X4106835Y218048D01*
X4107052Y216893D01*
X4107485Y216027D01*
X4108134Y215450D01*
X4108892Y215161D01*
X4109650Y215305D01*
X4110300Y215738D01*
X4110733Y216316D01*
G01X4119177Y220213D02*
X4118419Y220791D01*
X4117770Y220935D01*
X4116904Y220646D01*
X4116254Y220069D01*
X4115821Y219058D01*
X4115713Y218048D01*
X4115821Y217037D01*
X4116254Y216171D01*
X4116904Y215450D01*
X4117770Y215161D01*
X4118528Y215450D01*
X4119177Y216027D01*
G01X4124482Y219058D02*
X4127947D01*
X4127622Y220069D01*
X4127080Y220646D01*
X4126323Y220935D01*
X4125565Y220791D01*
X4124915Y220358D01*
X4124482Y219347D01*
X4124265Y218481D01*
Y217615D01*
X4124482Y216749D01*
X4125023Y215883D01*
X4125673Y215305D01*
X4126431Y215161D01*
X4127189Y215450D01*
X4127947Y216316D01*
G01X3964736Y312499D02*
X3965386Y311777D01*
X3966144Y311344D01*
X3967118Y311200D01*
X3968092Y311489D01*
X3968850Y312066D01*
X3969392Y313076D01*
X3969500Y314231D01*
X3969283Y315386D01*
X3968742Y316108D01*
X3967984Y316685D01*
X3967226Y316830D01*
X3966468Y316685D01*
X3965494Y316108D01*
X3965819Y319861D01*
X3968742D01*
G01X3973397Y312499D02*
X3974047Y311777D01*
X3974805Y311344D01*
X3975779Y311200D01*
X3976753Y311489D01*
X3977511Y312066D01*
X3978053Y313076D01*
X3978161Y314231D01*
X3977944Y315386D01*
X3977403Y316108D01*
X3976645Y316685D01*
X3975887Y316830D01*
X3975129Y316685D01*
X3974155Y316108D01*
X3974480Y319861D01*
X3977403D01*
G01X3984440Y310911D02*
X3984223Y311056D01*
Y311344D01*
X3984440Y311489D01*
X3984657Y311344D01*
Y311056D01*
X3984440Y310911D01*
G01X3993101Y319861D02*
X3992235Y319572D01*
X3991585Y318851D01*
X3991152Y317985D01*
X3990827Y316830D01*
X3990719Y315530D01*
X3990827Y314231D01*
X3991152Y313076D01*
X3991585Y312210D01*
X3992235Y311489D01*
X3993101Y311200D01*
X3993967Y311489D01*
X3994617Y312210D01*
X3995050Y313076D01*
X3995375Y314231D01*
X3995483Y315530D01*
X3995375Y316830D01*
X3995050Y317985D01*
X3994617Y318851D01*
X3993967Y319572D01*
X3993101Y319861D01*
G01X4001762D02*
X4000896Y319572D01*
X4000246Y318851D01*
X3999813Y317985D01*
X3999488Y316830D01*
X3999380Y315530D01*
X3999488Y314231D01*
X3999813Y313076D01*
X4000246Y312210D01*
X4000896Y311489D01*
X4001762Y311200D01*
X4002628Y311489D01*
X4003278Y312210D01*
X4003711Y313076D01*
X4004036Y314231D01*
X4004144Y315530D01*
X4004036Y316830D01*
X4003711Y317985D01*
X4003278Y318851D01*
X4002628Y319572D01*
X4001762Y319861D01*
G01X3965061Y361019D02*
X3965819Y362029D01*
X3966468Y362607D01*
X3967335Y362895D01*
X3968092Y362607D01*
X3968634Y362029D01*
X3969067Y361163D01*
X3969175Y360153D01*
X3969067Y359286D01*
X3968634Y358420D01*
X3967984Y357699D01*
X3967226Y357410D01*
X3966360Y357699D01*
X3965602Y358565D01*
X3965169Y359864D01*
X3965061Y361307D01*
X3965277Y363184D01*
X3965602Y364195D01*
X3966144Y365205D01*
X3966901Y365927D01*
X3967659Y366071D01*
X3968417Y365782D01*
X3968959Y365061D01*
G01X3973722Y361019D02*
X3974480Y362029D01*
X3975129Y362607D01*
X3975996Y362895D01*
X3976753Y362607D01*
X3977295Y362029D01*
X3977728Y361163D01*
X3977836Y360153D01*
X3977728Y359286D01*
X3977295Y358420D01*
X3976645Y357699D01*
X3975887Y357410D01*
X3975021Y357699D01*
X3974263Y358565D01*
X3973830Y359864D01*
X3973722Y361307D01*
X3973938Y363184D01*
X3974263Y364195D01*
X3974805Y365205D01*
X3975562Y365927D01*
X3976320Y366071D01*
X3977078Y365782D01*
X3977620Y365061D01*
G01X3984440Y357121D02*
X3984223Y357266D01*
Y357554D01*
X3984440Y357699D01*
X3984657Y357554D01*
Y357266D01*
X3984440Y357121D01*
G01X3992884Y357410D02*
X3993101Y359286D01*
X3993426Y360874D01*
X3993859Y362318D01*
X3994400Y363906D01*
X3995266Y366071D01*
X3990936D01*
G01X4003061Y357410D02*
Y366071D01*
X3999055Y359864D01*
X4004469D01*
G01X3985604Y337591D02*
X3997415D01*
G01X3979121Y397571D02*
X3990932D01*
G01X4006464Y-1687172D02*
Y-1777302D01*
G01X3998173Y333261D02*
Y341922D01*
X4003153Y333261D01*
Y341922D01*
G01X4009324Y333261D02*
X4008674Y333405D01*
X4008025Y333983D01*
X4007592Y334993D01*
X4007375Y336148D01*
X4007592Y337303D01*
X4008025Y338313D01*
X4008674Y338891D01*
X4009324Y339035D01*
X4009974Y338891D01*
X4010623Y338313D01*
X4011056Y337303D01*
X4011165Y336148D01*
X4011056Y334993D01*
X4010623Y333983D01*
X4009974Y333405D01*
X4009324Y333261D01*
G01X4026646Y341922D02*
Y333261D01*
G01X4025130Y339035D02*
X4028162D01*
G01X4033791Y333261D02*
Y339035D01*
G01Y337880D02*
X4034333Y338458D01*
X4034874Y338891D01*
X4035632Y339035D01*
X4036173Y338891D01*
X4036823Y338458D01*
G01X4045917Y333261D02*
Y339035D01*
G01Y338025D02*
X4045484Y338602D01*
X4044834Y338891D01*
X4044076Y339035D01*
X4043318Y338746D01*
X4042669Y338169D01*
X4042236Y337303D01*
X4042019Y336148D01*
X4042236Y334993D01*
X4042669Y334127D01*
X4043318Y333550D01*
X4044076Y333261D01*
X4044834Y333405D01*
X4045484Y333838D01*
X4045917Y334416D01*
G01X4054361Y338313D02*
X4053603Y338891D01*
X4052954Y339035D01*
X4052088Y338746D01*
X4051438Y338169D01*
X4051005Y337158D01*
X4050897Y336148D01*
X4051005Y335137D01*
X4051438Y334271D01*
X4052088Y333550D01*
X4052954Y333261D01*
X4053712Y333550D01*
X4054361Y334127D01*
G01X4059666Y337158D02*
X4063131D01*
X4062806Y338169D01*
X4062264Y338746D01*
X4061507Y339035D01*
X4060749Y338891D01*
X4060099Y338458D01*
X4059666Y337447D01*
X4059449Y336581D01*
Y335715D01*
X4059666Y334849D01*
X4060207Y333983D01*
X4060857Y333405D01*
X4061615Y333261D01*
X4062373Y333550D01*
X4063131Y334416D01*
G01X4080561Y333261D02*
Y339035D01*
G01Y338025D02*
X4080128Y338602D01*
X4079478Y338891D01*
X4078720Y339035D01*
X4077962Y338746D01*
X4077313Y338169D01*
X4076880Y337303D01*
X4076663Y336148D01*
X4076880Y334993D01*
X4077313Y334127D01*
X4077962Y333550D01*
X4078720Y333261D01*
X4079478Y333405D01*
X4080128Y333838D01*
X4080561Y334416D01*
G01X4087273Y341922D02*
Y333261D01*
G01X4085757Y339035D02*
X4088789D01*
G01X4102971Y334271D02*
X4103512Y333694D01*
X4104270Y333261D01*
X4104920D01*
X4105569Y333550D01*
X4106002Y333983D01*
X4106219Y334560D01*
X4106111Y335426D01*
X4105678Y335859D01*
X4103729Y336725D01*
X4103296Y337736D01*
X4103512Y338458D01*
X4103945Y338891D01*
X4104595Y339035D01*
X4105245Y338891D01*
X4105894Y338458D01*
G01X4111415Y339035D02*
Y334993D01*
X4111849Y333983D01*
X4112498Y333405D01*
X4113256Y333261D01*
X4114014Y333405D01*
X4114663Y333983D01*
X4115097Y334993D01*
G01Y333261D02*
Y339035D01*
G01X4120401Y333261D02*
Y339035D01*
G01Y337880D02*
X4120943Y338458D01*
X4121484Y338891D01*
X4122242Y339035D01*
X4122783Y338891D01*
X4123433Y338458D01*
G01X4129928Y333261D02*
Y340623D01*
X4130145Y341344D01*
X4130578Y341778D01*
X4131228Y341922D01*
X4131877Y341633D01*
X4132202Y340912D01*
G01X4130903Y338458D02*
X4128737D01*
G01X4141188Y333261D02*
Y339035D01*
G01Y338025D02*
X4140755Y338602D01*
X4140105Y338891D01*
X4139347Y339035D01*
X4138589Y338746D01*
X4137940Y338169D01*
X4137507Y337303D01*
X4137290Y336148D01*
X4137507Y334993D01*
X4137940Y334127D01*
X4138589Y333550D01*
X4139347Y333261D01*
X4140105Y333405D01*
X4140755Y333838D01*
X4141188Y334416D01*
G01X4149632Y338313D02*
X4148874Y338891D01*
X4148225Y339035D01*
X4147359Y338746D01*
X4146709Y338169D01*
X4146276Y337158D01*
X4146168Y336148D01*
X4146276Y335137D01*
X4146709Y334271D01*
X4147359Y333550D01*
X4148225Y333261D01*
X4148983Y333550D01*
X4149632Y334127D01*
G01X4154937Y337158D02*
X4158402D01*
X4158077Y338169D01*
X4157535Y338746D01*
X4156778Y339035D01*
X4156020Y338891D01*
X4155370Y338458D01*
X4154937Y337447D01*
X4154720Y336581D01*
Y335715D01*
X4154937Y334849D01*
X4155478Y333983D01*
X4156128Y333405D01*
X4156886Y333261D01*
X4157644Y333550D01*
X4158402Y334416D01*
G01X3991690Y393240D02*
Y401901D01*
X3996670Y393240D01*
Y401901D01*
G01X4002841Y393240D02*
X4002191Y393384D01*
X4001542Y393962D01*
X4001109Y394972D01*
X4000892Y396127D01*
X4001109Y397282D01*
X4001542Y398292D01*
X4002191Y398870D01*
X4002841Y399014D01*
X4003491Y398870D01*
X4004140Y398292D01*
X4004573Y397282D01*
X4004682Y396127D01*
X4004573Y394972D01*
X4004140Y393962D01*
X4003491Y393384D01*
X4002841Y393240D01*
G01X4020163Y401901D02*
Y393240D01*
G01X4018647Y399014D02*
X4021679D01*
G01X4027308Y393240D02*
Y399014D01*
G01Y397859D02*
X4027850Y398437D01*
X4028391Y398870D01*
X4029149Y399014D01*
X4029690Y398870D01*
X4030340Y398437D01*
G01X4039434Y393240D02*
Y399014D01*
G01Y398004D02*
X4039001Y398581D01*
X4038351Y398870D01*
X4037593Y399014D01*
X4036835Y398725D01*
X4036186Y398148D01*
X4035753Y397282D01*
X4035536Y396127D01*
X4035753Y394972D01*
X4036186Y394106D01*
X4036835Y393529D01*
X4037593Y393240D01*
X4038351Y393384D01*
X4039001Y393817D01*
X4039434Y394395D01*
G01X4047878Y398292D02*
X4047120Y398870D01*
X4046471Y399014D01*
X4045605Y398725D01*
X4044955Y398148D01*
X4044522Y397137D01*
X4044414Y396127D01*
X4044522Y395116D01*
X4044955Y394250D01*
X4045605Y393529D01*
X4046471Y393240D01*
X4047229Y393529D01*
X4047878Y394106D01*
G01X4053183Y397137D02*
X4056648D01*
X4056323Y398148D01*
X4055781Y398725D01*
X4055024Y399014D01*
X4054266Y398870D01*
X4053616Y398437D01*
X4053183Y397426D01*
X4052966Y396560D01*
Y395694D01*
X4053183Y394828D01*
X4053724Y393962D01*
X4054374Y393384D01*
X4055132Y393240D01*
X4055890Y393529D01*
X4056648Y394395D01*
G01X4074078Y393240D02*
Y399014D01*
G01Y398004D02*
X4073645Y398581D01*
X4072995Y398870D01*
X4072237Y399014D01*
X4071479Y398725D01*
X4070830Y398148D01*
X4070397Y397282D01*
X4070180Y396127D01*
X4070397Y394972D01*
X4070830Y394106D01*
X4071479Y393529D01*
X4072237Y393240D01*
X4072995Y393384D01*
X4073645Y393817D01*
X4074078Y394395D01*
G01X4080790Y401901D02*
Y393240D01*
G01X4079274Y399014D02*
X4082306D01*
G01X4096488Y394250D02*
X4097029Y393673D01*
X4097787Y393240D01*
X4098437D01*
X4099086Y393529D01*
X4099519Y393962D01*
X4099736Y394539D01*
X4099628Y395405D01*
X4099195Y395838D01*
X4097246Y396704D01*
X4096813Y397715D01*
X4097029Y398437D01*
X4097462Y398870D01*
X4098112Y399014D01*
X4098762Y398870D01*
X4099411Y398437D01*
G01X4104932Y399014D02*
Y394972D01*
X4105366Y393962D01*
X4106015Y393384D01*
X4106773Y393240D01*
X4107531Y393384D01*
X4108180Y393962D01*
X4108614Y394972D01*
G01Y393240D02*
Y399014D01*
G01X4113918Y393240D02*
Y399014D01*
G01Y397859D02*
X4114460Y398437D01*
X4115001Y398870D01*
X4115759Y399014D01*
X4116300Y398870D01*
X4116950Y398437D01*
G01X4123445Y393240D02*
Y400602D01*
X4123662Y401323D01*
X4124095Y401757D01*
X4124745Y401901D01*
X4125394Y401612D01*
X4125719Y400891D01*
G01X4124420Y398437D02*
X4122254D01*
G01X4134705Y393240D02*
Y399014D01*
G01Y398004D02*
X4134272Y398581D01*
X4133622Y398870D01*
X4132864Y399014D01*
X4132106Y398725D01*
X4131457Y398148D01*
X4131024Y397282D01*
X4130807Y396127D01*
X4131024Y394972D01*
X4131457Y394106D01*
X4132106Y393529D01*
X4132864Y393240D01*
X4133622Y393384D01*
X4134272Y393817D01*
X4134705Y394395D01*
G01X4143149Y398292D02*
X4142391Y398870D01*
X4141742Y399014D01*
X4140876Y398725D01*
X4140226Y398148D01*
X4139793Y397137D01*
X4139685Y396127D01*
X4139793Y395116D01*
X4140226Y394250D01*
X4140876Y393529D01*
X4141742Y393240D01*
X4142500Y393529D01*
X4143149Y394106D01*
G01X4148454Y397137D02*
X4151919D01*
X4151594Y398148D01*
X4151052Y398725D01*
X4150295Y399014D01*
X4149537Y398870D01*
X4148887Y398437D01*
X4148454Y397426D01*
X4148237Y396560D01*
Y395694D01*
X4148454Y394828D01*
X4148995Y393962D01*
X4149645Y393384D01*
X4150403Y393240D01*
X4151161Y393529D01*
X4151919Y394395D01*
G01X4010054Y-1837784D02*
Y-1856796D01*
G01Y1453929D02*
Y1434916D01*
G01X4052761Y-1717869D02*
Y-1697869D01*
X4049761Y-1701869D01*
G01Y-1717869D02*
X4055761D01*
G01X4072761Y-1718536D02*
X4072261Y-1718202D01*
Y-1717536D01*
X4072761Y-1717202D01*
X4073261Y-1717536D01*
Y-1718202D01*
X4072761Y-1718536D01*
G01X4088011Y-1709536D02*
X4089761Y-1707202D01*
X4091261Y-1705869D01*
X4093261Y-1705203D01*
X4095011Y-1705869D01*
X4096261Y-1707202D01*
X4097261Y-1709202D01*
X4097511Y-1711536D01*
X4097261Y-1713536D01*
X4096261Y-1715536D01*
X4094761Y-1717202D01*
X4093011Y-1717869D01*
X4091011Y-1717202D01*
X4089261Y-1715203D01*
X4088261Y-1712202D01*
X4088011Y-1708869D01*
X4088511Y-1704536D01*
X4089261Y-1702202D01*
X4090511Y-1699869D01*
X4092261Y-1698202D01*
X4094011Y-1697869D01*
X4095761Y-1698536D01*
X4097011Y-1700202D01*
G01X4105261Y-1717869D02*
Y-1704536D01*
G01Y-1708203D02*
X4106011Y-1706536D01*
X4107261Y-1705203D01*
X4109011Y-1704536D01*
X4110761Y-1705203D01*
X4112011Y-1706536D01*
X4112761Y-1708203D01*
Y-1717869D01*
G01Y-1708203D02*
X4113511Y-1706536D01*
X4114761Y-1705203D01*
X4116511Y-1704536D01*
X4118261Y-1705203D01*
X4119511Y-1706536D01*
X4120261Y-1708536D01*
Y-1717869D01*
G01X4125261D02*
Y-1704536D01*
G01Y-1708203D02*
X4126011Y-1706536D01*
X4127261Y-1705203D01*
X4129011Y-1704536D01*
X4130761Y-1705203D01*
X4132011Y-1706536D01*
X4132761Y-1708203D01*
Y-1717869D01*
G01Y-1708203D02*
X4133511Y-1706536D01*
X4134761Y-1705203D01*
X4136511Y-1704536D01*
X4138261Y-1705203D01*
X4139511Y-1706536D01*
X4140261Y-1708536D01*
Y-1717869D01*
G01X4114289Y-1843488D02*
X4115144Y-1842348D01*
X4116142Y-1841777D01*
X4117283Y-1841587D01*
X4118709Y-1841967D01*
X4119707Y-1842918D01*
X4119993Y-1844058D01*
X4119850Y-1845199D01*
X4119280Y-1846150D01*
X4116428Y-1848051D01*
X4115144Y-1849382D01*
X4114289Y-1851283D01*
X4114003Y-1852994D01*
X4119993D01*
G01X4128406D02*
Y-1841587D01*
X4126695Y-1843868D01*
G01Y-1852994D02*
X4130117D01*
G01X4114289Y1448225D02*
X4115144Y1449365D01*
X4116142Y1449936D01*
X4117283Y1450126D01*
X4118709Y1449746D01*
X4119707Y1448795D01*
X4119993Y1447655D01*
X4119850Y1446514D01*
X4119280Y1445563D01*
X4116428Y1443662D01*
X4115144Y1442331D01*
X4114289Y1440430D01*
X4114003Y1438719D01*
X4119993D01*
G01X4128406D02*
Y1450126D01*
X4126695Y1447845D01*
G01Y1438719D02*
X4130117D01*
G01X4197816Y-1837784D02*
X4235421D01*
G01Y1434916D02*
Y-1837784D01*
G01D02*
Y-1640466D01*
G01Y-1786451D02*
Y-1811058D01*
G01X4235339Y-1682912D02*
Y-1736025D01*
G01X4235421Y-1736640D02*
Y-1722860D01*
G01Y-1640466D02*
Y-1582095D01*
G01Y-1605749D02*
X4254433D01*
G01X4235421Y-1389010D02*
X4254433D01*
G01X4235421Y-1172271D02*
X4254433D01*
G01X4235421Y-955533D02*
X4254433D01*
G01X4235421Y-738794D02*
X4254433D01*
G01X4235421Y-522056D02*
X4254433D01*
G01X4235421Y-305317D02*
X4254433D01*
G01X4235421Y-88578D02*
X4254433D01*
G01X4235421Y128160D02*
X4254433D01*
G01X4235421Y344899D02*
X4254433D01*
G01X4235421Y561638D02*
X4254433D01*
G01X4235421Y778376D02*
X4254433D01*
G01X4235421Y995115D02*
X4254433D01*
G01X4235421Y1211853D02*
X4254433D01*
G01X4245403Y-1719822D02*
X4244262Y-1719632D01*
X4243264Y-1718872D01*
X4242408Y-1717731D01*
X4241838Y-1716400D01*
X4241553Y-1714879D01*
Y-1713358D01*
X4241838Y-1711837D01*
X4242408Y-1710506D01*
X4243264Y-1709366D01*
X4244262Y-1708605D01*
X4245403Y-1708415D01*
X4246544Y-1708605D01*
X4247542Y-1709366D01*
X4248398Y-1710506D01*
X4248968Y-1711837D01*
X4249253Y-1713358D01*
Y-1714879D01*
X4248968Y-1716400D01*
X4248398Y-1717731D01*
X4247542Y-1718872D01*
X4246544Y-1719632D01*
X4245403Y-1719822D01*
G01X4242123Y-1503083D02*
Y-1491676D01*
X4248683Y-1503083D01*
Y-1491676D01*
G01X4241695Y-1286345D02*
Y-1274938D01*
X4245403Y-1284444D01*
X4249111Y-1274938D01*
Y-1286345D01*
G01X4242551Y-1058389D02*
Y-1069796D01*
X4248255D01*
G01X4242266Y-853057D02*
Y-841650D01*
G01X4247685D02*
X4242266Y-848685D01*
G01X4248540Y-853057D02*
X4244690Y-845453D01*
G01X4242551Y-633847D02*
X4243264Y-634988D01*
X4244119Y-635748D01*
X4245118Y-636128D01*
X4246259Y-635748D01*
X4247114Y-634988D01*
X4247970Y-633847D01*
X4248255Y-632326D01*
Y-624721D01*
G01X4243692Y-407983D02*
X4247114D01*
G01X4245403D02*
Y-419390D01*
G01X4243692D02*
X4247114D01*
G01X4242408Y-202841D02*
Y-191434D01*
G01X4248398D02*
Y-202841D01*
G01Y-197138D02*
X4242408D01*
G01X4246259Y19600D02*
X4249111D01*
Y16178D01*
X4248255Y15037D01*
X4247257Y14277D01*
X4245831Y13897D01*
X4244405Y14277D01*
X4243407Y15037D01*
X4242551Y16178D01*
X4241980Y17509D01*
X4241695Y19030D01*
Y20361D01*
X4241980Y21501D01*
X4242551Y22833D01*
X4243407Y23973D01*
X4244262Y24733D01*
X4245403Y25304D01*
X4246401D01*
X4247542Y24924D01*
X4248398Y24163D01*
G01X4242313Y230826D02*
Y242233D01*
X4247731D01*
G01X4245735Y236720D02*
X4242313D01*
G01X4248255Y447755D02*
X4242551D01*
Y459162D01*
X4248255D01*
G01X4245973Y453649D02*
X4242551D01*
G01X4242266Y664303D02*
Y675710D01*
X4245118D01*
X4246259Y675139D01*
X4247114Y674379D01*
X4247827Y673239D01*
X4248398Y671907D01*
X4248540Y670006D01*
X4248398Y668105D01*
X4247827Y666774D01*
X4247114Y665634D01*
X4246259Y664873D01*
X4245118Y664303D01*
X4242266D01*
G01X4248540Y891688D02*
X4247685Y892259D01*
X4246687Y892639D01*
X4245546D01*
X4244262Y892068D01*
X4243264Y891118D01*
X4242551Y889977D01*
X4241980Y888076D01*
X4241838Y886365D01*
X4242123Y884654D01*
X4242551Y883513D01*
X4243407Y882372D01*
X4244405Y881612D01*
X4245403Y881232D01*
X4246401D01*
X4247399Y881612D01*
X4248255Y882182D01*
X4248968Y882943D01*
G01X4246544Y1103865D02*
X4247114Y1104435D01*
X4247542Y1105385D01*
X4247827Y1106717D01*
X4247542Y1107857D01*
X4246972Y1108617D01*
X4245973Y1109188D01*
X4242123D01*
Y1097781D01*
X4246829D01*
X4247827Y1098541D01*
X4248398Y1099682D01*
X4248683Y1101013D01*
X4248398Y1102344D01*
X4247542Y1103484D01*
X4246544Y1103865D01*
X4242123D01*
G01X4241838Y1314519D02*
X4245403Y1325926D01*
X4248968Y1314519D01*
G01X4247685Y1318511D02*
X4243121D01*
G01X4254433Y-1856796D02*
Y1454227D01*
M02*
